G04 ================== begin FILE IDENTIFICATION RECORD ==================*
G04 Layout Name:  15126-1b.brd*
G04 Film Name:    DP_REF_L14*
G04 File Format:  Gerber RS274X*
G04 File Origin:  Cadence Allegro 16.6-2015-S079*
G04 Origin Date:  Fri Feb 10 17:23:37 2017*
G04 *
G04 Layer:  BOARD GEOMETRY/PANEL_OUTLINE*
G04 Layer:  BOARD GEOMETRY/DP_REF_L14_TBL*
G04 Layer:  BOARD GEOMETRY/DP_REF_L14_BOTTOM*
G04 *
G04 Offset:    (0.00 0.00)*
G04 Mirror:    No*
G04 Mode:      Positive*
G04 Rotation:  0*
G04 FullContactRelief:  No*
G04 UndefLineWidth:     6.00*
G04 ================== end FILE IDENTIFICATION RECORD ====================*
%FSLAX35Y35*MOIN*%
%IR0*IPPOS*OFA0.00000B0.00000*MIA0B0*SFA1.00000B1.00000*%
%ADD10C,.02*%
%ADD11C,.006*%
%ADD12C,.0045*%
%ADD13C,.0065*%
%ADD14C,.00395*%
G75*
%LPD*%
G75*
G54D10*
G01X2026678Y631398D02*
Y458148D01*
G01D02*
X2831678D01*
G01X2026678Y492798D02*
X2831678D01*
G01X2026678Y527448D02*
X2831678D01*
G01X2026678Y562098D02*
X2831678D01*
G01X2026678Y596748D02*
X2831678D01*
G01X2026678Y631398D02*
X2831678D01*
G01X2201678D02*
Y458148D01*
G01X2516678Y631398D02*
Y458148D01*
G01X2621678Y631398D02*
Y458148D01*
G01X2831678Y631398D02*
Y458148D01*
G54D11*
G01X-17372Y-95792D02*
Y-113292D01*
G01X-22394Y-95792D02*
X-12350D01*
G01X-3584Y-113292D02*
Y-95792D01*
G01Y-104250D02*
X-2492Y-102792D01*
X-1400Y-101917D01*
X346Y-101626D01*
X1656Y-101917D01*
X3185Y-103084D01*
X3840Y-104834D01*
Y-113292D01*
G01X17628Y-101626D02*
Y-113292D01*
G01Y-96959D02*
X17191Y-96667D01*
Y-96084D01*
X17628Y-95792D01*
X18065Y-96084D01*
Y-96667D01*
X17628Y-96959D01*
G01X31853Y-111251D02*
X32945Y-112417D01*
X34473Y-113292D01*
X35783D01*
X37093Y-112709D01*
X37966Y-111834D01*
X38403Y-110668D01*
X38185Y-108917D01*
X37311Y-108042D01*
X33381Y-106292D01*
X32508Y-104250D01*
X32945Y-102792D01*
X33818Y-101917D01*
X35128Y-101626D01*
X36438Y-101917D01*
X37748Y-102792D01*
G01X67071Y-117667D02*
X68600Y-118834D01*
X70346Y-119125D01*
X71874Y-118834D01*
X73185Y-117376D01*
X74058Y-115334D01*
Y-101626D01*
G01Y-103959D02*
X73185Y-102792D01*
X71874Y-101917D01*
X70346Y-101626D01*
X68600Y-102209D01*
X67508Y-103375D01*
X66634Y-105417D01*
X66198Y-107459D01*
X66416Y-109209D01*
X67290Y-111251D01*
X68600Y-112709D01*
X70346Y-113292D01*
X71656Y-113000D01*
X73185Y-111834D01*
X74058Y-110668D01*
G01X84353Y-105417D02*
X91340D01*
X90685Y-103375D01*
X89593Y-102209D01*
X88065Y-101626D01*
X86536Y-101917D01*
X85226Y-102792D01*
X84353Y-104834D01*
X83916Y-106584D01*
Y-108334D01*
X84353Y-110084D01*
X85445Y-111834D01*
X86755Y-113000D01*
X88283Y-113292D01*
X89811Y-112709D01*
X91340Y-110959D01*
G01X102071Y-113292D02*
Y-101626D01*
G01Y-103959D02*
X103163Y-102792D01*
X104255Y-101917D01*
X105783Y-101626D01*
X106874Y-101917D01*
X108185Y-102792D01*
G01X118698Y-113292D02*
Y-95792D01*
G01Y-104542D02*
X119790Y-102792D01*
X121100Y-101917D01*
X122410Y-101626D01*
X124374Y-102209D01*
X125685Y-103375D01*
X126558Y-105417D01*
Y-107750D01*
X126121Y-110084D01*
X125248Y-111834D01*
X123720Y-113000D01*
X122410Y-113292D01*
X121100Y-113000D01*
X119790Y-112126D01*
X118698Y-110668D01*
G01X136853Y-105417D02*
X143840D01*
X143185Y-103375D01*
X142093Y-102209D01*
X140565Y-101626D01*
X139036Y-101917D01*
X137726Y-102792D01*
X136853Y-104834D01*
X136416Y-106584D01*
Y-108334D01*
X136853Y-110084D01*
X137945Y-111834D01*
X139255Y-113000D01*
X140783Y-113292D01*
X142311Y-112709D01*
X143840Y-110959D01*
G01X154571Y-113292D02*
Y-101626D01*
G01Y-103959D02*
X155663Y-102792D01*
X156755Y-101917D01*
X158283Y-101626D01*
X159374Y-101917D01*
X160685Y-102792D01*
G01X192628Y-101626D02*
Y-113292D01*
G01Y-96959D02*
X192191Y-96667D01*
Y-96084D01*
X192628Y-95792D01*
X193065Y-96084D01*
Y-96667D01*
X192628Y-96959D01*
G01X206853Y-111251D02*
X207945Y-112417D01*
X209473Y-113292D01*
X210783D01*
X212093Y-112709D01*
X212966Y-111834D01*
X213403Y-110668D01*
X213185Y-108917D01*
X212311Y-108042D01*
X208381Y-106292D01*
X207508Y-104250D01*
X207945Y-102792D01*
X208818Y-101917D01*
X210128Y-101626D01*
X211438Y-101917D01*
X212748Y-102792D01*
G01X241634Y-117667D02*
X243163Y-118834D01*
X244473Y-119125D01*
X246220Y-118542D01*
X247530Y-117084D01*
X248185Y-114458D01*
Y-101626D01*
G01Y-96959D02*
X247748Y-96667D01*
Y-96084D01*
X248185Y-95792D01*
X248621Y-96084D01*
Y-96667D01*
X248185Y-96959D01*
G01X258916Y-101626D02*
Y-109792D01*
X259790Y-111834D01*
X261100Y-113000D01*
X262628Y-113292D01*
X264156Y-113000D01*
X265466Y-111834D01*
X266340Y-109792D01*
G01Y-113292D02*
Y-101626D01*
G01X276853Y-111251D02*
X277945Y-112417D01*
X279473Y-113292D01*
X280783D01*
X282093Y-112709D01*
X282966Y-111834D01*
X283403Y-110668D01*
X283185Y-108917D01*
X282311Y-108042D01*
X278381Y-106292D01*
X277508Y-104250D01*
X277945Y-102792D01*
X278818Y-101917D01*
X280128Y-101626D01*
X281438Y-101917D01*
X282748Y-102792D01*
G01X297628Y-95792D02*
Y-113292D01*
G01X294571Y-101626D02*
X300685D01*
G01X331318Y-113292D02*
Y-98417D01*
X331755Y-96959D01*
X332628Y-96084D01*
X333938Y-95792D01*
X335248Y-96375D01*
X335903Y-97834D01*
G01X333283Y-102792D02*
X328916D01*
G01X350128Y-113292D02*
X348818Y-113000D01*
X347508Y-111834D01*
X346634Y-109792D01*
X346198Y-107459D01*
X346634Y-105125D01*
X347508Y-103084D01*
X348818Y-101917D01*
X350128Y-101626D01*
X351438Y-101917D01*
X352748Y-103084D01*
X353621Y-105125D01*
X353840Y-107459D01*
X353621Y-109792D01*
X352748Y-111834D01*
X351438Y-113000D01*
X350128Y-113292D01*
G01X364571D02*
Y-101626D01*
G01Y-103959D02*
X365663Y-102792D01*
X366755Y-101917D01*
X368283Y-101626D01*
X369374Y-101917D01*
X370685Y-102792D01*
G01X398043Y-118542D02*
X399353Y-119125D01*
X401100Y-118542D01*
X402191Y-117376D01*
X403065Y-115917D01*
X404374Y-111251D01*
X407213Y-101626D01*
G01X400226D02*
X404374Y-111251D01*
G01X420128Y-113292D02*
X418818Y-113000D01*
X417508Y-111834D01*
X416634Y-109792D01*
X416198Y-107459D01*
X416634Y-105125D01*
X417508Y-103084D01*
X418818Y-101917D01*
X420128Y-101626D01*
X421438Y-101917D01*
X422748Y-103084D01*
X423621Y-105125D01*
X423840Y-107459D01*
X423621Y-109792D01*
X422748Y-111834D01*
X421438Y-113000D01*
X420128Y-113292D01*
G01X433916Y-101626D02*
Y-109792D01*
X434790Y-111834D01*
X436100Y-113000D01*
X437628Y-113292D01*
X439156Y-113000D01*
X440466Y-111834D01*
X441340Y-109792D01*
G01Y-113292D02*
Y-101626D01*
G01X452071Y-113292D02*
Y-101626D01*
G01Y-103959D02*
X453163Y-102792D01*
X454255Y-101917D01*
X455783Y-101626D01*
X456874Y-101917D01*
X458185Y-102792D01*
G01X487071Y-113292D02*
Y-101626D01*
G01Y-103959D02*
X488163Y-102792D01*
X489255Y-101917D01*
X490783Y-101626D01*
X491874Y-101917D01*
X493185Y-102792D01*
G01X504353Y-105417D02*
X511340D01*
X510685Y-103375D01*
X509593Y-102209D01*
X508065Y-101626D01*
X506536Y-101917D01*
X505226Y-102792D01*
X504353Y-104834D01*
X503916Y-106584D01*
Y-108334D01*
X504353Y-110084D01*
X505445Y-111834D01*
X506755Y-113000D01*
X508283Y-113292D01*
X509811Y-112709D01*
X511340Y-110959D01*
G01X523818Y-113292D02*
Y-98417D01*
X524255Y-96959D01*
X525128Y-96084D01*
X526438Y-95792D01*
X527748Y-96375D01*
X528403Y-97834D01*
G01X525783Y-102792D02*
X521416D01*
G01X539353Y-105417D02*
X546340D01*
X545685Y-103375D01*
X544593Y-102209D01*
X543065Y-101626D01*
X541536Y-101917D01*
X540226Y-102792D01*
X539353Y-104834D01*
X538916Y-106584D01*
Y-108334D01*
X539353Y-110084D01*
X540445Y-111834D01*
X541755Y-113000D01*
X543283Y-113292D01*
X544811Y-112709D01*
X546340Y-110959D01*
G01X557071Y-113292D02*
Y-101626D01*
G01Y-103959D02*
X558163Y-102792D01*
X559255Y-101917D01*
X560783Y-101626D01*
X561874Y-101917D01*
X563185Y-102792D01*
G01X574353Y-105417D02*
X581340D01*
X580685Y-103375D01*
X579593Y-102209D01*
X578065Y-101626D01*
X576536Y-101917D01*
X575226Y-102792D01*
X574353Y-104834D01*
X573916Y-106584D01*
Y-108334D01*
X574353Y-110084D01*
X575445Y-111834D01*
X576755Y-113000D01*
X578283Y-113292D01*
X579811Y-112709D01*
X581340Y-110959D01*
G01X591416Y-113292D02*
Y-101626D01*
G01Y-104542D02*
X592290Y-103084D01*
X593600Y-101917D01*
X595346Y-101626D01*
X596874Y-101917D01*
X598185Y-103084D01*
X598840Y-105125D01*
Y-113292D01*
G01X616121Y-103084D02*
X614593Y-101917D01*
X613283Y-101626D01*
X611536Y-102209D01*
X610226Y-103375D01*
X609353Y-105417D01*
X609134Y-107459D01*
X609353Y-109501D01*
X610226Y-111251D01*
X611536Y-112709D01*
X613283Y-113292D01*
X614811Y-112709D01*
X616121Y-111542D01*
G01X626853Y-105417D02*
X633840D01*
X633185Y-103375D01*
X632093Y-102209D01*
X630565Y-101626D01*
X629036Y-101917D01*
X627726Y-102792D01*
X626853Y-104834D01*
X626416Y-106584D01*
Y-108334D01*
X626853Y-110084D01*
X627945Y-111834D01*
X629255Y-113000D01*
X630783Y-113292D01*
X632311Y-112709D01*
X633840Y-110959D01*
G01X665128Y-95792D02*
Y-113292D01*
G01X662071Y-101626D02*
X668185D01*
G01X682628Y-113292D02*
X681318Y-113000D01*
X680008Y-111834D01*
X679134Y-109792D01*
X678698Y-107459D01*
X679134Y-105125D01*
X680008Y-103084D01*
X681318Y-101917D01*
X682628Y-101626D01*
X683938Y-101917D01*
X685248Y-103084D01*
X686121Y-105125D01*
X686340Y-107459D01*
X686121Y-109792D01*
X685248Y-111834D01*
X683938Y-113000D01*
X682628Y-113292D01*
G01X716318D02*
Y-98417D01*
X716755Y-96959D01*
X717628Y-96084D01*
X718938Y-95792D01*
X720248Y-96375D01*
X720903Y-97834D01*
G01X718283Y-102792D02*
X713916D01*
G01X735128Y-101626D02*
Y-113292D01*
G01Y-96959D02*
X734691Y-96667D01*
Y-96084D01*
X735128Y-95792D01*
X735565Y-96084D01*
Y-96667D01*
X735128Y-96959D01*
G01X748916Y-113292D02*
Y-101626D01*
G01Y-104542D02*
X749790Y-103084D01*
X751100Y-101917D01*
X752846Y-101626D01*
X754374Y-101917D01*
X755685Y-103084D01*
X756340Y-105125D01*
Y-113292D01*
G01X774058Y-95792D02*
Y-113292D01*
G01Y-110668D02*
X773185Y-112126D01*
X771874Y-113000D01*
X770346Y-113292D01*
X768600Y-112709D01*
X767290Y-111251D01*
X766416Y-109501D01*
X766198Y-107459D01*
X766416Y-105417D01*
X767290Y-103667D01*
X768600Y-102209D01*
X770346Y-101626D01*
X771874Y-101917D01*
X772966Y-102501D01*
X774058Y-103667D01*
G01X805128Y-95792D02*
Y-113292D01*
G01X802071Y-101626D02*
X808185D01*
G01X818916Y-113292D02*
Y-95792D01*
G01Y-104250D02*
X820008Y-102792D01*
X821100Y-101917D01*
X822846Y-101626D01*
X824156Y-101917D01*
X825685Y-103084D01*
X826340Y-104834D01*
Y-113292D01*
G01X836853Y-105417D02*
X843840D01*
X843185Y-103375D01*
X842093Y-102209D01*
X840565Y-101626D01*
X839036Y-101917D01*
X837726Y-102792D01*
X836853Y-104834D01*
X836416Y-106584D01*
Y-108334D01*
X836853Y-110084D01*
X837945Y-111834D01*
X839255Y-113000D01*
X840783Y-113292D01*
X842311Y-112709D01*
X843840Y-110959D01*
G01X870325Y-113292D02*
Y-95792D01*
X874691D01*
X876438Y-96667D01*
X877748Y-97834D01*
X878840Y-99583D01*
X879713Y-101626D01*
X879931Y-104542D01*
X879713Y-107459D01*
X878840Y-109501D01*
X877748Y-111251D01*
X876438Y-112417D01*
X874691Y-113292D01*
X870325D01*
G01X888261D02*
Y-95792D01*
X893501D01*
X895248Y-96667D01*
X896558Y-98709D01*
X896995Y-101042D01*
X896558Y-103375D01*
X895466Y-105125D01*
X893501Y-106001D01*
X888261D01*
G01X927628Y-101626D02*
Y-113292D01*
G01Y-96959D02*
X927191Y-96667D01*
Y-96084D01*
X927628Y-95792D01*
X928065Y-96084D01*
Y-96667D01*
X927628Y-96959D01*
G01X938578Y-113292D02*
Y-101626D01*
G01Y-104834D02*
X939233Y-103375D01*
X940325Y-102209D01*
X941853Y-101626D01*
X943381Y-102209D01*
X944473Y-103375D01*
X945128Y-104834D01*
Y-113292D01*
G01Y-104834D02*
X945783Y-103375D01*
X946874Y-102209D01*
X948403Y-101626D01*
X949931Y-102209D01*
X951023Y-103375D01*
X951678Y-105125D01*
Y-113292D01*
G01X958698Y-119125D02*
Y-101626D01*
G01Y-104250D02*
X959790Y-102792D01*
X960881Y-101917D01*
X962628Y-101626D01*
X964156Y-101917D01*
X965685Y-103375D01*
X966340Y-105417D01*
X966558Y-107459D01*
X966340Y-109501D01*
X965685Y-111542D01*
X964374Y-112709D01*
X962628Y-113292D01*
X961100Y-113000D01*
X959571Y-112126D01*
X958698Y-110959D01*
G01X976853Y-105417D02*
X983840D01*
X983185Y-103375D01*
X982093Y-102209D01*
X980565Y-101626D01*
X979036Y-101917D01*
X977726Y-102792D01*
X976853Y-104834D01*
X976416Y-106584D01*
Y-108334D01*
X976853Y-110084D01*
X977945Y-111834D01*
X979255Y-113000D01*
X980783Y-113292D01*
X982311Y-112709D01*
X983840Y-110959D01*
G01X1001558Y-95792D02*
Y-113292D01*
G01Y-110668D02*
X1000685Y-112126D01*
X999374Y-113000D01*
X997846Y-113292D01*
X996100Y-112709D01*
X994790Y-111251D01*
X993916Y-109501D01*
X993698Y-107459D01*
X993916Y-105417D01*
X994790Y-103667D01*
X996100Y-102209D01*
X997846Y-101626D01*
X999374Y-101917D01*
X1000466Y-102501D01*
X1001558Y-103667D01*
G01X1019058Y-113292D02*
Y-101626D01*
G01Y-103667D02*
X1018185Y-102501D01*
X1016874Y-101917D01*
X1015346Y-101626D01*
X1013818Y-102209D01*
X1012508Y-103375D01*
X1011634Y-105125D01*
X1011198Y-107459D01*
X1011634Y-109792D01*
X1012508Y-111542D01*
X1013818Y-112709D01*
X1015346Y-113292D01*
X1016874Y-113000D01*
X1018185Y-112126D01*
X1019058Y-110959D01*
G01X1028916Y-113292D02*
Y-101626D01*
G01Y-104542D02*
X1029790Y-103084D01*
X1031100Y-101917D01*
X1032846Y-101626D01*
X1034374Y-101917D01*
X1035685Y-103084D01*
X1036340Y-105125D01*
Y-113292D01*
G01X1053621Y-103084D02*
X1052093Y-101917D01*
X1050783Y-101626D01*
X1049036Y-102209D01*
X1047726Y-103375D01*
X1046853Y-105417D01*
X1046634Y-107459D01*
X1046853Y-109501D01*
X1047726Y-111251D01*
X1049036Y-112709D01*
X1050783Y-113292D01*
X1052311Y-112709D01*
X1053621Y-111542D01*
G01X1064353Y-105417D02*
X1071340D01*
X1070685Y-103375D01*
X1069593Y-102209D01*
X1068065Y-101626D01*
X1066536Y-101917D01*
X1065226Y-102792D01*
X1064353Y-104834D01*
X1063916Y-106584D01*
Y-108334D01*
X1064353Y-110084D01*
X1065445Y-111834D01*
X1066755Y-113000D01*
X1068283Y-113292D01*
X1069811Y-112709D01*
X1071340Y-110959D01*
G01X1102628Y-95792D02*
Y-113292D01*
G01X1099571Y-101626D02*
X1105685D01*
G01X1117071Y-113292D02*
Y-101626D01*
G01Y-103959D02*
X1118163Y-102792D01*
X1119255Y-101917D01*
X1120783Y-101626D01*
X1121874Y-101917D01*
X1123185Y-102792D01*
G01X1141558Y-113292D02*
Y-101626D01*
G01Y-103667D02*
X1140685Y-102501D01*
X1139374Y-101917D01*
X1137846Y-101626D01*
X1136318Y-102209D01*
X1135008Y-103375D01*
X1134134Y-105125D01*
X1133698Y-107459D01*
X1134134Y-109792D01*
X1135008Y-111542D01*
X1136318Y-112709D01*
X1137846Y-113292D01*
X1139374Y-113000D01*
X1140685Y-112126D01*
X1141558Y-110959D01*
G01X1158621Y-103084D02*
X1157093Y-101917D01*
X1155783Y-101626D01*
X1154036Y-102209D01*
X1152726Y-103375D01*
X1151853Y-105417D01*
X1151634Y-107459D01*
X1151853Y-109501D01*
X1152726Y-111251D01*
X1154036Y-112709D01*
X1155783Y-113292D01*
X1157311Y-112709D01*
X1158621Y-111542D01*
G01X1169353Y-105417D02*
X1176340D01*
X1175685Y-103375D01*
X1174593Y-102209D01*
X1173065Y-101626D01*
X1171536Y-101917D01*
X1170226Y-102792D01*
X1169353Y-104834D01*
X1168916Y-106584D01*
Y-108334D01*
X1169353Y-110084D01*
X1170445Y-111834D01*
X1171755Y-113000D01*
X1173283Y-113292D01*
X1174811Y-112709D01*
X1176340Y-110959D01*
G01X1186853Y-111251D02*
X1187945Y-112417D01*
X1189473Y-113292D01*
X1190783D01*
X1192093Y-112709D01*
X1192966Y-111834D01*
X1193403Y-110668D01*
X1193185Y-108917D01*
X1192311Y-108042D01*
X1188381Y-106292D01*
X1187508Y-104250D01*
X1187945Y-102792D01*
X1188818Y-101917D01*
X1190128Y-101626D01*
X1191438Y-101917D01*
X1192748Y-102792D01*
G01X1225128Y-101626D02*
Y-113292D01*
G01Y-96959D02*
X1224691Y-96667D01*
Y-96084D01*
X1225128Y-95792D01*
X1225565Y-96084D01*
Y-96667D01*
X1225128Y-96959D01*
G01X1238916Y-113292D02*
Y-101626D01*
G01Y-104542D02*
X1239790Y-103084D01*
X1241100Y-101917D01*
X1242846Y-101626D01*
X1244374Y-101917D01*
X1245685Y-103084D01*
X1246340Y-105125D01*
Y-113292D01*
G01X1277628D02*
Y-95792D01*
G01X1299058Y-113292D02*
Y-101626D01*
G01Y-103667D02*
X1298185Y-102501D01*
X1296874Y-101917D01*
X1295346Y-101626D01*
X1293818Y-102209D01*
X1292508Y-103375D01*
X1291634Y-105125D01*
X1291198Y-107459D01*
X1291634Y-109792D01*
X1292508Y-111542D01*
X1293818Y-112709D01*
X1295346Y-113292D01*
X1296874Y-113000D01*
X1298185Y-112126D01*
X1299058Y-110959D01*
G01X1308043Y-118542D02*
X1309353Y-119125D01*
X1311100Y-118542D01*
X1312191Y-117376D01*
X1313065Y-115917D01*
X1314374Y-111251D01*
X1317213Y-101626D01*
G01X1310226D02*
X1314374Y-111251D01*
G01X1326853Y-105417D02*
X1333840D01*
X1333185Y-103375D01*
X1332093Y-102209D01*
X1330565Y-101626D01*
X1329036Y-101917D01*
X1327726Y-102792D01*
X1326853Y-104834D01*
X1326416Y-106584D01*
Y-108334D01*
X1326853Y-110084D01*
X1327945Y-111834D01*
X1329255Y-113000D01*
X1330783Y-113292D01*
X1332311Y-112709D01*
X1333840Y-110959D01*
G01X1344571Y-113292D02*
Y-101626D01*
G01Y-103959D02*
X1345663Y-102792D01*
X1346755Y-101917D01*
X1348283Y-101626D01*
X1349374Y-101917D01*
X1350685Y-102792D01*
G01X1378261Y-95792D02*
Y-113292D01*
X1386995D01*
G01X1400128D02*
Y-95792D01*
X1397508Y-99292D01*
G01Y-113292D02*
X1402748D01*
G01X1420248D02*
Y-95792D01*
X1412169Y-108334D01*
X1423087D01*
G01X1435128Y-113875D02*
X1434691Y-113584D01*
Y-113000D01*
X1435128Y-112709D01*
X1435565Y-113000D01*
Y-113584D01*
X1435128Y-113875D01*
G01X2079178Y467898D02*
Y485398D01*
X2076558Y481898D01*
G01Y467898D02*
X2081798D01*
G01X2096678Y485398D02*
X2094931Y484815D01*
X2093621Y483356D01*
X2092748Y481607D01*
X2092093Y479273D01*
X2091875Y476648D01*
X2092093Y474023D01*
X2092748Y471689D01*
X2093621Y469939D01*
X2094931Y468481D01*
X2096678Y467898D01*
X2098424Y468481D01*
X2099735Y469939D01*
X2100608Y471689D01*
X2101263Y474023D01*
X2101481Y476648D01*
X2101263Y479273D01*
X2100608Y481607D01*
X2099735Y483356D01*
X2098424Y484815D01*
X2096678Y485398D01*
G01X2114178D02*
X2112431Y484815D01*
X2111121Y483356D01*
X2110248Y481607D01*
X2109593Y479273D01*
X2109375Y476648D01*
X2109593Y474023D01*
X2110248Y471689D01*
X2111121Y469939D01*
X2112431Y468481D01*
X2114178Y467898D01*
X2115924Y468481D01*
X2117235Y469939D01*
X2118108Y471689D01*
X2118763Y474023D01*
X2118981Y476648D01*
X2118763Y479273D01*
X2118108Y481607D01*
X2117235Y483356D01*
X2115924Y484815D01*
X2114178Y485398D01*
G01X2131678Y467315D02*
X2131241Y467606D01*
Y468190D01*
X2131678Y468481D01*
X2132115Y468190D01*
Y467606D01*
X2131678Y467315D01*
G01X2149178Y485398D02*
X2147431Y484815D01*
X2146121Y483356D01*
X2145248Y481607D01*
X2144593Y479273D01*
X2144375Y476648D01*
X2144593Y474023D01*
X2145248Y471689D01*
X2146121Y469939D01*
X2147431Y468481D01*
X2149178Y467898D01*
X2150924Y468481D01*
X2152235Y469939D01*
X2153108Y471689D01*
X2153763Y474023D01*
X2153981Y476648D01*
X2153763Y479273D01*
X2153108Y481607D01*
X2152235Y483356D01*
X2150924Y484815D01*
X2149178Y485398D01*
G01X2084216Y504589D02*
X2085745Y503131D01*
X2087491Y502548D01*
X2089238Y503131D01*
X2090766Y504881D01*
X2091858Y507506D01*
X2092295Y510131D01*
Y513339D01*
X2091858Y515964D01*
X2090766Y518298D01*
X2089456Y519465D01*
X2087928Y520048D01*
X2086181Y519465D01*
X2084871Y518298D01*
X2083998Y516548D01*
X2083561Y514214D01*
X2083998Y512173D01*
X2085090Y510131D01*
X2086400Y508964D01*
X2087928Y508673D01*
X2089674Y509256D01*
X2090985Y510715D01*
X2092295Y513339D01*
G01X2100625Y505172D02*
X2101934Y503714D01*
X2103463Y502840D01*
X2105428Y502548D01*
X2107393Y503131D01*
X2108921Y504298D01*
X2110013Y506339D01*
X2110231Y508673D01*
X2109795Y511006D01*
X2108703Y512465D01*
X2107174Y513631D01*
X2105646Y513923D01*
X2104118Y513631D01*
X2102153Y512465D01*
X2102808Y520048D01*
X2108703D01*
G01X2122928Y501965D02*
X2122491Y502256D01*
Y502840D01*
X2122928Y503131D01*
X2123365Y502840D01*
Y502256D01*
X2122928Y501965D01*
G01X2140428Y520048D02*
X2138681Y519465D01*
X2137371Y518006D01*
X2136498Y516257D01*
X2135843Y513923D01*
X2135625Y511298D01*
X2135843Y508673D01*
X2136498Y506339D01*
X2137371Y504589D01*
X2138681Y503131D01*
X2140428Y502548D01*
X2142174Y503131D01*
X2143485Y504589D01*
X2144358Y506339D01*
X2145013Y508673D01*
X2145231Y511298D01*
X2145013Y513923D01*
X2144358Y516257D01*
X2143485Y518006D01*
X2142174Y519465D01*
X2140428Y520048D01*
G01X2087928Y537198D02*
X2089456Y537490D01*
X2091203Y538364D01*
X2092295Y539822D01*
X2092731Y541865D01*
X2092295Y543906D01*
X2090985Y545656D01*
X2089020Y546531D01*
X2086836D01*
X2085526Y547115D01*
X2084434Y548573D01*
X2083998Y550614D01*
X2084653Y552656D01*
X2086181Y554115D01*
X2087928Y554698D01*
X2089674Y554115D01*
X2091203Y552656D01*
X2091858Y550614D01*
X2091421Y548573D01*
X2090330Y547115D01*
X2089020Y546531D01*
X2086836D01*
X2084871Y545656D01*
X2083561Y543906D01*
X2083125Y541865D01*
X2083561Y539822D01*
X2084653Y538364D01*
X2086400Y537490D01*
X2087928Y537198D01*
G01X2100625Y539822D02*
X2101934Y538364D01*
X2103463Y537490D01*
X2105428Y537198D01*
X2107393Y537781D01*
X2108921Y538948D01*
X2110013Y540989D01*
X2110231Y543323D01*
X2109795Y545656D01*
X2108703Y547115D01*
X2107174Y548281D01*
X2105646Y548573D01*
X2104118Y548281D01*
X2102153Y547115D01*
X2102808Y554698D01*
X2108703D01*
G01X2122928Y536615D02*
X2122491Y536906D01*
Y537490D01*
X2122928Y537781D01*
X2123365Y537490D01*
Y536906D01*
X2122928Y536615D01*
G01X2140428Y554698D02*
X2138681Y554115D01*
X2137371Y552656D01*
X2136498Y550907D01*
X2135843Y548573D01*
X2135625Y545948D01*
X2135843Y543323D01*
X2136498Y540989D01*
X2137371Y539239D01*
X2138681Y537781D01*
X2140428Y537198D01*
X2142174Y537781D01*
X2143485Y539239D01*
X2144358Y540989D01*
X2145013Y543323D01*
X2145231Y545948D01*
X2145013Y548573D01*
X2144358Y550907D01*
X2143485Y552656D01*
X2142174Y554115D01*
X2140428Y554698D01*
G01X2087491Y571848D02*
X2087928Y575639D01*
X2088583Y578848D01*
X2089456Y581765D01*
X2090548Y584973D01*
X2092295Y589348D01*
X2083561D01*
G01X2100625Y575348D02*
X2101934Y573306D01*
X2103681Y572140D01*
X2105646Y571848D01*
X2107393Y572140D01*
X2109140Y573598D01*
X2110231Y575348D01*
X2110450Y577098D01*
X2110013Y579139D01*
X2108485Y580598D01*
X2106956Y581181D01*
X2104991D01*
G01X2106956D02*
X2108266Y582056D01*
X2109358Y583514D01*
X2109795Y585264D01*
X2109358Y587015D01*
X2108266Y588473D01*
X2106301Y589348D01*
X2104336Y589056D01*
X2102371Y587889D01*
G01X2122928Y571265D02*
X2122491Y571556D01*
Y572140D01*
X2122928Y572431D01*
X2123365Y572140D01*
Y571556D01*
X2122928Y571265D01*
G01X2140428Y589348D02*
X2138681Y588765D01*
X2137371Y587306D01*
X2136498Y585557D01*
X2135843Y583223D01*
X2135625Y580598D01*
X2135843Y577973D01*
X2136498Y575639D01*
X2137371Y573889D01*
X2138681Y572431D01*
X2140428Y571848D01*
X2142174Y572431D01*
X2143485Y573889D01*
X2144358Y575639D01*
X2145013Y577973D01*
X2145231Y580598D01*
X2145013Y583223D01*
X2144358Y585557D01*
X2143485Y587306D01*
X2142174Y588765D01*
X2140428Y589348D01*
G01X2050308Y623998D02*
X2055548D01*
G01X2052928D02*
Y606498D01*
G01X2050308D02*
X2055548D01*
G01X2064751D02*
Y623998D01*
X2070428Y609415D01*
X2076105Y623998D01*
Y606498D01*
G01X2083561D02*
Y623998D01*
X2088801D01*
X2090548Y623123D01*
X2091858Y621081D01*
X2092295Y618748D01*
X2091858Y616415D01*
X2090766Y614665D01*
X2088801Y613789D01*
X2083561D01*
G01X2104336Y600665D02*
X2102153Y603581D01*
X2101061Y606498D01*
Y618164D01*
X2102153Y621081D01*
X2104336Y623998D01*
G01X2122928Y606498D02*
X2121181Y606790D01*
X2119653Y607956D01*
X2118343Y609706D01*
X2117469Y611748D01*
X2117033Y614081D01*
Y616415D01*
X2117469Y618748D01*
X2118343Y620790D01*
X2119653Y622539D01*
X2121181Y623706D01*
X2122928Y623998D01*
X2124674Y623706D01*
X2126203Y622539D01*
X2127513Y620790D01*
X2128387Y618748D01*
X2128823Y616415D01*
Y614081D01*
X2128387Y611748D01*
X2127513Y609706D01*
X2126203Y607956D01*
X2124674Y606790D01*
X2122928Y606498D01*
G01X2136716D02*
Y623998D01*
G01Y615540D02*
X2137808Y616998D01*
X2138900Y617873D01*
X2140646Y618164D01*
X2141956Y617873D01*
X2143485Y616706D01*
X2144140Y614956D01*
Y606498D01*
G01X2151378D02*
Y618164D01*
G01Y614956D02*
X2152033Y616415D01*
X2153125Y617581D01*
X2154653Y618164D01*
X2156181Y617581D01*
X2157273Y616415D01*
X2157928Y614956D01*
Y606498D01*
G01Y614956D02*
X2158583Y616415D01*
X2159674Y617581D01*
X2161203Y618164D01*
X2162731Y617581D01*
X2163823Y616415D01*
X2164478Y614665D01*
Y606498D01*
G01X2176520Y600665D02*
X2178703Y603581D01*
X2179795Y606498D01*
Y618164D01*
X2178703Y621081D01*
X2176520Y623998D01*
G01X2028425Y641148D02*
Y658648D01*
X2032791D01*
X2034538Y657773D01*
X2035848Y656606D01*
X2036940Y654857D01*
X2037813Y652814D01*
X2038031Y649898D01*
X2037813Y646981D01*
X2036940Y644939D01*
X2035848Y643189D01*
X2034538Y642023D01*
X2032791Y641148D01*
X2028425D01*
G01X2046361D02*
Y658648D01*
X2051601D01*
X2053348Y657773D01*
X2054658Y655731D01*
X2055095Y653398D01*
X2054658Y651065D01*
X2053566Y649315D01*
X2051601Y648439D01*
X2046361D01*
G01X2083108Y658648D02*
X2088348D01*
G01X2085728D02*
Y641148D01*
G01X2083108D02*
X2088348D01*
G01X2097551D02*
Y658648D01*
X2103228Y644065D01*
X2108905Y658648D01*
Y641148D01*
G01X2116361D02*
Y658648D01*
X2121601D01*
X2123348Y657773D01*
X2124658Y655731D01*
X2125095Y653398D01*
X2124658Y651065D01*
X2123566Y649315D01*
X2121601Y648439D01*
X2116361D01*
G01X2142595Y641148D02*
X2133861D01*
Y658648D01*
X2142595D01*
G01X2139101Y650190D02*
X2133861D01*
G01X2150925Y641148D02*
Y658648D01*
X2155291D01*
X2157038Y657773D01*
X2158348Y656606D01*
X2159440Y654857D01*
X2160313Y652814D01*
X2160531Y649898D01*
X2160313Y646981D01*
X2159440Y644939D01*
X2158348Y643189D01*
X2157038Y642023D01*
X2155291Y641148D01*
X2150925D01*
G01X2167769D02*
X2173228Y658648D01*
X2178687Y641148D01*
G01X2176721Y647273D02*
X2169734D01*
G01X2185706Y641148D02*
Y658648D01*
X2195750Y641148D01*
Y658648D01*
G01X2213031Y657189D02*
X2211721Y658065D01*
X2210193Y658648D01*
X2208446D01*
X2206481Y657773D01*
X2204953Y656315D01*
X2203861Y654564D01*
X2202988Y651648D01*
X2202769Y649023D01*
X2203206Y646398D01*
X2203861Y644648D01*
X2205171Y642898D01*
X2206700Y641731D01*
X2208228Y641148D01*
X2209756D01*
X2211285Y641731D01*
X2212595Y642606D01*
X2213687Y643772D01*
G01X2230095Y641148D02*
X2221361D01*
Y658648D01*
X2230095D01*
G01X2226601Y650190D02*
X2221361D01*
G01X2260728Y658648D02*
Y641148D01*
G01X2255706Y658648D02*
X2265750D01*
G01X2272769Y641148D02*
X2278228Y658648D01*
X2283687Y641148D01*
G01X2281721Y647273D02*
X2274734D01*
G01X2297474Y650481D02*
X2298348Y651356D01*
X2299003Y652814D01*
X2299440Y654857D01*
X2299003Y656606D01*
X2298130Y657773D01*
X2296601Y658648D01*
X2290706D01*
Y641148D01*
X2297911D01*
X2299440Y642314D01*
X2300313Y644065D01*
X2300750Y646106D01*
X2300313Y648148D01*
X2299003Y649898D01*
X2297474Y650481D01*
X2290706D01*
G01X2308861Y658648D02*
Y641148D01*
X2317595D01*
G01X2335095D02*
X2326361D01*
Y658648D01*
X2335095D01*
G01X2331601Y650190D02*
X2326361D01*
G01X2348228Y640565D02*
X2347791Y640856D01*
Y641440D01*
X2348228Y641731D01*
X2348665Y641440D01*
Y640856D01*
X2348228Y640565D01*
G01Y648439D02*
X2347791Y648731D01*
Y649315D01*
X2348228Y649606D01*
X2348665Y649315D01*
Y648731D01*
X2348228Y648439D01*
G01X2378861Y658648D02*
Y641148D01*
X2387595D01*
G01X2400728D02*
Y658648D01*
X2398108Y655148D01*
G01Y641148D02*
X2403348D01*
G01X2420848D02*
Y658648D01*
X2412769Y646106D01*
X2423687D01*
G01X2265128Y623998D02*
X2268184Y606498D01*
X2271678Y623998D01*
X2275171Y606498D01*
X2278228Y623998D01*
G01X2286558D02*
X2291798D01*
G01X2289178D02*
Y606498D01*
G01X2286558D02*
X2291798D01*
G01X2301875D02*
Y623998D01*
X2306241D01*
X2307988Y623123D01*
X2309298Y621956D01*
X2310390Y620207D01*
X2311263Y618164D01*
X2311481Y615248D01*
X2311263Y612331D01*
X2310390Y610289D01*
X2309298Y608539D01*
X2307988Y607373D01*
X2306241Y606498D01*
X2301875D01*
G01X2324178Y623998D02*
Y606498D01*
G01X2319156Y623998D02*
X2329200D01*
G01X2337093Y606498D02*
Y623998D01*
G01X2346263D02*
Y606498D01*
G01Y615248D02*
X2337093D01*
G01X2358086Y600665D02*
X2355903Y603581D01*
X2354811Y606498D01*
Y618164D01*
X2355903Y621081D01*
X2358086Y623998D01*
G01X2370128Y606498D02*
Y618164D01*
G01Y614956D02*
X2370783Y616415D01*
X2371875Y617581D01*
X2373403Y618164D01*
X2374931Y617581D01*
X2376023Y616415D01*
X2376678Y614956D01*
Y606498D01*
G01Y614956D02*
X2377333Y616415D01*
X2378424Y617581D01*
X2379953Y618164D01*
X2381481Y617581D01*
X2382573Y616415D01*
X2383228Y614665D01*
Y606498D01*
G01X2394178Y618164D02*
Y606498D01*
G01Y622831D02*
X2393741Y623123D01*
Y623706D01*
X2394178Y623998D01*
X2394615Y623706D01*
Y623123D01*
X2394178Y622831D01*
G01X2411678Y606498D02*
Y623998D01*
G01X2425903Y608539D02*
X2426995Y607373D01*
X2428523Y606498D01*
X2429833D01*
X2431143Y607081D01*
X2432016Y607956D01*
X2432453Y609122D01*
X2432235Y610873D01*
X2431361Y611748D01*
X2427431Y613498D01*
X2426558Y615540D01*
X2426995Y616998D01*
X2427868Y617873D01*
X2429178Y618164D01*
X2430488Y617873D01*
X2431798Y616998D01*
G01X2447770Y600665D02*
X2449953Y603581D01*
X2451045Y606498D01*
Y618164D01*
X2449953Y621081D01*
X2447770Y623998D01*
G01X2275625Y471398D02*
X2276934Y469356D01*
X2278681Y468190D01*
X2280646Y467898D01*
X2282393Y468190D01*
X2284140Y469648D01*
X2285231Y471398D01*
X2285450Y473148D01*
X2285013Y475189D01*
X2283485Y476648D01*
X2281956Y477231D01*
X2279991D01*
G01X2281956D02*
X2283266Y478106D01*
X2284358Y479564D01*
X2284795Y481314D01*
X2284358Y483065D01*
X2283266Y484523D01*
X2281301Y485398D01*
X2279336Y485106D01*
X2277371Y483939D01*
G01X2297928Y467315D02*
X2297491Y467606D01*
Y468190D01*
X2297928Y468481D01*
X2298365Y468190D01*
Y467606D01*
X2297928Y467315D01*
G01X2311716Y469939D02*
X2313245Y468481D01*
X2314991Y467898D01*
X2316738Y468481D01*
X2318266Y470231D01*
X2319358Y472856D01*
X2319795Y475481D01*
Y478689D01*
X2319358Y481314D01*
X2318266Y483648D01*
X2316956Y484815D01*
X2315428Y485398D01*
X2313681Y484815D01*
X2312371Y483648D01*
X2311498Y481898D01*
X2311061Y479564D01*
X2311498Y477523D01*
X2312590Y475481D01*
X2313900Y474314D01*
X2315428Y474023D01*
X2317174Y474606D01*
X2318485Y476065D01*
X2319795Y478689D01*
G01X2328125Y470522D02*
X2329434Y469064D01*
X2330963Y468190D01*
X2332928Y467898D01*
X2334893Y468481D01*
X2336421Y469648D01*
X2337513Y471689D01*
X2337731Y474023D01*
X2337295Y476356D01*
X2336203Y477815D01*
X2334674Y478981D01*
X2333146Y479273D01*
X2331618Y478981D01*
X2329653Y477815D01*
X2330308Y485398D01*
X2336203D01*
G01X2346498Y467315D02*
X2354358Y485398D01*
G01X2367928Y467898D02*
Y485398D01*
X2365308Y481898D01*
G01Y467898D02*
X2370548D01*
G01X2388048D02*
Y485398D01*
X2379969Y472856D01*
X2390887D01*
G01X2402928Y467315D02*
X2402491Y467606D01*
Y468190D01*
X2402928Y468481D01*
X2403365Y468190D01*
Y467606D01*
X2402928Y467315D01*
G01X2420428Y485398D02*
X2418681Y484815D01*
X2417371Y483356D01*
X2416498Y481607D01*
X2415843Y479273D01*
X2415625Y476648D01*
X2415843Y474023D01*
X2416498Y471689D01*
X2417371Y469939D01*
X2418681Y468481D01*
X2420428Y467898D01*
X2422174Y468481D01*
X2423485Y469939D01*
X2424358Y471689D01*
X2425013Y474023D01*
X2425231Y476648D01*
X2425013Y479273D01*
X2424358Y481607D01*
X2423485Y483356D01*
X2422174Y484815D01*
X2420428Y485398D01*
G01X2433125Y470522D02*
X2434434Y469064D01*
X2435963Y468190D01*
X2437928Y467898D01*
X2439893Y468481D01*
X2441421Y469648D01*
X2442513Y471689D01*
X2442731Y474023D01*
X2442295Y476356D01*
X2441203Y477815D01*
X2439674Y478981D01*
X2438146Y479273D01*
X2436618Y478981D01*
X2434653Y477815D01*
X2435308Y485398D01*
X2441203D01*
G01X2284375Y501965D02*
X2293981Y514798D01*
G01X2289178Y517131D02*
Y499631D01*
G01X2293981Y501965D02*
X2284375Y514798D01*
G01X2282628Y508381D02*
X2295728D01*
G01X2309298Y502548D02*
Y520048D01*
X2301219Y507506D01*
X2312137D01*
G01X2324178Y501965D02*
X2323741Y502256D01*
Y502840D01*
X2324178Y503131D01*
X2324615Y502840D01*
Y502256D01*
X2324178Y501965D01*
G01X2337530Y509839D02*
X2339058Y511881D01*
X2340368Y513048D01*
X2342115Y513631D01*
X2343643Y513048D01*
X2344735Y511881D01*
X2345608Y510131D01*
X2345826Y508090D01*
X2345608Y506339D01*
X2344735Y504589D01*
X2343424Y503131D01*
X2341896Y502548D01*
X2340150Y503131D01*
X2338621Y504881D01*
X2337748Y507506D01*
X2337530Y510423D01*
X2337966Y514214D01*
X2338621Y516257D01*
X2339713Y518298D01*
X2341241Y519756D01*
X2342770Y520048D01*
X2344298Y519465D01*
X2345390Y518006D01*
G01X2355248Y501965D02*
X2363108Y520048D01*
G01X2376678Y502548D02*
Y520048D01*
X2374058Y516548D01*
G01Y502548D02*
X2379298D01*
G01X2389375Y506048D02*
X2390684Y504006D01*
X2392431Y502840D01*
X2394396Y502548D01*
X2396143Y502840D01*
X2397890Y504298D01*
X2398981Y506048D01*
X2399200Y507798D01*
X2398763Y509839D01*
X2397235Y511298D01*
X2395706Y511881D01*
X2393741D01*
G01X2395706D02*
X2397016Y512756D01*
X2398108Y514214D01*
X2398545Y515964D01*
X2398108Y517715D01*
X2397016Y519173D01*
X2395051Y520048D01*
X2393086Y519756D01*
X2391121Y518589D01*
G01X2411678Y501965D02*
X2411241Y502256D01*
Y502840D01*
X2411678Y503131D01*
X2412115Y502840D01*
Y502256D01*
X2411678Y501965D01*
G01X2424375Y505172D02*
X2425684Y503714D01*
X2427213Y502840D01*
X2429178Y502548D01*
X2431143Y503131D01*
X2432671Y504298D01*
X2433763Y506339D01*
X2433981Y508673D01*
X2433545Y511006D01*
X2432453Y512465D01*
X2430924Y513631D01*
X2429396Y513923D01*
X2427868Y513631D01*
X2425903Y512465D01*
X2426558Y520048D01*
X2432453D01*
G01X2309298Y537198D02*
Y554698D01*
X2301219Y542156D01*
X2312137D01*
G01X2324178Y536615D02*
X2323741Y536906D01*
Y537490D01*
X2324178Y537781D01*
X2324615Y537490D01*
Y536906D01*
X2324178Y536615D01*
G01X2336875Y539822D02*
X2338184Y538364D01*
X2339713Y537490D01*
X2341678Y537198D01*
X2343643Y537781D01*
X2345171Y538948D01*
X2346263Y540989D01*
X2346481Y543323D01*
X2346045Y545656D01*
X2344953Y547115D01*
X2343424Y548281D01*
X2341896Y548573D01*
X2340368Y548281D01*
X2338403Y547115D01*
X2339058Y554698D01*
X2344953D01*
G01X2355248Y536615D02*
X2363108Y554698D01*
G01X2371875Y539822D02*
X2373184Y538364D01*
X2374713Y537490D01*
X2376678Y537198D01*
X2378643Y537781D01*
X2380171Y538948D01*
X2381263Y540989D01*
X2381481Y543323D01*
X2381045Y545656D01*
X2379953Y547115D01*
X2378424Y548281D01*
X2376896Y548573D01*
X2375368Y548281D01*
X2373403Y547115D01*
X2374058Y554698D01*
X2379953D01*
G01X2394178Y536615D02*
X2393741Y536906D01*
Y537490D01*
X2394178Y537781D01*
X2394615Y537490D01*
Y536906D01*
X2394178Y536615D01*
G01X2411678Y554698D02*
X2409931Y554115D01*
X2408621Y552656D01*
X2407748Y550907D01*
X2407093Y548573D01*
X2406875Y545948D01*
X2407093Y543323D01*
X2407748Y540989D01*
X2408621Y539239D01*
X2409931Y537781D01*
X2411678Y537198D01*
X2413424Y537781D01*
X2414735Y539239D01*
X2415608Y540989D01*
X2416263Y543323D01*
X2416481Y545948D01*
X2416263Y548573D01*
X2415608Y550907D01*
X2414735Y552656D01*
X2413424Y554115D01*
X2411678Y554698D01*
G01X2302530Y579139D02*
X2304058Y581181D01*
X2305368Y582348D01*
X2307115Y582931D01*
X2308643Y582348D01*
X2309735Y581181D01*
X2310608Y579431D01*
X2310826Y577390D01*
X2310608Y575639D01*
X2309735Y573889D01*
X2308424Y572431D01*
X2306896Y571848D01*
X2305150Y572431D01*
X2303621Y574181D01*
X2302748Y576806D01*
X2302530Y579723D01*
X2302966Y583514D01*
X2303621Y585557D01*
X2304713Y587598D01*
X2306241Y589056D01*
X2307770Y589348D01*
X2309298Y588765D01*
X2310390Y587306D01*
G01X2324178Y571265D02*
X2323741Y571556D01*
Y572140D01*
X2324178Y572431D01*
X2324615Y572140D01*
Y571556D01*
X2324178Y571265D01*
G01X2336875Y574472D02*
X2338184Y573014D01*
X2339713Y572140D01*
X2341678Y571848D01*
X2343643Y572431D01*
X2345171Y573598D01*
X2346263Y575639D01*
X2346481Y577973D01*
X2346045Y580306D01*
X2344953Y581765D01*
X2343424Y582931D01*
X2341896Y583223D01*
X2340368Y582931D01*
X2338403Y581765D01*
X2339058Y589348D01*
X2344953D01*
G01X2355248Y571265D02*
X2363108Y589348D01*
G01X2371875Y574472D02*
X2373184Y573014D01*
X2374713Y572140D01*
X2376678Y571848D01*
X2378643Y572431D01*
X2380171Y573598D01*
X2381263Y575639D01*
X2381481Y577973D01*
X2381045Y580306D01*
X2379953Y581765D01*
X2378424Y582931D01*
X2376896Y583223D01*
X2375368Y582931D01*
X2373403Y581765D01*
X2374058Y589348D01*
X2379953D01*
G01X2394178Y571265D02*
X2393741Y571556D01*
Y572140D01*
X2394178Y572431D01*
X2394615Y572140D01*
Y571556D01*
X2394178Y571265D01*
G01X2411678Y589348D02*
X2409931Y588765D01*
X2408621Y587306D01*
X2407748Y585557D01*
X2407093Y583223D01*
X2406875Y580598D01*
X2407093Y577973D01*
X2407748Y575639D01*
X2408621Y573889D01*
X2409931Y572431D01*
X2411678Y571848D01*
X2413424Y572431D01*
X2414735Y573889D01*
X2415608Y575639D01*
X2416263Y577973D01*
X2416481Y580598D01*
X2416263Y583223D01*
X2415608Y585557D01*
X2414735Y587306D01*
X2413424Y588765D01*
X2411678Y589348D01*
G01X2555625Y467898D02*
Y485398D01*
X2559991D01*
X2561738Y484523D01*
X2563048Y483356D01*
X2564140Y481607D01*
X2565013Y479564D01*
X2565231Y476648D01*
X2565013Y473731D01*
X2564140Y471689D01*
X2563048Y469939D01*
X2561738Y468773D01*
X2559991Y467898D01*
X2555625D01*
G01X2573561D02*
Y485398D01*
X2578801D01*
X2580548Y484523D01*
X2581858Y482481D01*
X2582295Y480148D01*
X2581858Y477815D01*
X2580766Y476065D01*
X2578801Y475189D01*
X2573561D01*
G01X2555625Y502548D02*
Y520048D01*
X2559991D01*
X2561738Y519173D01*
X2563048Y518006D01*
X2564140Y516257D01*
X2565013Y514214D01*
X2565231Y511298D01*
X2565013Y508381D01*
X2564140Y506339D01*
X2563048Y504589D01*
X2561738Y503423D01*
X2559991Y502548D01*
X2555625D01*
G01X2573561D02*
Y520048D01*
X2578801D01*
X2580548Y519173D01*
X2581858Y517131D01*
X2582295Y514798D01*
X2581858Y512465D01*
X2580766Y510715D01*
X2578801Y509839D01*
X2573561D01*
G01X2555625Y537198D02*
Y554698D01*
X2559991D01*
X2561738Y553823D01*
X2563048Y552656D01*
X2564140Y550907D01*
X2565013Y548864D01*
X2565231Y545948D01*
X2565013Y543031D01*
X2564140Y540989D01*
X2563048Y539239D01*
X2561738Y538073D01*
X2559991Y537198D01*
X2555625D01*
G01X2573561D02*
Y554698D01*
X2578801D01*
X2580548Y553823D01*
X2581858Y551781D01*
X2582295Y549448D01*
X2581858Y547115D01*
X2580766Y545365D01*
X2578801Y544489D01*
X2573561D01*
G01X2555625Y571848D02*
Y589348D01*
X2559991D01*
X2561738Y588473D01*
X2563048Y587306D01*
X2564140Y585557D01*
X2565013Y583514D01*
X2565231Y580598D01*
X2565013Y577681D01*
X2564140Y575639D01*
X2563048Y573889D01*
X2561738Y572723D01*
X2559991Y571848D01*
X2555625D01*
G01X2573561D02*
Y589348D01*
X2578801D01*
X2580548Y588473D01*
X2581858Y586431D01*
X2582295Y584098D01*
X2581858Y581765D01*
X2580766Y580015D01*
X2578801Y579139D01*
X2573561D01*
G01X2542928Y623998D02*
Y606498D01*
G01X2537906Y623998D02*
X2547950D01*
G01X2560428Y606498D02*
Y614373D01*
X2556061Y623998D01*
G01X2564795D02*
X2560428Y614373D01*
G01X2573561Y606498D02*
Y623998D01*
X2578801D01*
X2580548Y623123D01*
X2581858Y621081D01*
X2582295Y618748D01*
X2581858Y616415D01*
X2580766Y614665D01*
X2578801Y613789D01*
X2573561D01*
G01X2599795Y606498D02*
X2591061D01*
Y623998D01*
X2599795D01*
G01X2596301Y615540D02*
X2591061D01*
G01X2643561Y606498D02*
Y623998D01*
X2649020D01*
X2650766Y623123D01*
X2651858Y621956D01*
X2652295Y619623D01*
X2651858Y617289D01*
X2650548Y615831D01*
X2649020Y614956D01*
X2643561D01*
G01X2649020D02*
X2652295Y606498D01*
G01X2662153Y614373D02*
X2669140D01*
X2668485Y616415D01*
X2667393Y617581D01*
X2665865Y618164D01*
X2664336Y617873D01*
X2663026Y616998D01*
X2662153Y614956D01*
X2661716Y613206D01*
Y611456D01*
X2662153Y609706D01*
X2663245Y607956D01*
X2664555Y606790D01*
X2666083Y606498D01*
X2667611Y607081D01*
X2669140Y608831D01*
G01X2681618Y606498D02*
Y621373D01*
X2682055Y622831D01*
X2682928Y623706D01*
X2684238Y623998D01*
X2685548Y623415D01*
X2686203Y621956D01*
G01X2683583Y616998D02*
X2679216D01*
G01X2700428Y605915D02*
X2699991Y606206D01*
Y606790D01*
X2700428Y607081D01*
X2700865Y606790D01*
Y606206D01*
X2700428Y605915D01*
G01X2731061Y606498D02*
Y623998D01*
X2736301D01*
X2738048Y623123D01*
X2739358Y621081D01*
X2739795Y618748D01*
X2739358Y616415D01*
X2738266Y614665D01*
X2736301Y613789D01*
X2731061D01*
G01X2752928Y606498D02*
Y623998D01*
G01X2774358Y606498D02*
Y618164D01*
G01Y616123D02*
X2773485Y617289D01*
X2772174Y617873D01*
X2770646Y618164D01*
X2769118Y617581D01*
X2767808Y616415D01*
X2766934Y614665D01*
X2766498Y612331D01*
X2766934Y609998D01*
X2767808Y608248D01*
X2769118Y607081D01*
X2770646Y606498D01*
X2772174Y606790D01*
X2773485Y607664D01*
X2774358Y608831D01*
G01X2784216Y606498D02*
Y618164D01*
G01Y615248D02*
X2785090Y616706D01*
X2786400Y617873D01*
X2788146Y618164D01*
X2789674Y617873D01*
X2790985Y616706D01*
X2791640Y614665D01*
Y606498D01*
G01X2802153Y614373D02*
X2809140D01*
X2808485Y616415D01*
X2807393Y617581D01*
X2805865Y618164D01*
X2804336Y617873D01*
X2803026Y616998D01*
X2802153Y614956D01*
X2801716Y613206D01*
Y611456D01*
X2802153Y609706D01*
X2803245Y607956D01*
X2804555Y606790D01*
X2806083Y606498D01*
X2807611Y607081D01*
X2809140Y608831D01*
G01X2704811Y485398D02*
Y467898D01*
X2713545D01*
G01X2726678D02*
Y485398D01*
X2724058Y481898D01*
G01Y467898D02*
X2729298D01*
G01X2739375Y471398D02*
X2740684Y469356D01*
X2742431Y468190D01*
X2744396Y467898D01*
X2746143Y468190D01*
X2747890Y469648D01*
X2748981Y471398D01*
X2749200Y473148D01*
X2748763Y475189D01*
X2747235Y476648D01*
X2745706Y477231D01*
X2743741D01*
G01X2745706D02*
X2747016Y478106D01*
X2748108Y479564D01*
X2748545Y481314D01*
X2748108Y483065D01*
X2747016Y484523D01*
X2745051Y485398D01*
X2743086Y485106D01*
X2741121Y483939D01*
G01X2704811Y520048D02*
Y502548D01*
X2713545D01*
G01X2726678D02*
Y520048D01*
X2724058Y516548D01*
G01Y502548D02*
X2729298D01*
G01X2739375Y506048D02*
X2740684Y504006D01*
X2742431Y502840D01*
X2744396Y502548D01*
X2746143Y502840D01*
X2747890Y504298D01*
X2748981Y506048D01*
X2749200Y507798D01*
X2748763Y509839D01*
X2747235Y511298D01*
X2745706Y511881D01*
X2743741D01*
G01X2745706D02*
X2747016Y512756D01*
X2748108Y514214D01*
X2748545Y515964D01*
X2748108Y517715D01*
X2747016Y519173D01*
X2745051Y520048D01*
X2743086Y519756D01*
X2741121Y518589D01*
G01X2704811Y554698D02*
Y537198D01*
X2713545D01*
G01X2726678D02*
Y554698D01*
X2724058Y551198D01*
G01Y537198D02*
X2729298D01*
G01X2739375Y540698D02*
X2740684Y538656D01*
X2742431Y537490D01*
X2744396Y537198D01*
X2746143Y537490D01*
X2747890Y538948D01*
X2748981Y540698D01*
X2749200Y542448D01*
X2748763Y544489D01*
X2747235Y545948D01*
X2745706Y546531D01*
X2743741D01*
G01X2745706D02*
X2747016Y547406D01*
X2748108Y548864D01*
X2748545Y550614D01*
X2748108Y552365D01*
X2747016Y553823D01*
X2745051Y554698D01*
X2743086Y554406D01*
X2741121Y553239D01*
G01X2704811Y589348D02*
Y571848D01*
X2713545D01*
G01X2726678D02*
Y589348D01*
X2724058Y585848D01*
G01Y571848D02*
X2729298D01*
G01X2739375Y575348D02*
X2740684Y573306D01*
X2742431Y572140D01*
X2744396Y571848D01*
X2746143Y572140D01*
X2747890Y573598D01*
X2748981Y575348D01*
X2749200Y577098D01*
X2748763Y579139D01*
X2747235Y580598D01*
X2745706Y581181D01*
X2743741D01*
G01X2745706D02*
X2747016Y582056D01*
X2748108Y583514D01*
X2748545Y585264D01*
X2748108Y587015D01*
X2747016Y588473D01*
X2745051Y589348D01*
X2743086Y589056D01*
X2741121Y587889D01*
G01X2923228Y548864D02*
Y537198D01*
G01Y553531D02*
X2922791Y553823D01*
Y554406D01*
X2923228Y554698D01*
X2923665Y554406D01*
Y553823D01*
X2923228Y553531D01*
G01X2937016Y537198D02*
Y548864D01*
G01Y545948D02*
X2937890Y547406D01*
X2939200Y548573D01*
X2940946Y548864D01*
X2942474Y548573D01*
X2943785Y547406D01*
X2944440Y545365D01*
Y537198D01*
G01X2954953Y539239D02*
X2956045Y538073D01*
X2957573Y537198D01*
X2958883D01*
X2960193Y537781D01*
X2961066Y538656D01*
X2961503Y539822D01*
X2961285Y541573D01*
X2960411Y542448D01*
X2956481Y544198D01*
X2955608Y546240D01*
X2956045Y547698D01*
X2956918Y548573D01*
X2958228Y548864D01*
X2959538Y548573D01*
X2960848Y547698D01*
G01X2975728Y548864D02*
Y537198D01*
G01Y553531D02*
X2975291Y553823D01*
Y554406D01*
X2975728Y554698D01*
X2976165Y554406D01*
Y553823D01*
X2975728Y553531D01*
G01X2997158Y554698D02*
Y537198D01*
G01Y539822D02*
X2996285Y538364D01*
X2994974Y537490D01*
X2993446Y537198D01*
X2991700Y537781D01*
X2990390Y539239D01*
X2989516Y540989D01*
X2989298Y543031D01*
X2989516Y545073D01*
X2990390Y546823D01*
X2991700Y548281D01*
X2993446Y548864D01*
X2994974Y548573D01*
X2996066Y547989D01*
X2997158Y546823D01*
G01X3007453Y545073D02*
X3014440D01*
X3013785Y547115D01*
X3012693Y548281D01*
X3011165Y548864D01*
X3009636Y548573D01*
X3008326Y547698D01*
X3007453Y545656D01*
X3007016Y543906D01*
Y542156D01*
X3007453Y540406D01*
X3008545Y538656D01*
X3009855Y537490D01*
X3011383Y537198D01*
X3012911Y537781D01*
X3014440Y539531D01*
G01X3041798Y537198D02*
Y554698D01*
G01Y545948D02*
X3042890Y547698D01*
X3044200Y548573D01*
X3045510Y548864D01*
X3047474Y548281D01*
X3048785Y547115D01*
X3049658Y545073D01*
Y542740D01*
X3049221Y540406D01*
X3048348Y538656D01*
X3046820Y537490D01*
X3045510Y537198D01*
X3044200Y537490D01*
X3042890Y538364D01*
X3041798Y539822D01*
G01X3063228Y537198D02*
X3061918Y537490D01*
X3060608Y538656D01*
X3059734Y540698D01*
X3059298Y543031D01*
X3059734Y545365D01*
X3060608Y547406D01*
X3061918Y548573D01*
X3063228Y548864D01*
X3064538Y548573D01*
X3065848Y547406D01*
X3066721Y545365D01*
X3066940Y543031D01*
X3066721Y540698D01*
X3065848Y538656D01*
X3064538Y537490D01*
X3063228Y537198D01*
G01X3084658D02*
Y548864D01*
G01Y546823D02*
X3083785Y547989D01*
X3082474Y548573D01*
X3080946Y548864D01*
X3079418Y548281D01*
X3078108Y547115D01*
X3077234Y545365D01*
X3076798Y543031D01*
X3077234Y540698D01*
X3078108Y538948D01*
X3079418Y537781D01*
X3080946Y537198D01*
X3082474Y537490D01*
X3083785Y538364D01*
X3084658Y539531D01*
G01X3095171Y537198D02*
Y548864D01*
G01Y546531D02*
X3096263Y547698D01*
X3097355Y548573D01*
X3098883Y548864D01*
X3099974Y548573D01*
X3101285Y547698D01*
G01X3119658Y554698D02*
Y537198D01*
G01Y539822D02*
X3118785Y538364D01*
X3117474Y537490D01*
X3115946Y537198D01*
X3114200Y537781D01*
X3112890Y539239D01*
X3112016Y540989D01*
X3111798Y543031D01*
X3112016Y545073D01*
X3112890Y546823D01*
X3114200Y548281D01*
X3115946Y548864D01*
X3117474Y548573D01*
X3118566Y547989D01*
X3119658Y546823D01*
G01X3150728Y537198D02*
X3149418Y537490D01*
X3148108Y538656D01*
X3147234Y540698D01*
X3146798Y543031D01*
X3147234Y545365D01*
X3148108Y547406D01*
X3149418Y548573D01*
X3150728Y548864D01*
X3152038Y548573D01*
X3153348Y547406D01*
X3154221Y545365D01*
X3154440Y543031D01*
X3154221Y540698D01*
X3153348Y538656D01*
X3152038Y537490D01*
X3150728Y537198D01*
G01X3164516Y548864D02*
Y540698D01*
X3165390Y538656D01*
X3166700Y537490D01*
X3168228Y537198D01*
X3169756Y537490D01*
X3171066Y538656D01*
X3171940Y540698D01*
G01Y537198D02*
Y548864D01*
G01X3185728Y554698D02*
Y537198D01*
G01X3182671Y548864D02*
X3188785D01*
G01X3203228Y537198D02*
Y554698D01*
G01X3220728Y548864D02*
Y537198D01*
G01Y553531D02*
X3220291Y553823D01*
Y554406D01*
X3220728Y554698D01*
X3221165Y554406D01*
Y553823D01*
X3220728Y553531D01*
G01X3234516Y537198D02*
Y548864D01*
G01Y545948D02*
X3235390Y547406D01*
X3236700Y548573D01*
X3238446Y548864D01*
X3239974Y548573D01*
X3241285Y547406D01*
X3241940Y545365D01*
Y537198D01*
G01X3252453Y545073D02*
X3259440D01*
X3258785Y547115D01*
X3257693Y548281D01*
X3256165Y548864D01*
X3254636Y548573D01*
X3253326Y547698D01*
X3252453Y545656D01*
X3252016Y543906D01*
Y542156D01*
X3252453Y540406D01*
X3253545Y538656D01*
X3254855Y537490D01*
X3256383Y537198D01*
X3257911Y537781D01*
X3259440Y539531D01*
G01X3273228Y536615D02*
X3272791Y536906D01*
Y537490D01*
X3273228Y537781D01*
X3273665Y537490D01*
Y536906D01*
X3273228Y536615D01*
G01X2923228Y583514D02*
Y571848D01*
G01Y588181D02*
X2922791Y588473D01*
Y589056D01*
X2923228Y589348D01*
X2923665Y589056D01*
Y588473D01*
X2923228Y588181D01*
G01X2937453Y573889D02*
X2938545Y572723D01*
X2940073Y571848D01*
X2941383D01*
X2942693Y572431D01*
X2943566Y573306D01*
X2944003Y574472D01*
X2943785Y576223D01*
X2942911Y577098D01*
X2938981Y578848D01*
X2938108Y580890D01*
X2938545Y582348D01*
X2939418Y583223D01*
X2940728Y583514D01*
X2942038Y583223D01*
X2943348Y582348D01*
G01X2970706Y571848D02*
Y589348D01*
X2980750Y571848D01*
Y589348D01*
G01X2993228Y571848D02*
X2991481Y572140D01*
X2989953Y573306D01*
X2988643Y575056D01*
X2987769Y577098D01*
X2987333Y579431D01*
Y581765D01*
X2987769Y584098D01*
X2988643Y586140D01*
X2989953Y587889D01*
X2991481Y589056D01*
X2993228Y589348D01*
X2994974Y589056D01*
X2996503Y587889D01*
X2997813Y586140D01*
X2998687Y584098D01*
X2999123Y581765D01*
Y579431D01*
X2998687Y577098D01*
X2997813Y575056D01*
X2996503Y573306D01*
X2994974Y572140D01*
X2993228Y571848D01*
G01X3010728Y589348D02*
Y571848D01*
G01X3005706Y589348D02*
X3015750D01*
G01X3042016Y583514D02*
Y575348D01*
X3042890Y573306D01*
X3044200Y572140D01*
X3045728Y571848D01*
X3047256Y572140D01*
X3048566Y573306D01*
X3049440Y575348D01*
G01Y571848D02*
Y583514D01*
G01X3059953Y573889D02*
X3061045Y572723D01*
X3062573Y571848D01*
X3063883D01*
X3065193Y572431D01*
X3066066Y573306D01*
X3066503Y574472D01*
X3066285Y576223D01*
X3065411Y577098D01*
X3061481Y578848D01*
X3060608Y580890D01*
X3061045Y582348D01*
X3061918Y583223D01*
X3063228Y583514D01*
X3064538Y583223D01*
X3065848Y582348D01*
G01X3077453Y579723D02*
X3084440D01*
X3083785Y581765D01*
X3082693Y582931D01*
X3081165Y583514D01*
X3079636Y583223D01*
X3078326Y582348D01*
X3077453Y580306D01*
X3077016Y578556D01*
Y576806D01*
X3077453Y575056D01*
X3078545Y573306D01*
X3079855Y572140D01*
X3081383Y571848D01*
X3082911Y572431D01*
X3084440Y574181D01*
G01X3102158Y589348D02*
Y571848D01*
G01Y574472D02*
X3101285Y573014D01*
X3099974Y572140D01*
X3098446Y571848D01*
X3096700Y572431D01*
X3095390Y573889D01*
X3094516Y575639D01*
X3094298Y577681D01*
X3094516Y579723D01*
X3095390Y581473D01*
X3096700Y582931D01*
X3098446Y583514D01*
X3099974Y583223D01*
X3101066Y582639D01*
X3102158Y581473D01*
G01X3133228Y583514D02*
Y571848D01*
G01Y588181D02*
X3132791Y588473D01*
Y589056D01*
X3133228Y589348D01*
X3133665Y589056D01*
Y588473D01*
X3133228Y588181D01*
G01X3147016Y571848D02*
Y583514D01*
G01Y580598D02*
X3147890Y582056D01*
X3149200Y583223D01*
X3150946Y583514D01*
X3152474Y583223D01*
X3153785Y582056D01*
X3154440Y580015D01*
Y571848D01*
G01X3185728Y589348D02*
Y571848D01*
G01X3182671Y583514D02*
X3188785D01*
G01X3199516Y571848D02*
Y589348D01*
G01Y580890D02*
X3200608Y582348D01*
X3201700Y583223D01*
X3203446Y583514D01*
X3204756Y583223D01*
X3206285Y582056D01*
X3206940Y580306D01*
Y571848D01*
G01X3220728Y583514D02*
Y571848D01*
G01Y588181D02*
X3220291Y588473D01*
Y589056D01*
X3220728Y589348D01*
X3221165Y589056D01*
Y588473D01*
X3220728Y588181D01*
G01X3234953Y573889D02*
X3236045Y572723D01*
X3237573Y571848D01*
X3238883D01*
X3240193Y572431D01*
X3241066Y573306D01*
X3241503Y574472D01*
X3241285Y576223D01*
X3240411Y577098D01*
X3236481Y578848D01*
X3235608Y580890D01*
X3236045Y582348D01*
X3236918Y583223D01*
X3238228Y583514D01*
X3239538Y583223D01*
X3240848Y582348D01*
G01X3273228Y571848D02*
Y589348D01*
G01X3294658Y571848D02*
Y583514D01*
G01Y581473D02*
X3293785Y582639D01*
X3292474Y583223D01*
X3290946Y583514D01*
X3289418Y582931D01*
X3288108Y581765D01*
X3287234Y580015D01*
X3286798Y577681D01*
X3287234Y575348D01*
X3288108Y573598D01*
X3289418Y572431D01*
X3290946Y571848D01*
X3292474Y572140D01*
X3293785Y573014D01*
X3294658Y574181D01*
G01X3303643Y566598D02*
X3304953Y566015D01*
X3306700Y566598D01*
X3307791Y567764D01*
X3308665Y569223D01*
X3309974Y573889D01*
X3312813Y583514D01*
G01X3305826D02*
X3309974Y573889D01*
G01X3322453Y579723D02*
X3329440D01*
X3328785Y581765D01*
X3327693Y582931D01*
X3326165Y583514D01*
X3324636Y583223D01*
X3323326Y582348D01*
X3322453Y580306D01*
X3322016Y578556D01*
Y576806D01*
X3322453Y575056D01*
X3323545Y573306D01*
X3324855Y572140D01*
X3326383Y571848D01*
X3327911Y572431D01*
X3329440Y574181D01*
G01X3340171Y571848D02*
Y583514D01*
G01Y581181D02*
X3341263Y582348D01*
X3342355Y583223D01*
X3343883Y583514D01*
X3344974Y583223D01*
X3346285Y582348D01*
G01X2848425Y605915D02*
X2858031Y618748D01*
G01X2853228Y621081D02*
Y603581D01*
G01X2858031Y605915D02*
X2848425Y618748D01*
G01X2846678Y612331D02*
X2859778D01*
G01X2885390D02*
X2891066D01*
G01X2918425Y606498D02*
Y623998D01*
X2922791D01*
X2924538Y623123D01*
X2925848Y621956D01*
X2926940Y620207D01*
X2927813Y618164D01*
X2928031Y615248D01*
X2927813Y612331D01*
X2926940Y610289D01*
X2925848Y608539D01*
X2924538Y607373D01*
X2922791Y606498D01*
X2918425D01*
G01X2937453Y614373D02*
X2944440D01*
X2943785Y616415D01*
X2942693Y617581D01*
X2941165Y618164D01*
X2939636Y617873D01*
X2938326Y616998D01*
X2937453Y614956D01*
X2937016Y613206D01*
Y611456D01*
X2937453Y609706D01*
X2938545Y607956D01*
X2939855Y606790D01*
X2941383Y606498D01*
X2942911Y607081D01*
X2944440Y608831D01*
G01X2954516Y606498D02*
Y618164D01*
G01Y615248D02*
X2955390Y616706D01*
X2956700Y617873D01*
X2958446Y618164D01*
X2959974Y617873D01*
X2961285Y616706D01*
X2961940Y614665D01*
Y606498D01*
G01X2975728D02*
X2974418Y606790D01*
X2973108Y607956D01*
X2972234Y609998D01*
X2971798Y612331D01*
X2972234Y614665D01*
X2973108Y616706D01*
X2974418Y617873D01*
X2975728Y618164D01*
X2977038Y617873D01*
X2978348Y616706D01*
X2979221Y614665D01*
X2979440Y612331D01*
X2979221Y609998D01*
X2978348Y607956D01*
X2977038Y606790D01*
X2975728Y606498D01*
G01X2993228Y623998D02*
Y606498D01*
G01X2990171Y618164D02*
X2996285D01*
G01X3007453Y614373D02*
X3014440D01*
X3013785Y616415D01*
X3012693Y617581D01*
X3011165Y618164D01*
X3009636Y617873D01*
X3008326Y616998D01*
X3007453Y614956D01*
X3007016Y613206D01*
Y611456D01*
X3007453Y609706D01*
X3008545Y607956D01*
X3009855Y606790D01*
X3011383Y606498D01*
X3012911Y607081D01*
X3014440Y608831D01*
G01X3024953Y608539D02*
X3026045Y607373D01*
X3027573Y606498D01*
X3028883D01*
X3030193Y607081D01*
X3031066Y607956D01*
X3031503Y609122D01*
X3031285Y610873D01*
X3030411Y611748D01*
X3026481Y613498D01*
X3025608Y615540D01*
X3026045Y616998D01*
X3026918Y617873D01*
X3028228Y618164D01*
X3029538Y617873D01*
X3030848Y616998D01*
G01X3063228Y623998D02*
Y606498D01*
G01X3060171Y618164D02*
X3066285D01*
G01X3077016Y606498D02*
Y623998D01*
G01Y615540D02*
X3078108Y616998D01*
X3079200Y617873D01*
X3080946Y618164D01*
X3082256Y617873D01*
X3083785Y616706D01*
X3084440Y614956D01*
Y606498D01*
G01X3102158D02*
Y618164D01*
G01Y616123D02*
X3101285Y617289D01*
X3099974Y617873D01*
X3098446Y618164D01*
X3096918Y617581D01*
X3095608Y616415D01*
X3094734Y614665D01*
X3094298Y612331D01*
X3094734Y609998D01*
X3095608Y608248D01*
X3096918Y607081D01*
X3098446Y606498D01*
X3099974Y606790D01*
X3101285Y607664D01*
X3102158Y608831D01*
G01X3115728Y623998D02*
Y606498D01*
G01X3112671Y618164D02*
X3118785D01*
G01X3144178Y623998D02*
X3147234Y606498D01*
X3150728Y623998D01*
X3154221Y606498D01*
X3157278Y623998D01*
G01X3165608D02*
X3170848D01*
G01X3168228D02*
Y606498D01*
G01X3165608D02*
X3170848D01*
G01X3180925D02*
Y623998D01*
X3185291D01*
X3187038Y623123D01*
X3188348Y621956D01*
X3189440Y620207D01*
X3190313Y618164D01*
X3190531Y615248D01*
X3190313Y612331D01*
X3189440Y610289D01*
X3188348Y608539D01*
X3187038Y607373D01*
X3185291Y606498D01*
X3180925D01*
G01X3203228Y623998D02*
Y606498D01*
G01X3198206Y623998D02*
X3208250D01*
G01X3216143Y606498D02*
Y623998D01*
G01X3225313D02*
Y606498D01*
G01Y615248D02*
X3216143D01*
G01X-7874Y-31496D02*
X-19685D01*
G01X-7874D02*
X-19685D01*
G01D02*
G03X-23622Y-35433I0J-3937D01*
G01D02*
Y-59055D01*
G01Y-35433D02*
Y-59055D01*
G01X-19685Y-31496D02*
G03X-23622Y-35433I0J-3937D01*
G01Y-59055D02*
G03X-19685Y-62992I3937J0D01*
G01D02*
X1972441D01*
G01X-19685D02*
X1972441D01*
G01X-23622Y-59055D02*
G03X-19685Y-62992I3937J0D01*
G01Y-23622D02*
X1972441D01*
G01X-19685D02*
X1972441D01*
G01X-19685D02*
X1972441D01*
G01X-19685D02*
X1972441D01*
G01X-23622Y622441D02*
Y-19685D01*
G01Y622441D02*
Y-19685D01*
G01Y622441D02*
Y-19685D01*
G01Y622441D02*
Y-19685D01*
G01D02*
G03X-19685Y-23622I3937J0D01*
G01X-23622Y-19685D02*
G03X-19685Y-23622I3937J0D01*
G01X-23622Y-19685D02*
G03X-19685Y-23622I3937J0D01*
G01X-23622Y-19685D02*
G03X-19685Y-23622I3937J0D01*
G01X1972441Y626378D02*
X-19685D01*
G01X1972441D02*
X-19685D01*
G01X1972441D02*
X-19685D01*
G01X1972441D02*
X-19685D01*
G01D02*
G03X-23622Y622441I0J-3937D01*
G01X-19685Y626378D02*
G03X-23622Y622441I0J-3937D01*
G01X-19685Y626378D02*
G03X-23622Y622441I0J-3937D01*
G01X-19685Y626378D02*
G03X-23622Y622441I0J-3937D01*
G01X-19685Y634252D02*
X-7874D01*
G01X-19685D02*
X-7874D01*
G01X-23622Y661811D02*
Y638189D01*
G01Y661811D02*
Y638189D01*
G01D02*
G03X-19685Y634252I3937J0D01*
G01X-23622Y638189D02*
G03X-19685Y634252I3937J0D01*
G01X1972441Y665748D02*
X-19685D01*
G01X1972441D02*
X-19685D01*
G01D02*
G03X-23622Y661811I0J-3937D01*
G01X-19685Y665748D02*
G03X-23622Y661811I0J-3937D01*
G01X-7874Y-31496D02*
G03Y-23622I0J3937D01*
G01Y-31496D02*
G03Y-23622I0J3937D01*
G01X22835D02*
G03Y-31496I0J-3937D01*
G01X137795D02*
X22835D01*
G01X137795D02*
X22835D01*
G01Y-23622D02*
G03Y-31496I0J-3937D01*
G01X0Y616535D02*
G03Y604724I0J-5905D01*
G01Y616535D02*
G03Y604724I0J-5905D01*
G01Y616535D02*
X2646D01*
G01X2644D02*
X0D01*
G01Y604724D02*
X2644D01*
G01X2646D02*
X0D01*
G01X2646D02*
X0D01*
G01D02*
X2644D01*
G01Y616535D02*
X0D01*
G01D02*
X2646D01*
G01X0D02*
G03Y604724I0J-5905D01*
G01Y616535D02*
G03Y604724I0J-5905D01*
G01X2646Y616535D02*
G03X7595Y618285I0J7874D01*
G01X2644Y616535D02*
G03X7593Y618285I0J7874D01*
G01X2644Y616535D02*
G03X7593Y618285I0J7874D01*
G01X7595Y602975D02*
G03X2646Y604724I-4948J-6125D01*
G01X7593Y602975D02*
G03X2644Y604724I-4948J-6125D01*
G01X7593Y602975D02*
G03X2644Y604724I-4948J-6125D01*
G01X7593Y602975D02*
G03X2644Y604724I-4948J-6125D01*
G01X7593Y602975D02*
G03X2644Y604724I-4948J-6125D01*
G01X7595Y602975D02*
G03X2646Y604724I-4948J-6125D01*
G01X2644Y616535D02*
G03X7593Y618285I0J7874D01*
G01X2644Y616535D02*
G03X7593Y618285I0J7874D01*
G01X2646Y616535D02*
G03X7595Y618285I0J7874D01*
G01Y602975D02*
G03Y618285I6186J7655D01*
G01X7593Y602975D02*
G03Y618285I6187J7655D01*
G01Y602975D02*
G03Y618285I6187J7655D01*
G01Y602975D02*
G03Y618285I6187J7655D01*
G01Y602975D02*
G03Y618285I6187J7655D01*
G01X7595Y602975D02*
G03Y618285I6186J7655D01*
G01X-7874Y626378D02*
G03Y634252I0J3937D01*
G01Y626378D02*
G03Y634252I0J3937D01*
G01X22835D02*
G03Y626378I0J-3937D01*
G01Y634252D02*
X137795D01*
G01X22835D02*
X137795D01*
G01X22835D02*
G03Y626378I0J-3937D01*
G01X168504Y-23622D02*
G03Y-31496I0J-3937D01*
G01X137795D02*
G03Y-23622I0J3937D01*
G01X341732Y-31496D02*
X168504D01*
G01X341732D02*
X168504D01*
G01X137795D02*
G03Y-23622I0J3937D01*
G01X168504D02*
G03Y-31496I0J-3937D01*
G01Y634252D02*
G03Y626378I0J-3937D01*
G01X137795D02*
G03Y634252I0J3937D01*
G01X168504D02*
X341732D01*
G01X168504D02*
X341732D01*
G01X137795Y626378D02*
G03Y634252I0J3937D01*
G01X168504D02*
G03Y626378I0J-3937D01*
G01X341732Y-31496D02*
G03Y-23622I0J3937D01*
G01Y-31496D02*
G03Y-23622I0J3937D01*
G01Y626378D02*
G03Y634252I0J3937D01*
G01Y626378D02*
G03Y634252I0J3937D01*
G01X372441Y-23622D02*
G03Y-31496I0J-3937D01*
G01X529921D02*
X372441D01*
G01X529921D02*
X372441D01*
G01Y-23622D02*
G03Y-31496I0J-3937D01*
G01Y634252D02*
G03Y626378I0J-3937D01*
G01Y634252D02*
X529921D01*
G01X372441D02*
X529921D01*
G01X372441D02*
G03Y626378I0J-3937D01*
G01X529921Y-31496D02*
G03Y-23622I0J3937D01*
G01Y-31496D02*
G03Y-23622I0J3937D01*
G01Y626378D02*
G03Y634252I0J3937D01*
G01Y626378D02*
G03Y634252I0J3937D01*
G01X560630Y-23622D02*
G03Y-31496I0J-3937D01*
G01X788976D02*
X560630D01*
G01X788976D02*
X560630D01*
G01Y-23622D02*
G03Y-31496I0J-3937D01*
G01Y634252D02*
G03Y626378I0J-3937D01*
G01Y634252D02*
X788976D01*
G01X560630D02*
X788976D01*
G01X560630D02*
G03Y626378I0J-3937D01*
G01X684760Y-15529D02*
G03Y-219I6187J7655D01*
G01X684759Y-15529D02*
G03X679809Y-13780I-4948J-6125D01*
G01X679811Y-1969D02*
G03X684760Y-219I0J7874D01*
G01X677165Y-1969D02*
X679811D01*
G01X677165D02*
G03Y-13780I0J-5906D01*
G01D02*
X679809D01*
G01X684760Y602975D02*
G03Y618285I6187J7655D01*
G01X684759Y602975D02*
G03Y618285I6186J7655D01*
G01Y602975D02*
G03Y618285I6186J7655D01*
G01Y602975D02*
G03Y618285I6186J7655D01*
G01Y602975D02*
G03Y618285I6186J7655D01*
G01X684760Y602975D02*
G03Y618285I6187J7655D01*
G01X679811Y616535D02*
G03X684760Y618285I0J7874D01*
G01X679809Y616535D02*
G03X684759Y618285I0J7874D01*
G01X679809Y616535D02*
G03X684759Y618285I0J7874D01*
G01X684760Y602975D02*
G03X679811Y604724I-4948J-6125D01*
G01X684759Y602975D02*
G03X679809Y604724I-4948J-6125D01*
G01X684759Y602975D02*
G03X679809Y604724I-4948J-6125D01*
G01X684759Y602975D02*
G03X679809Y604724I-4948J-6125D01*
G01X684759Y602975D02*
G03X679809Y604724I-4948J-6125D01*
G01X684760Y602975D02*
G03X679811Y604724I-4948J-6125D01*
G01X679809Y616535D02*
G03X684759Y618285I0J7874D01*
G01X679809Y616535D02*
G03X684759Y618285I0J7874D01*
G01X679811Y616535D02*
G03X684760Y618285I0J7874D01*
G01X677165Y616535D02*
X679811D01*
G01X677165D02*
G03Y604724I0J-5905D01*
G01D02*
X679809D01*
G01X788976Y-31496D02*
G03Y-23622I0J3937D01*
G01Y-31496D02*
G03Y-23622I0J3937D01*
G01X819685D02*
G03Y-31496I0J-3937D01*
G01X975591D02*
X819685D01*
G01X975591D02*
X819685D01*
G01Y-23622D02*
G03Y-31496I0J-3937D01*
G01X788976Y626378D02*
G03Y634252I0J3937D01*
G01Y626378D02*
G03Y634252I0J3937D01*
G01X819685D02*
G03Y626378I0J-3937D01*
G01Y634252D02*
X975591D01*
G01X819685D02*
X975591D01*
G01X819685D02*
G03Y626378I0J-3937D01*
G01X975591Y-31496D02*
G03Y-23622I0J3937D01*
G01Y-31496D02*
G03Y-23622I0J3937D01*
G01X1006299D02*
G03Y-31496I0J-3937D01*
G01X1162205D02*
X1006299D01*
G01X1162205D02*
X1006299D01*
G01Y-23622D02*
G03Y-31496I0J-3937D01*
G01Y634252D02*
X1162205D01*
G01X1006299D02*
X1162205D01*
G01X975591Y626378D02*
G03Y634252I0J3937D01*
G01Y626378D02*
G03Y634252I0J3937D01*
G01X1006299D02*
G03Y626378I0J-3937D01*
G01Y634252D02*
G03Y626378I0J-3937D01*
G01X1162205Y-31496D02*
G03Y-23622I0J3937D01*
G01Y-31496D02*
G03Y-23622I0J3937D01*
G01X1192913D02*
G03Y-31496I0J-3937D01*
G01X1398425D02*
X1192913D01*
G01X1398425D02*
X1192913D01*
G01Y-23622D02*
G03Y-31496I0J-3937D01*
G01Y634252D02*
X1394488D01*
G01X1192913D02*
X1394488D01*
G01X1162205Y626378D02*
G03Y634252I0J3937D01*
G01Y626378D02*
G03Y634252I0J3937D01*
G01X1192913D02*
G03Y626378I0J-3937D01*
G01Y634252D02*
G03Y626378I0J-3937D01*
G01X1398425Y-31496D02*
G03Y-23622I0J3937D01*
G01Y-31496D02*
G03Y-23622I0J3937D01*
G01X1405512Y-1968D02*
G03Y-13779I0J-5906D01*
G01Y-1968D02*
G03Y-13779I0J-5906D01*
G01Y-1968D02*
G03Y-13779I0J-5906D01*
G01Y-1968D02*
G03Y-13779I0J-5906D01*
G01X1394488Y626378D02*
G03Y634252I0J3937D01*
G01Y626378D02*
G03Y634252I0J3937D01*
G01X1405512Y616535D02*
G03Y604724I0J-5905D01*
G01Y616535D02*
G03Y604724I0J-5905D01*
G01Y616535D02*
G03Y604724I0J-5905D01*
G01Y616535D02*
G03Y604724I0J-5905D01*
G01X1429134Y-23622D02*
G03Y-31496I0J-3937D01*
G01X1851181D02*
X1429134D01*
G01X1851181D02*
X1429134D01*
G01Y-23622D02*
G03Y-31496I0J-3937D01*
G01X1413107Y-15529D02*
G03Y-218I6186J7655D01*
G01X1413105Y-15529D02*
G03Y-218I6186J7655D01*
G01Y-15529D02*
G03Y-218I6186J7655D01*
G01Y-15529D02*
G03Y-218I6186J7655D01*
G01Y-15529D02*
G03Y-218I6186J7655D01*
G01X1413107Y-15529D02*
G03Y-218I6186J7655D01*
G01X1408157Y-1968D02*
G03X1413107Y-218I1J7874D01*
G01X1408156Y-1968D02*
G03X1413105Y-218I0J7874D01*
G01X1408156Y-1968D02*
G03X1413105Y-218I0J7874D01*
G01X1408156Y-1968D02*
G03X1413105Y-218I0J7874D01*
G01X1408156Y-1968D02*
G03X1413105Y-218I0J7874D01*
G01X1408157Y-1968D02*
G03X1413107Y-218I1J7874D01*
G01Y-15529D02*
G03X1408157Y-13779I-4949J-6124D01*
G01X1413105Y-15529D02*
G03X1408156Y-13779I-4949J-6124D01*
G01X1413105Y-15529D02*
G03X1408156Y-13779I-4949J-6124D01*
G01X1413105Y-15529D02*
G03X1408156Y-13779I-4949J-6124D01*
G01X1413105Y-15529D02*
G03X1408156Y-13779I-4949J-6124D01*
G01X1413107Y-15529D02*
G03X1408157Y-13779I-4949J-6124D01*
G01X1405512D02*
X1408156D01*
G01X1408157D02*
X1405512D01*
G01X1408157D02*
X1405512D01*
G01D02*
X1408156D01*
G01X1405512Y-1968D02*
X1408157D01*
G01X1408156D02*
X1405512D01*
G01X1408156D02*
X1405512D01*
G01D02*
X1408157D01*
G01X1425197Y634252D02*
X1851181D01*
G01X1425197D02*
X1851181D01*
G01X1425197D02*
G03Y626378I0J-3937D01*
G01Y634252D02*
G03Y626378I0J-3937D01*
G01X1408157Y616535D02*
G03X1413107Y618285I1J7874D01*
G01X1408156Y616535D02*
G03X1413105Y618285I0J7874D01*
G01X1408156Y616535D02*
G03X1413105Y618285I0J7874D01*
G01X1413107Y602975D02*
G03Y618285I6186J7655D01*
G01X1413105Y602975D02*
G03Y618285I6187J7655D01*
G01Y602975D02*
G03Y618285I6187J7655D01*
G01X1413107Y602975D02*
G03X1408157Y604724I-4948J-6125D01*
G01X1413105Y602975D02*
G03X1408156Y604724I-4948J-6125D01*
G01X1413105Y602975D02*
G03X1408156Y604724I-4948J-6125D01*
G01X1413105Y602975D02*
G03X1408156Y604724I-4948J-6125D01*
G01X1413105Y602975D02*
G03X1408156Y604724I-4948J-6125D01*
G01X1413107Y602975D02*
G03X1408157Y604724I-4948J-6125D01*
G01X1413105Y602975D02*
G03Y618285I6187J7655D01*
G01Y602975D02*
G03Y618285I6187J7655D01*
G01X1413107Y602975D02*
G03Y618285I6186J7655D01*
G01X1408156Y616535D02*
G03X1413105Y618285I0J7874D01*
G01X1408156Y616535D02*
G03X1413105Y618285I0J7874D01*
G01X1408157Y616535D02*
G03X1413107Y618285I1J7874D01*
G01X1405512Y616535D02*
X1408157D01*
G01X1408156D02*
X1405512D01*
G01Y604724D02*
X1408156D01*
G01X1408157D02*
X1405512D01*
G01X1408157D02*
X1405512D01*
G01D02*
X1408156D01*
G01Y616535D02*
X1405512D01*
G01D02*
X1408157D01*
G01X1685866Y267244D02*
X1883780D01*
G01X1685866D02*
X1883780D01*
G01X1685866D02*
X1883780D01*
G01X1685866D02*
X1883780D01*
G01X1681929Y271181D02*
G03X1685866Y267244I3937J0D01*
G01X1681929Y271181D02*
G03X1685866Y267244I3937J0D01*
G01X1681929Y271181D02*
G03X1685866Y267244I3937J0D01*
G01X1681929Y271181D02*
G03X1685866Y267244I3937J0D01*
G01X1681929Y428661D02*
Y271181D01*
G01Y428661D02*
Y271181D01*
G01Y428661D02*
Y271181D01*
G01Y428661D02*
Y271181D01*
G01X1685866Y432598D02*
G03X1681929Y428661I0J-3937D01*
G01X1685866Y432598D02*
G03X1681929Y428661I0J-3937D01*
G01X1972441Y432598D02*
X1685866D01*
G01X1972441D02*
X1685866D01*
G01X1972441D02*
X1685866D01*
G01X1972441D02*
X1685866D01*
G01D02*
G03X1681929Y428661I0J-3937D01*
G01X1685866Y432598D02*
G03X1681929Y428661I0J-3937D01*
G01X1851181Y-31496D02*
G03Y-23622I0J3937D01*
G01Y-31496D02*
G03Y-23622I0J3937D01*
G01X1881890D02*
G03Y-31496I0J-3937D01*
G01X1972441D02*
X1881890D01*
G01X1972441D02*
X1881890D01*
G01Y-23622D02*
G03Y-31496I0J-3937D01*
G01X1861926Y-15529D02*
G03X1856976Y-13780I-4948J-6125D01*
G01X1861924Y-15529D02*
G03X1856975Y-13780I-4948J-6125D01*
G01X1861924Y-15529D02*
G03X1856975Y-13780I-4948J-6125D01*
G01X1861924Y-15529D02*
G03X1856975Y-13780I-4948J-6125D01*
G01X1861924Y-15529D02*
G03X1856975Y-13780I-4948J-6125D01*
G01X1861926Y-15529D02*
G03X1856976Y-13780I-4948J-6125D01*
G01Y-1969D02*
G03X1861926Y-219I0J7874D01*
G01X1856975Y-1969D02*
G03X1861924Y-219I0J7874D01*
G01X1856975Y-1969D02*
G03X1861924Y-219I0J7874D01*
G01X1861926Y-15529D02*
G03Y-219I6186J7655D01*
G01X1861924Y-15529D02*
G03Y-219I6186J7655D01*
G01Y-15529D02*
G03Y-219I6186J7655D01*
G01Y-15529D02*
G03Y-219I6186J7655D01*
G01Y-15529D02*
G03Y-219I6186J7655D01*
G01X1861926Y-15529D02*
G03Y-219I6186J7655D01*
G01X1856975Y-1969D02*
G03X1861924Y-219I0J7874D01*
G01X1856975Y-1969D02*
G03X1861924Y-219I0J7874D01*
G01X1856976Y-1969D02*
G03X1861926Y-219I0J7874D01*
G01X1854331Y-1969D02*
G03Y-13780I0J-5906D01*
G01Y-1969D02*
G03Y-13780I0J-5906D01*
G01D02*
X1856975D01*
G01X1856976D02*
X1854331D01*
G01X1856976D02*
X1854331D01*
G01D02*
X1856975D01*
G01X1854331Y-1969D02*
G03Y-13780I0J-5906D01*
G01Y-1969D02*
G03Y-13780I0J-5906D01*
G01Y-1969D02*
X1856976D01*
G01X1856975D02*
X1854331D01*
G01X1856975D02*
X1854331D01*
G01D02*
X1856976D01*
G01X1891654Y246772D02*
X1972441D01*
G01X1891654D02*
X1972441D01*
G01X1891654D02*
X1972441D01*
G01X1891654D02*
X1972441D01*
G01X1887717Y250709D02*
G03X1891654Y246772I3937J0D01*
G01X1887717Y250709D02*
G03X1891654Y246772I3937J0D01*
G01X1887717Y263307D02*
Y250709D01*
G01Y263307D02*
Y250709D01*
G01Y263307D02*
Y250709D01*
G01Y263307D02*
Y250709D01*
G01D02*
G03X1891654Y246772I3937J0D01*
G01X1887717Y250709D02*
G03X1891654Y246772I3937J0D01*
G01X1887717Y263307D02*
G03X1883780Y267244I-3937J0D01*
G01X1887717Y263307D02*
G03X1883780Y267244I-3937J0D01*
G01X1887717Y263307D02*
G03X1883780Y267244I-3937J0D01*
G01X1887717Y263307D02*
G03X1883780Y267244I-3937J0D01*
G01X1881890Y634252D02*
G03Y626378I0J-3937D01*
G01Y634252D02*
X1972441D01*
G01X1881890D02*
X1972441D01*
G01X1881890D02*
G03Y626378I0J-3937D01*
G01X1851181D02*
G03Y634252I0J3937D01*
G01Y626378D02*
G03Y634252I0J3937D01*
G01X1856976Y616535D02*
G03X1861926Y618285I0J7874D01*
G01X1856975Y616535D02*
G03X1861924Y618285I0J7874D01*
G01X1856975Y616535D02*
G03X1861924Y618285I0J7874D01*
G01X1861926Y602975D02*
G03Y618285I6186J7655D01*
G01X1861924Y602975D02*
G03Y618285I6186J7655D01*
G01Y602975D02*
G03Y618285I6186J7655D01*
G01Y602975D02*
G03Y618285I6186J7655D01*
G01Y602975D02*
G03Y618285I6186J7655D01*
G01X1861926Y602975D02*
G03Y618285I6186J7655D01*
G01X1856975Y616535D02*
G03X1861924Y618285I0J7874D01*
G01X1856975Y616535D02*
G03X1861924Y618285I0J7874D01*
G01X1856976Y616535D02*
G03X1861926Y618285I0J7874D01*
G01Y602975D02*
G03X1856976Y604724I-4948J-6125D01*
G01X1861924Y602975D02*
G03X1856975Y604724I-4948J-6125D01*
G01X1861924Y602975D02*
G03X1856975Y604724I-4948J-6125D01*
G01X1861924Y602975D02*
G03X1856975Y604724I-4948J-6125D01*
G01X1861924Y602975D02*
G03X1856975Y604724I-4948J-6125D01*
G01X1861926Y602975D02*
G03X1856976Y604724I-4948J-6125D01*
G01X1854331Y616535D02*
G03Y604724I0J-5905D01*
G01Y616535D02*
G03Y604724I0J-5905D01*
G01D02*
X1856975D01*
G01X1856976D02*
X1854331D01*
G01X1856976D02*
X1854331D01*
G01D02*
X1856975D01*
G01X1854331Y616535D02*
G03Y604724I0J-5905D01*
G01Y616535D02*
G03Y604724I0J-5905D01*
G01Y616535D02*
X1856976D01*
G01X1856975D02*
X1854331D01*
G01X1856975D02*
X1854331D01*
G01D02*
X1856976D01*
G01X1972441Y-11811D02*
X1906890D01*
G01X1904921Y-9843D02*
G03X1906890Y-11811I1969J1D01*
G01X1904921Y53150D02*
Y-9843D01*
G01X1972441Y-11811D02*
X1906890D01*
G01X1904921Y-9843D02*
G03X1906890Y-11811I1969J1D01*
G01X1904921Y53150D02*
Y-9843D01*
G01X1923071Y53150D02*
Y-9843D01*
G01X1940787Y-3937D02*
X1972441D01*
G01X1940787D02*
G03X1938819Y-5906I0J-1968D01*
G01Y-9843D02*
Y-5906D01*
G01Y-9843D02*
G03X1940787Y-11811I1968J0D01*
G01X1921102D02*
G03X1923071Y-9843I0J1969D01*
G01X1906890Y55118D02*
G03X1904921Y53150I0J-1969D01*
G01X1972441Y55118D02*
X1906890D01*
G01X1972441D02*
X1906890D01*
G01X1972441D02*
X1906890D01*
G01X1972441D02*
X1906890D01*
G01D02*
G03X1904921Y53150I0J-1969D01*
G01X1923071D02*
G03X1921102Y55118I-1969J-1D01*
G01X1940787D02*
G03X1938819Y53150I0J-1968D01*
G01Y49213D02*
Y53150D01*
G01Y49213D02*
G03X1940787Y47244I1968J-1D01*
G01X1972441D02*
X1940787D01*
G01X1976378Y-35433D02*
G03X1972441Y-31496I-3937J0D01*
G01X1976378Y-59055D02*
Y-35433D01*
G01Y-59055D02*
Y-35433D01*
G01D02*
G03X1972441Y-31496I-3937J0D01*
G01Y-62992D02*
G03X1976378Y-59055I0J3937D01*
G01X1972441Y-62992D02*
G03X1976378Y-59055I0J3937D01*
G01X1972441Y-23622D02*
G03X1976378Y-19685I0J3937D01*
G01X1972441Y-23622D02*
G03X1976378Y-19685I0J3937D01*
G01X1972441Y-23622D02*
G03X1976378Y-19685I0J3937D01*
G01X1972441Y-23622D02*
G03X1976378Y-19685I0J3937D01*
G01D02*
Y-15748D01*
G01Y-19685D02*
Y-15748D01*
G01Y-19685D02*
Y-15748D01*
G01Y-19685D02*
Y-15748D01*
G01D02*
G03X1972441Y-11811I-3937J0D01*
G01X1976378Y-15748D02*
G03X1972441Y-11811I-3937J0D01*
G01X1976378Y-15748D02*
G03X1972441Y-11811I-3937J0D01*
G01X1976378Y-15748D02*
G03X1972441Y-11811I-3937J0D01*
G01X1976378Y0D02*
Y43307D01*
G01X1972441Y-3937D02*
G03X1976378Y0I0J3937D01*
G01X1972441Y55118D02*
G03X1976378Y59055I0J3937D01*
G01X1972441Y55118D02*
G03X1976378Y59055I0J3937D01*
G01X1972441Y55118D02*
G03X1976378Y59055I0J3937D01*
G01X1972441Y55118D02*
G03X1976378Y59055I0J3937D01*
G01D02*
Y242835D01*
G01Y59055D02*
Y242835D01*
G01Y59055D02*
Y242835D01*
G01Y59055D02*
Y242835D01*
G01Y43307D02*
G03X1972441Y47244I-3937J0D01*
G01X1976378Y242835D02*
G03X1972441Y246772I-3937J0D01*
G01X1976378Y242835D02*
G03X1972441Y246772I-3937J0D01*
G01X1976378Y242835D02*
G03X1972441Y246772I-3937J0D01*
G01X1976378Y242835D02*
G03X1972441Y246772I-3937J0D01*
G01Y432598D02*
G03X1976378Y436535I0J3937D01*
G01X1972441Y432598D02*
G03X1976378Y436535I0J3937D01*
G01X1972441Y432598D02*
G03X1976378Y436535I0J3937D01*
G01X1972441Y432598D02*
G03X1976378Y436535I0J3937D01*
G01D02*
Y622441D01*
G01Y436535D02*
Y622441D01*
G01Y436535D02*
Y622441D01*
G01Y436535D02*
Y622441D01*
G01D02*
G03X1972441Y626378I-3937J0D01*
G01X1976378Y622441D02*
G03X1972441Y626378I-3937J0D01*
G01X1976378Y622441D02*
G03X1972441Y626378I-3937J0D01*
G01X1976378Y622441D02*
G03X1972441Y626378I-3937J0D01*
G01Y634252D02*
G03X1976378Y638189I0J3937D01*
G01X1972441Y634252D02*
G03X1976378Y638189I0J3937D01*
G01D02*
Y661811D01*
G01Y638189D02*
Y661811D01*
G01D02*
G03X1972441Y665748I-3937J0D01*
G01X1976378Y661811D02*
G03X1972441Y665748I-3937J0D01*
G54D12*
G01X38539Y94705D02*
X39494Y93750D01*
G01X34700Y97200D02*
X39100Y92800D01*
G01X39494Y93750D02*
X41585D01*
G01X43835D02*
X45185D01*
G01X39100Y92800D02*
X50799D01*
G01X34700Y97200D02*
X39100Y92800D01*
G01X34700Y97200D02*
X39100Y92800D01*
G01X38539Y94705D02*
X39494Y93750D01*
G01X39100Y92800D02*
X50799D01*
G01X39494Y93750D02*
X41585D01*
G01X39100Y92800D02*
X50799D01*
G01X43835Y93750D02*
X45185D01*
G01X39100Y92800D02*
X50799D01*
G01X-6654Y100482D02*
Y98943D01*
G01X-7604Y100165D02*
Y98549D01*
G01X-6654Y98943D02*
X-5861Y98150D01*
G01X-7604Y98549D02*
X-6255Y97200D01*
G01X-5861Y98150D02*
X-112D01*
G01X2138D02*
X16935D01*
G01X19185D02*
X31994D01*
G01X34244D02*
X35094D01*
G01X-6255Y97200D02*
X34700D01*
G01X35094Y98150D02*
X36948Y96296D01*
G01X-7604Y100165D02*
Y98549D01*
G01X-6654Y100482D02*
Y98943D01*
G01X-7604Y98549D02*
X-6255Y97200D01*
G01X-6654Y98943D02*
X-5861Y98150D01*
G01X-6255Y97200D02*
X34700D01*
G01X-5861Y98150D02*
X-112D01*
G01X-6255Y97200D02*
X34700D01*
G01X2138Y98150D02*
X16935D01*
G01X-6255Y97200D02*
X34700D01*
G01X19185Y98150D02*
X31994D01*
G01X-6255Y97200D02*
X34700D01*
G01X34244Y98150D02*
X35094D01*
G01D02*
X36948Y96296D01*
G01X9530Y101671D02*
Y103480D01*
G01X8580Y101671D02*
Y103874D01*
G01X9530Y103480D02*
X11194Y105144D01*
G01X8580Y103874D02*
X10800Y106094D01*
G01X11194Y105144D02*
X24001D01*
G01X26251D02*
X27601D01*
G01X29851D02*
X31201D01*
G01X10800Y106094D02*
X31390D01*
G01X31201Y105144D02*
X35535Y103348D01*
G01X37614Y102487D02*
X38861Y101970D01*
G01X40940Y101109D02*
X44174Y99770D01*
G01X31390Y106094D02*
X44363Y100720D01*
G01X44174Y99770D02*
X46455D01*
G01X44363Y100720D02*
X46445D01*
G01X4701Y109885D02*
Y111551D01*
G01X3751Y109834D02*
Y111945D01*
G01X4701Y111551D02*
X5707Y112557D01*
G01X3751Y111945D02*
X5313Y113507D01*
G01X5707Y112557D02*
X20400D01*
G01X22650D02*
X24000D01*
G01X26250D02*
X27600D01*
G01X29850D02*
X31200D01*
G01X33450D02*
X34800D01*
G01X5313Y113507D02*
X34406D01*
G01X34800Y112557D02*
X37902Y115659D01*
G01X39493Y117250D02*
X40447Y118204D01*
G01X42038Y119795D02*
X42993Y120750D01*
G01X34406Y113507D02*
X42599Y121700D01*
G01X42993Y120750D02*
X50850D01*
G01X42599Y121700D02*
X50528D01*
G01X9515Y117633D02*
Y119015D01*
G01X8565Y117570D02*
Y119409D01*
G01X9515Y119015D02*
X10931Y120431D01*
G01X8565Y119409D02*
X10537Y121381D01*
G01X10931Y120431D02*
X29775D01*
G01X10537Y121381D02*
X29381D01*
G01X29775Y120431D02*
X33932Y124588D01*
G01X35523Y126179D02*
X36477Y127133D01*
G01X38068Y128724D02*
X39023Y129679D01*
G01X40614Y131270D02*
X41568Y132224D01*
G01X43159Y133815D02*
X44114Y134770D01*
G01X29381Y121381D02*
X43720Y135720D01*
G01X44114Y134770D02*
X50929D01*
G01X43720Y135720D02*
X51011D01*
G01X8580Y101671D02*
Y103874D01*
G01X9530Y101671D02*
Y103480D01*
G01X8580Y103874D02*
X10800Y106094D01*
G01X9530Y103480D02*
X11194Y105144D01*
G01X10800Y106094D02*
X31390D01*
G01X11194Y105144D02*
X24001D01*
G01X10800Y106094D02*
X31390D01*
G01X26251Y105144D02*
X27601D01*
G01X10800Y106094D02*
X31390D01*
G01X29851Y105144D02*
X31201D01*
G01X31390Y106094D02*
X44363Y100720D01*
G01X31201Y105144D02*
X35535Y103348D01*
G01X31390Y106094D02*
X44363Y100720D01*
G01X37614Y102487D02*
X38861Y101970D01*
G01X31390Y106094D02*
X44363Y100720D01*
G01X40940Y101109D02*
X44174Y99770D01*
G01X44363Y100720D02*
X46445D01*
G01X44174Y99770D02*
X46455D01*
G01X3751Y109834D02*
Y111945D01*
G01X4701Y109885D02*
Y111551D01*
G01X3751Y111945D02*
X5313Y113507D01*
G01X4701Y111551D02*
X5707Y112557D01*
G01X5313Y113507D02*
X34406D01*
G01X5707Y112557D02*
X20400D01*
G01X5313Y113507D02*
X34406D01*
G01X22650Y112557D02*
X24000D01*
G01X5313Y113507D02*
X34406D01*
G01X26250Y112557D02*
X27600D01*
G01X5313Y113507D02*
X34406D01*
G01X29850Y112557D02*
X31200D01*
G01X5313Y113507D02*
X34406D01*
G01X33450Y112557D02*
X34800D01*
G01X34406Y113507D02*
X42599Y121700D01*
G01X34800Y112557D02*
X37902Y115659D01*
G01X34406Y113507D02*
X42599Y121700D01*
G01X39493Y117250D02*
X40447Y118204D01*
G01X34406Y113507D02*
X42599Y121700D01*
G01X42038Y119795D02*
X42993Y120750D01*
G01X42599Y121700D02*
X50528D01*
G01X42993Y120750D02*
X50850D01*
G01X8565Y117570D02*
Y119409D01*
G01X9515Y117633D02*
Y119015D01*
G01X8565Y119409D02*
X10537Y121381D01*
G01X9515Y119015D02*
X10931Y120431D01*
G01X10537Y121381D02*
X29381D01*
G01X10931Y120431D02*
X29775D01*
G01X29381Y121381D02*
X43720Y135720D01*
G01X29775Y120431D02*
X33932Y124588D01*
G01X29381Y121381D02*
X43720Y135720D01*
G01X35523Y126179D02*
X36477Y127133D01*
G01X29381Y121381D02*
X43720Y135720D01*
G01X38068Y128724D02*
X39023Y129679D01*
G01X29381Y121381D02*
X43720Y135720D01*
G01X40614Y131270D02*
X41568Y132224D01*
G01X29381Y121381D02*
X43720Y135720D01*
G01X43159Y133815D02*
X44114Y134770D01*
G01X43720Y135720D02*
X51011D01*
G01X44114Y134770D02*
X50929D01*
G01X25116Y148915D02*
Y151416D01*
G01X26066Y149535D02*
Y151022D01*
G01X25116Y151416D02*
X26632Y152932D01*
G01X26066Y151022D02*
X27026Y151982D01*
G01X26632Y152932D02*
X37812D01*
G01X27026Y151982D02*
X37418D01*
G01X37812Y152932D02*
X38814Y151930D01*
G01X37418Y151982D02*
X38420Y150980D01*
G01X38814Y151930D02*
X48030D01*
G01X38420Y150980D02*
X48424D01*
G01X41771Y148125D02*
X54123D01*
G01X54517Y147175D02*
X42165D01*
G01X38637Y144991D02*
X41771Y148125D01*
G01X42165Y147175D02*
X39031Y144041D01*
G01X-11366Y144991D02*
X38637D01*
G01X39031Y144041D02*
X-10972D01*
G01X-13073Y143284D02*
X-11366Y144991D01*
G01X-10972Y144041D02*
X-12123Y142890D01*
G01X-13073Y141041D02*
Y143284D01*
G01X-12123Y142890D02*
Y141041D01*
G01X26066Y149535D02*
Y151022D01*
G01X25116Y148915D02*
Y151416D01*
G01X26066Y151022D02*
X27026Y151982D01*
G01X25116Y151416D02*
X26632Y152932D01*
G01X27026Y151982D02*
X37418D01*
G01X26632Y152932D02*
X37812D01*
G01X37418Y151982D02*
X38420Y150980D01*
G01X37812Y152932D02*
X38814Y151930D01*
G01X38420Y150980D02*
X48424D01*
G01X38814Y151930D02*
X48030D01*
G01X-12123Y142890D02*
Y141041D01*
G01X-13073D02*
Y143284D01*
G01X-10972Y144041D02*
X-12123Y142890D01*
G01X-13073Y143284D02*
X-11366Y144991D01*
G01X39031Y144041D02*
X-10972D01*
G01X-11366Y144991D02*
X38637D01*
G01X42165Y147175D02*
X39031Y144041D01*
G01X38637Y144991D02*
X41771Y148125D01*
G01X54517Y147175D02*
X42165D01*
G01X41771Y148125D02*
X54123D01*
G01X41771D02*
X54123D01*
G01X54517Y147175D02*
X42165D01*
G01X38637Y144991D02*
X41771Y148125D01*
G01X42165Y147175D02*
X39031Y144041D01*
G01X-11366Y144991D02*
X38637D01*
G01X39031Y144041D02*
X-10972D01*
G01X-13073Y143284D02*
X-11366Y144991D01*
G01X-10972Y144041D02*
X-12123Y142890D01*
G01X-13073Y141041D02*
Y143284D01*
G01X-12123Y142890D02*
Y141041D01*
G01Y142890D02*
Y141041D01*
G01X-13073D02*
Y143284D01*
G01X-10972Y144041D02*
X-12123Y142890D01*
G01X-13073Y143284D02*
X-11366Y144991D01*
G01X39031Y144041D02*
X-10972D01*
G01X-11366Y144991D02*
X38637D01*
G01X42165Y147175D02*
X39031Y144041D01*
G01X38637Y144991D02*
X41771Y148125D01*
G01X54517Y147175D02*
X42165D01*
G01X41771Y148125D02*
X54123D01*
G01X45759Y424034D02*
X36624Y401980D01*
G01X44953Y424573D02*
X35818Y402519D01*
G01X36624Y401980D02*
X34437Y399794D01*
G01X35818Y402519D02*
X34043Y400744D01*
G01X34437Y399794D02*
X27706D01*
G01X34043Y400744D02*
X28100D01*
G01X27706Y399794D02*
X25340Y402160D01*
G01X28100Y400744D02*
X26290Y402554D01*
G01X25340Y402160D02*
Y404173D01*
G01X26290Y402554D02*
Y403690D01*
G01X44953Y424573D02*
X35818Y402519D01*
G01X45759Y424034D02*
X36624Y401980D01*
G01X35818Y402519D02*
X34043Y400744D01*
G01X36624Y401980D02*
X34437Y399794D01*
G01X34043Y400744D02*
X28100D01*
G01X34437Y399794D02*
X27706D01*
G01X28100Y400744D02*
X26290Y402554D01*
G01X27706Y399794D02*
X25340Y402160D01*
G01X26290Y402554D02*
Y403690D01*
G01X25340Y402160D02*
Y404173D01*
G01X4247Y364046D02*
Y362575D01*
G01X3297Y364268D02*
Y362181D01*
G01X4247Y362575D02*
X5028Y361794D01*
G01X3297Y362181D02*
X4634Y360844D01*
G01X5028Y361794D02*
X29350D01*
G01X4634Y360844D02*
X29744D01*
G01X29350Y361794D02*
X36322Y368767D01*
G01X29744Y360844D02*
X37128Y368228D01*
G01X36322Y368767D02*
X40146Y377997D01*
G01X41007Y380076D02*
X41524Y381323D01*
G01X42385Y383402D02*
X42901Y384649D01*
G01X43763Y386728D02*
X44279Y387975D01*
G01X45140Y390054D02*
X45657Y391301D01*
G01X37128Y368228D02*
X46463Y390762D01*
G01X45657Y391301D02*
X48602Y394245D01*
G01X45657Y391301D02*
X48602Y394245D01*
G01X9530Y373580D02*
Y375330D01*
G01X8580Y373580D02*
Y375724D01*
G01X9530Y375330D02*
X10792Y376592D01*
G01X8580Y375724D02*
X10398Y377542D01*
G01X10792Y376592D02*
X30236D01*
G01X10398Y377542D02*
X29842D01*
G01X30236Y376592D02*
X33599Y379955D01*
G01X35191Y381546D02*
X36145Y382500D01*
G01X37736Y384091D02*
X38740Y385095D01*
G01X29842Y377542D02*
X37934Y385634D01*
G01X38740Y385095D02*
X40295Y388848D01*
G01X41156Y390927D02*
X41672Y392174D01*
G01X42534Y394253D02*
X43050Y395500D01*
G01X43911Y397579D02*
X44428Y398826D01*
G01X37934Y385634D02*
X43622Y399365D01*
G01X44428Y398826D02*
X46795Y401195D01*
G01X43622Y399365D02*
X46401Y402145D01*
G01X-6560Y356437D02*
Y354974D01*
G01X-7510Y356331D02*
Y354580D01*
G01X-6560Y354974D02*
X-5206Y353620D01*
G01X-7510Y354580D02*
X-5600Y352670D01*
G01X-5206Y353620D02*
X26504D01*
G01X28754D02*
X30104D01*
G01X32354D02*
X33719D01*
G01X-5600Y352670D02*
X34113D01*
G01X32354Y353620D02*
X33719D01*
G01D02*
X38179Y358080D01*
G01X34113Y352670D02*
X38985Y357541D01*
G01X38179Y358080D02*
X38705Y359348D01*
G01X39566Y361427D02*
X40083Y362674D01*
G01X40944Y364753D02*
X41461Y366000D01*
G01X42322Y368078D02*
X42839Y369325D01*
G01X43700Y371404D02*
X45235Y375107D01*
G01X38985Y357541D02*
X46149Y374830D01*
G01X45235Y375107D02*
X45498Y376431D01*
G01X45937Y378638D02*
X46706Y382506D01*
G01X46149Y374830D02*
X47582Y382038D01*
G01X3297Y364268D02*
Y362181D01*
G01X4247Y364046D02*
Y362575D01*
G01X3297Y362181D02*
X4634Y360844D01*
G01X4247Y362575D02*
X5028Y361794D01*
G01X4634Y360844D02*
X29744D01*
G01X5028Y361794D02*
X29350D01*
G01X29744Y360844D02*
X37128Y368228D01*
G01X29350Y361794D02*
X36322Y368767D01*
G01X37128Y368228D02*
X46463Y390762D01*
G01X36322Y368767D02*
X40146Y377997D01*
G01X37128Y368228D02*
X46463Y390762D01*
G01X41007Y380076D02*
X41524Y381323D01*
G01X37128Y368228D02*
X46463Y390762D01*
G01X42385Y383402D02*
X42901Y384649D01*
G01X37128Y368228D02*
X46463Y390762D01*
G01X43763Y386728D02*
X44279Y387975D01*
G01X37128Y368228D02*
X46463Y390762D01*
G01X45140Y390054D02*
X45657Y391301D01*
G01D02*
X48602Y394245D01*
G01X8580Y373580D02*
Y375724D01*
G01X9530Y373580D02*
Y375330D01*
G01X8580Y375724D02*
X10398Y377542D01*
G01X9530Y375330D02*
X10792Y376592D01*
G01X10398Y377542D02*
X29842D01*
G01X10792Y376592D02*
X30236D01*
G01X29842Y377542D02*
X37934Y385634D01*
G01X30236Y376592D02*
X33599Y379955D01*
G01X29842Y377542D02*
X37934Y385634D01*
G01X35191Y381546D02*
X36145Y382500D01*
G01X29842Y377542D02*
X37934Y385634D01*
G01X37736Y384091D02*
X38740Y385095D01*
G01X37934Y385634D02*
X43622Y399365D01*
G01X38740Y385095D02*
X40295Y388848D01*
G01X37934Y385634D02*
X43622Y399365D01*
G01X41156Y390927D02*
X41672Y392174D01*
G01X37934Y385634D02*
X43622Y399365D01*
G01X42534Y394253D02*
X43050Y395500D01*
G01X37934Y385634D02*
X43622Y399365D01*
G01X43911Y397579D02*
X44428Y398826D01*
G01X43622Y399365D02*
X46401Y402145D01*
G01X44428Y398826D02*
X46795Y401195D01*
G01X-7510Y356331D02*
Y354580D01*
G01X-6560Y356437D02*
Y354974D01*
G01X-7510Y354580D02*
X-5600Y352670D01*
G01X-6560Y354974D02*
X-5206Y353620D01*
G01X-5600Y352670D02*
X34113D01*
G01X-5206Y353620D02*
X26504D01*
G01X-5600Y352670D02*
X34113D01*
G01X28754Y353620D02*
X30104D01*
G01X-5600Y352670D02*
X34113D01*
G01D02*
X38985Y357541D01*
G01X32354Y353620D02*
X33719D01*
G01X34113Y352670D02*
X38985Y357541D01*
G01X33719Y353620D02*
X38179Y358080D01*
G01X38985Y357541D02*
X46149Y374830D01*
G01X38179Y358080D02*
X38705Y359348D01*
G01X38985Y357541D02*
X46149Y374830D01*
G01X39566Y361427D02*
X40083Y362674D01*
G01X38985Y357541D02*
X46149Y374830D01*
G01X40944Y364753D02*
X41461Y366000D01*
G01X38985Y357541D02*
X46149Y374830D01*
G01X42322Y368078D02*
X42839Y369325D01*
G01X38985Y357541D02*
X46149Y374830D01*
G01X43700Y371404D02*
X45235Y375107D01*
G01X46149Y374830D02*
X47582Y382038D01*
G01X45235Y375107D02*
X45498Y376431D01*
G01X46149Y374830D02*
X47582Y382038D01*
G01X45937Y378638D02*
X46706Y382506D01*
G01X48764Y427038D02*
X45759Y424034D01*
G01X48225Y427844D02*
X44953Y424573D01*
G01X48225Y427844D02*
X44953Y424573D01*
G01X48764Y427038D02*
X45759Y424034D01*
G01X38991Y432297D02*
X67743Y444208D01*
G01X68282Y443402D02*
X39530Y431491D01*
G01X34362Y427668D02*
X38991Y432297D01*
G01X39530Y431491D02*
X35168Y427129D01*
G01X31030Y419629D02*
X34362Y427668D01*
G01X35168Y427129D02*
X31774Y418942D01*
G01X23675Y415873D02*
X31030Y419629D01*
G01X31774Y418942D02*
X23904Y414923D01*
G01X19998Y413961D02*
X21910Y415873D01*
G01D02*
X23675D01*
G01X23904Y414923D02*
X22304D01*
G01X19998Y413961D02*
X21910Y415873D01*
G01X22304Y414923D02*
X20948Y413567D01*
G01X19998Y412930D02*
Y413961D01*
G01X20948Y413567D02*
Y412930D01*
G01X61630Y453035D02*
X32691Y441046D01*
G01X61091Y453841D02*
X32152Y441852D01*
G01X32691Y441046D02*
X20104Y428460D01*
G01X32152Y441852D02*
X19710Y429410D01*
G01X20104Y428460D02*
X16340D01*
G01X19710Y429410D02*
X15946D01*
G01X16340Y428460D02*
X15000Y427120D01*
G01X15946Y429410D02*
X14050Y427514D01*
G01X15000Y427120D02*
Y425300D01*
G01X14050Y427514D02*
Y425300D01*
G01X69868Y440937D02*
X46031Y431065D01*
G01X46571Y430259D02*
X42496Y426163D01*
G01X46031Y431065D02*
X41690Y426700D01*
G01X42496Y426163D02*
X37923Y415122D01*
G01X41690Y426700D02*
X37117Y415661D01*
G01X37923Y415122D02*
X30889Y408088D01*
G01X37117Y415661D02*
X30495Y409038D01*
G01X30889Y408088D02*
X11088D01*
G01X30495Y409038D02*
X10694D01*
G01X11088Y408088D02*
X9700Y406700D01*
G01X10694Y409038D02*
X8750Y407094D01*
G01X9700Y406700D02*
Y405110D01*
G01X8750Y407094D02*
Y405240D01*
G01X29619Y445029D02*
X59037Y457216D01*
G01X59576Y456410D02*
X30156Y444222D01*
G01X26919Y442329D02*
X29619Y445029D01*
G01X30156Y444222D02*
X27313Y441379D01*
G01X24897Y442329D02*
X26919D01*
G01X27313Y441379D02*
X24897D01*
G01X47518Y455667D02*
X38578Y451964D01*
G01D02*
X29638Y448260D01*
G01X46979Y456473D02*
X29448Y449210D01*
G01X29638Y448260D02*
X21140D01*
G01X29448Y449210D02*
X20746D01*
G01X21140Y448260D02*
X17340Y444460D01*
G01X20746Y449210D02*
X16946Y445410D01*
G01X17340Y444460D02*
X15349D01*
G01X16946Y445410D02*
X14955D01*
G01X15349Y444460D02*
X13761Y442872D01*
G01X14955Y445410D02*
X12811Y443266D01*
G01X13761Y442872D02*
Y442235D01*
G01X12811Y443266D02*
Y442235D01*
G01X37381Y434753D02*
X66053Y446631D01*
G01X65514Y447437D02*
X36842Y435559D01*
G01X31729Y429101D02*
X37381Y434753D01*
G01X36842Y435559D02*
X30940Y429656D01*
G01X28136Y421492D02*
X31729Y429101D01*
G01X30940Y429656D02*
X27415Y422191D01*
G01X18899Y416773D02*
X28136Y421492D01*
G01X27415Y422191D02*
X18670Y417723D01*
G01X-10264Y416773D02*
X18899D01*
G01X18670Y417723D02*
X-10658D01*
G01X-11620Y415417D02*
X-10264Y416773D01*
G01X-10658Y417723D02*
X-12570Y415811D01*
G01X-11620Y413370D02*
Y415417D01*
G01X-12570Y415811D02*
Y413181D01*
G01X63322Y450647D02*
X34675Y438779D01*
G01X63861Y449841D02*
X35214Y437973D01*
G01X34675Y438779D02*
X27618Y431721D01*
G01X35214Y437973D02*
X28407Y431166D01*
G01X27618Y431721D02*
X24413Y424929D01*
G01X28407Y431166D02*
X25134Y424230D01*
G01X24413Y424929D02*
X17996Y421650D01*
G01X25134Y424230D02*
X18225Y420700D01*
G01X17996Y421650D02*
X6200D01*
G01X18225Y420700D02*
X5806D01*
G01X6200Y421650D02*
X5000Y422850D01*
G01X5806Y420700D02*
X4050Y422456D01*
G01X5000Y422850D02*
Y424400D01*
G01X4050Y422456D02*
Y424400D01*
G01X20948Y413567D02*
Y412930D01*
G01X19998D02*
Y413961D01*
G01X23904Y414923D02*
X22304D01*
G01D02*
X20948Y413567D01*
G01X19998Y413961D02*
X21910Y415873D01*
G01X23904Y414923D02*
X22304D01*
G01X21910Y415873D02*
X23675D01*
G01X31774Y418942D02*
X23904Y414923D01*
G01X23675Y415873D02*
X31030Y419629D01*
G01X35168Y427129D02*
X31774Y418942D01*
G01X31030Y419629D02*
X34362Y427668D01*
G01X39530Y431491D02*
X35168Y427129D01*
G01X34362Y427668D02*
X38991Y432297D01*
G01X68282Y443402D02*
X39530Y431491D01*
G01X38991Y432297D02*
X67743Y444208D01*
G01X61091Y453841D02*
X32152Y441852D01*
G01X61630Y453035D02*
X32691Y441046D01*
G01X32152Y441852D02*
X19710Y429410D01*
G01X32691Y441046D02*
X20104Y428460D01*
G01X19710Y429410D02*
X15946D01*
G01X20104Y428460D02*
X16340D01*
G01X15946Y429410D02*
X14050Y427514D01*
G01X16340Y428460D02*
X15000Y427120D01*
G01X14050Y427514D02*
Y425300D01*
G01X15000Y427120D02*
Y425300D01*
G01X69868Y440937D02*
X46031Y431065D01*
G01D02*
X41690Y426700D01*
G01X46571Y430259D02*
X42496Y426163D01*
G01X41690Y426700D02*
X37117Y415661D01*
G01X42496Y426163D02*
X37923Y415122D01*
G01X37117Y415661D02*
X30495Y409038D01*
G01X37923Y415122D02*
X30889Y408088D01*
G01X30495Y409038D02*
X10694D01*
G01X30889Y408088D02*
X11088D01*
G01X10694Y409038D02*
X8750Y407094D01*
G01X11088Y408088D02*
X9700Y406700D01*
G01X8750Y407094D02*
Y405240D01*
G01X9700Y406700D02*
Y405110D01*
G01X27313Y441379D02*
X24897D01*
G01Y442329D02*
X26919D01*
G01X30156Y444222D02*
X27313Y441379D01*
G01X26919Y442329D02*
X29619Y445029D01*
G01X59576Y456410D02*
X30156Y444222D01*
G01X29619Y445029D02*
X59037Y457216D01*
G01X46979Y456473D02*
X29448Y449210D01*
G01X47518Y455667D02*
X38578Y451964D01*
G01X46979Y456473D02*
X29448Y449210D01*
G01X38578Y451964D02*
X29638Y448260D01*
G01X29448Y449210D02*
X20746D01*
G01X29638Y448260D02*
X21140D01*
G01X20746Y449210D02*
X16946Y445410D01*
G01X21140Y448260D02*
X17340Y444460D01*
G01X16946Y445410D02*
X14955D01*
G01X17340Y444460D02*
X15349D01*
G01X14955Y445410D02*
X12811Y443266D01*
G01X15349Y444460D02*
X13761Y442872D01*
G01X12811Y443266D02*
Y442235D01*
G01X13761Y442872D02*
Y442235D01*
G01X-12570Y415811D02*
Y413181D01*
G01X-11620Y413370D02*
Y415417D01*
G01X-10658Y417723D02*
X-12570Y415811D01*
G01X-11620Y415417D02*
X-10264Y416773D01*
G01X18670Y417723D02*
X-10658D01*
G01X-10264Y416773D02*
X18899D01*
G01X27415Y422191D02*
X18670Y417723D01*
G01X18899Y416773D02*
X28136Y421492D01*
G01X30940Y429656D02*
X27415Y422191D01*
G01X28136Y421492D02*
X31729Y429101D01*
G01X36842Y435559D02*
X30940Y429656D01*
G01X31729Y429101D02*
X37381Y434753D01*
G01X65514Y447437D02*
X36842Y435559D01*
G01X37381Y434753D02*
X66053Y446631D01*
G01X63861Y449841D02*
X35214Y437973D01*
G01X63322Y450647D02*
X34675Y438779D01*
G01X35214Y437973D02*
X28407Y431166D01*
G01X34675Y438779D02*
X27618Y431721D01*
G01X28407Y431166D02*
X25134Y424230D01*
G01X27618Y431721D02*
X24413Y424929D01*
G01X25134Y424230D02*
X18225Y420700D01*
G01X24413Y424929D02*
X17996Y421650D01*
G01X18225Y420700D02*
X5806D01*
G01X17996Y421650D02*
X6200D01*
G01X5806Y420700D02*
X4050Y422456D01*
G01X6200Y421650D02*
X5000Y422850D01*
G01X4050Y422456D02*
Y424400D01*
G01X5000Y422850D02*
Y424400D01*
G01X47518Y455667D02*
X38578Y451964D01*
G01D02*
X29638Y448260D01*
G01X46979Y456473D02*
X29448Y449210D01*
G01X29638Y448260D02*
X21140D01*
G01X29448Y449210D02*
X20746D01*
G01X21140Y448260D02*
X17340Y444460D01*
G01X20746Y449210D02*
X16946Y445410D01*
G01X17340Y444460D02*
X15349D01*
G01X16946Y445410D02*
X14955D01*
G01X15349Y444460D02*
X13761Y442872D01*
G01X14955Y445410D02*
X12811Y443266D01*
G01X13761Y442872D02*
Y442235D01*
G01X12811Y443266D02*
Y442235D01*
G01X46979Y456473D02*
X29448Y449210D01*
G01X47518Y455667D02*
X38578Y451964D01*
G01X46979Y456473D02*
X29448Y449210D01*
G01X38578Y451964D02*
X29638Y448260D01*
G01X29448Y449210D02*
X20746D01*
G01X29638Y448260D02*
X21140D01*
G01X20746Y449210D02*
X16946Y445410D01*
G01X21140Y448260D02*
X17340Y444460D01*
G01X16946Y445410D02*
X14955D01*
G01X17340Y444460D02*
X15349D01*
G01X14955Y445410D02*
X12811Y443266D01*
G01X15349Y444460D02*
X13761Y442872D01*
G01X12811Y443266D02*
Y442235D01*
G01X13761Y442872D02*
Y442235D01*
G01X47435Y93750D02*
X50821D01*
G01X47435D02*
X50821D01*
G01X48030Y151930D02*
X48834Y152734D01*
G01X48424Y150980D02*
X49784Y152340D01*
G01X48834Y152734D02*
Y153906D01*
G01X49784Y152340D02*
Y153484D01*
G01X65123Y149492D02*
Y151023D01*
G01X66073D02*
Y149098D01*
G01X62560Y148940D02*
X64571D01*
G01D02*
X65123Y149492D01*
G01X66073Y149098D02*
X64965Y147990D01*
G01X62560Y148940D02*
X64571D01*
G01X54938D02*
X62560D01*
G01X64965Y147990D02*
X57069D01*
G01X54938Y148940D02*
X62560D01*
G01X57069Y147990D02*
X55332D01*
G01X54123Y148125D02*
X54938Y148940D01*
G01X55332Y147990D02*
X54517Y147175D01*
G01X48424Y150980D02*
X49784Y152340D01*
G01X48030Y151930D02*
X48834Y152734D01*
G01X49784Y152340D02*
Y153484D01*
G01X48834Y152734D02*
Y153906D01*
G01X66073Y149098D02*
X64965Y147990D01*
G01D02*
X57069D01*
G01X62560Y148940D02*
X64571D01*
G01X66073Y149098D02*
X64965Y147990D01*
G01X64571Y148940D02*
X65123Y149492D01*
G01X66073Y151023D02*
Y149098D01*
G01X65123Y149492D02*
Y151023D01*
G01X55332Y147990D02*
X54517Y147175D01*
G01X54123Y148125D02*
X54938Y148940D01*
G01X64965Y147990D02*
X57069D01*
G01D02*
X55332D01*
G01X54938Y148940D02*
X62560D01*
G01X65123Y149492D02*
Y151023D01*
G01X66073D02*
Y149098D01*
G01X62560Y148940D02*
X64571D01*
G01D02*
X65123Y149492D01*
G01X66073Y149098D02*
X64965Y147990D01*
G01X62560Y148940D02*
X64571D01*
G01X54938D02*
X62560D01*
G01X64965Y147990D02*
X57069D01*
G01X54938Y148940D02*
X62560D01*
G01X57069Y147990D02*
X55332D01*
G01X54123Y148125D02*
X54938Y148940D01*
G01X55332Y147990D02*
X54517Y147175D01*
G01X66073Y149098D02*
X64965Y147990D01*
G01D02*
X57069D01*
G01X62560Y148940D02*
X64571D01*
G01X66073Y149098D02*
X64965Y147990D01*
G01X64571Y148940D02*
X65123Y149492D01*
G01X66073Y151023D02*
Y149098D01*
G01X65123Y149492D02*
Y151023D01*
G01X55332Y147990D02*
X54517Y147175D01*
G01X54123Y148125D02*
X54938Y148940D01*
G01X64965Y147990D02*
X57069D01*
G01D02*
X55332D01*
G01X54938Y148940D02*
X62560D01*
G01X46463Y390762D02*
X48996Y393295D01*
G01X48602Y394245D02*
X50355D01*
G01X48996Y393295D02*
X50355D01*
G01X46795Y401195D02*
X47555D01*
G01X46401Y402145D02*
X47555D01*
G01X46706Y382506D02*
X48772Y384572D01*
G01X47582Y382038D02*
X49163Y383619D01*
G01X48772Y384572D02*
X50356Y384562D01*
G01X49163Y383619D02*
X50351Y383612D01*
G01X48772Y384572D02*
X50356Y384562D01*
G01X50351Y383612D02*
X50354D01*
G01X46463Y390762D02*
X48996Y393295D01*
G01D02*
X50355D01*
G01X48996D02*
X50355D01*
G01X48602Y394245D02*
X50355D01*
G01X46401Y402145D02*
X47555D01*
G01X46795Y401195D02*
X47555D01*
G01X47582Y382038D02*
X49163Y383619D01*
G01X46706Y382506D02*
X48772Y384572D01*
G01X49163Y383619D02*
X50351Y383612D01*
G01D02*
X50354D01*
G01X48772Y384572D02*
X50356Y384562D01*
G01X87016Y408117D02*
X80201Y401300D01*
G01X87822Y407578D02*
X80595Y400350D01*
G01X80201Y401300D02*
X75856D01*
G01X80595Y400350D02*
X76250D01*
G01X75856Y401300D02*
X74886Y400330D01*
G01X76250Y400350D02*
X75280Y399380D01*
G01X74886Y400330D02*
X63086D01*
G01X75280Y399380D02*
X63480D01*
G01X63086Y400330D02*
X61050Y398294D01*
G01X63480Y399380D02*
X62000Y397900D01*
G01X61050Y398294D02*
Y396094D01*
G01X62000Y397900D02*
Y395700D01*
G01X61050Y396094D02*
X59379Y394423D01*
G01X62000Y395700D02*
X59773Y393473D01*
G01X59379Y394423D02*
X56227D01*
G01X59773Y393473D02*
X56583D01*
G01X53295Y400885D02*
X56429D01*
G01X53915Y401835D02*
X56035D01*
G01X56429Y400885D02*
X59651Y404107D01*
G01X56035Y401835D02*
X58845Y404646D01*
G01X96111Y409933D02*
X91148Y397948D01*
G01X96917Y409394D02*
X91954Y397409D01*
G01X91148Y397948D02*
X81251Y388050D01*
G01X91954Y397409D02*
X84522Y389977D01*
G01X91148Y397948D02*
X81251Y388050D01*
G01X84522Y389977D02*
X81645Y387100D01*
G01X66178Y388050D02*
X69500D01*
G01X81251D02*
X69500D01*
G01X81645Y387100D02*
X66367D01*
G01X57791Y384577D02*
X66178Y388050D01*
G01X66367Y387100D02*
X58156Y383699D01*
G01X56373Y384577D02*
X57791D01*
G01X58084Y383627D02*
X56397D01*
G01X96111Y409933D02*
X91148Y397948D01*
G01X96917Y409394D02*
X91954Y397409D01*
G01X91148Y397948D02*
X81251Y388050D01*
G01X91954Y397409D02*
X84522Y389977D01*
G01X91148Y397948D02*
X81251Y388050D01*
G01X84522Y389977D02*
X81645Y387100D01*
G01X66178Y388050D02*
X69500D01*
G01X81251D02*
X69500D01*
G01X81645Y387100D02*
X66367D01*
G01X57791Y384577D02*
X66178Y388050D01*
G01X66367Y387100D02*
X58156Y383699D01*
G01X56373Y384577D02*
X57791D01*
G01X58084Y383627D02*
X56397D01*
G01X74935Y394875D02*
X81974D01*
G01X75075Y393925D02*
X82368D01*
G01X81974Y394875D02*
X88272Y401173D01*
G01X82368Y393925D02*
X89079Y400636D01*
G01X88273Y401175D02*
X92754Y411996D01*
G01X89079Y400636D02*
X93560Y411457D01*
G01X87822Y407578D02*
X80595Y400350D01*
G01X87016Y408117D02*
X80201Y401300D01*
G01X80595Y400350D02*
X76250D01*
G01X80201Y401300D02*
X75856D01*
G01X76250Y400350D02*
X75280Y399380D01*
G01X75856Y401300D02*
X74886Y400330D01*
G01X75280Y399380D02*
X63480D01*
G01X74886Y400330D02*
X63086D01*
G01X63480Y399380D02*
X62000Y397900D01*
G01X63086Y400330D02*
X61050Y398294D01*
G01X62000Y397900D02*
Y395700D01*
G01X61050Y398294D02*
Y396094D01*
G01X62000Y395700D02*
X59773Y393473D01*
G01X61050Y396094D02*
X59379Y394423D01*
G01X59773Y393473D02*
X56583D01*
G01X59379Y394423D02*
X56227D01*
G01X53915Y401835D02*
X56035D01*
G01X53295Y400885D02*
X56429D01*
G01X56035Y401835D02*
X58845Y404646D01*
G01X56429Y400885D02*
X59651Y404107D01*
G01X58084Y383627D02*
X56397D01*
G01X56373Y384577D02*
X57791D01*
G01X66367Y387100D02*
X58156Y383699D01*
G01X57791Y384577D02*
X66178Y388050D01*
G01X81645Y387100D02*
X66367D01*
G01X66178Y388050D02*
X69500D01*
G01X96917Y409394D02*
X91954Y397409D01*
G01X96111Y409933D02*
X91148Y397948D01*
G01X91954Y397409D02*
X84522Y389977D01*
G01D02*
X81645Y387100D01*
G01X91148Y397948D02*
X81251Y388050D01*
G01X81645Y387100D02*
X66367D01*
G01X81251Y388050D02*
X69500D01*
G01X58084Y383627D02*
X56397D01*
G01X56373Y384577D02*
X57791D01*
G01X66367Y387100D02*
X58156Y383699D01*
G01X57791Y384577D02*
X66178Y388050D01*
G01X81645Y387100D02*
X66367D01*
G01X66178Y388050D02*
X69500D01*
G01X96917Y409394D02*
X91954Y397409D01*
G01X96111Y409933D02*
X91148Y397948D01*
G01X91954Y397409D02*
X84522Y389977D01*
G01D02*
X81645Y387100D01*
G01X91148Y397948D02*
X81251Y388050D01*
G01X81645Y387100D02*
X66367D01*
G01X81251Y388050D02*
X69500D01*
G01X75075Y393925D02*
X82368D01*
G01X74935Y394875D02*
X81974D01*
G01X82368Y393925D02*
X89079Y400636D01*
G01X81974Y394875D02*
X88272Y401173D01*
G01X89079Y400636D02*
X93560Y411457D01*
G01X88273Y401175D02*
X92754Y411996D01*
G01X68822Y394672D02*
X66698D01*
G01X69088Y393722D02*
X66522D01*
G01X69088D02*
X66522D01*
G01X68822Y394672D02*
X66698D01*
G01X87016Y408117D02*
X80201Y401300D01*
G01X87822Y407578D02*
X80595Y400350D01*
G01X80201Y401300D02*
X75856D01*
G01X80595Y400350D02*
X76250D01*
G01X75856Y401300D02*
X74886Y400330D01*
G01X76250Y400350D02*
X75280Y399380D01*
G01X74886Y400330D02*
X63086D01*
G01X75280Y399380D02*
X63480D01*
G01X63086Y400330D02*
X61050Y398294D01*
G01X63480Y399380D02*
X62000Y397900D01*
G01X61050Y398294D02*
Y396094D01*
G01X62000Y397900D02*
Y395700D01*
G01X61050Y396094D02*
X59379Y394423D01*
G01X62000Y395700D02*
X59773Y393473D01*
G01X59379Y394423D02*
X56227D01*
G01X59773Y393473D02*
X56583D01*
G01X53295Y400885D02*
X56429D01*
G01X53915Y401835D02*
X56035D01*
G01X56429Y400885D02*
X59651Y404107D01*
G01X56035Y401835D02*
X58845Y404646D01*
G01X87822Y407578D02*
X80595Y400350D01*
G01X87016Y408117D02*
X80201Y401300D01*
G01X80595Y400350D02*
X76250D01*
G01X80201Y401300D02*
X75856D01*
G01X76250Y400350D02*
X75280Y399380D01*
G01X75856Y401300D02*
X74886Y400330D01*
G01X75280Y399380D02*
X63480D01*
G01X74886Y400330D02*
X63086D01*
G01X63480Y399380D02*
X62000Y397900D01*
G01X63086Y400330D02*
X61050Y398294D01*
G01X62000Y397900D02*
Y395700D01*
G01X61050Y398294D02*
Y396094D01*
G01X62000Y395700D02*
X59773Y393473D01*
G01X61050Y396094D02*
X59379Y394423D01*
G01X59773Y393473D02*
X56583D01*
G01X59379Y394423D02*
X56227D01*
G01X53915Y401835D02*
X56035D01*
G01X53295Y400885D02*
X56429D01*
G01X56035Y401835D02*
X58845Y404646D01*
G01X56429Y400885D02*
X59651Y404107D01*
G01X74935Y394875D02*
X81974D01*
G01X75075Y393925D02*
X82368D01*
G01X81974Y394875D02*
X88272Y401173D01*
G01X82368Y393925D02*
X89079Y400636D01*
G01X88273Y401175D02*
X92754Y411996D01*
G01X89079Y400636D02*
X93560Y411457D01*
G01X75075Y393925D02*
X82368D01*
G01X74935Y394875D02*
X81974D01*
G01X82368Y393925D02*
X89079Y400636D01*
G01X81974Y394875D02*
X88272Y401173D01*
G01X89079Y400636D02*
X93560Y411457D01*
G01X88273Y401175D02*
X92754Y411996D01*
G01X119826Y465929D02*
X91618Y455832D01*
G01X119661Y466879D02*
X91097Y456656D01*
G01X91618Y455832D02*
X72666Y436936D01*
G01X91097Y456656D02*
X72128Y437743D01*
G01X72666Y436936D02*
X48764Y427038D01*
G01X72128Y437743D02*
X48225Y427844D01*
G01X119661Y466879D02*
X91097Y456656D01*
G01X119826Y465929D02*
X91618Y455832D01*
G01X91097Y456656D02*
X72128Y437743D01*
G01X91618Y455832D02*
X72666Y436936D01*
G01X72128Y437743D02*
X48225Y427844D01*
G01X72666Y436936D02*
X48764Y427038D01*
G01X86863Y463330D02*
X120597Y475400D01*
G01X120762Y474450D02*
X87384Y462507D01*
G01X67743Y444208D02*
X86863Y463330D01*
G01X87384Y462507D02*
X68282Y443402D01*
G01X81052Y472457D02*
X61630Y453035D01*
G01X80529Y473278D02*
X61091Y453841D01*
G01X120472Y470200D02*
X89328Y459054D01*
G01X120307Y471150D02*
X88807Y459877D01*
G01X89328Y459054D02*
X70407Y440131D01*
G01X88807Y459877D02*
X69868Y440937D01*
G01X70407Y440131D02*
X46571Y430259D01*
G01X59037Y457216D02*
X81865Y480044D01*
G01X82404Y479238D02*
X59576Y456410D01*
G01X56000Y470700D02*
Y464150D01*
G01X55050Y471094D02*
Y464544D01*
G01X56000Y464150D02*
X53779Y461928D01*
G01D02*
X47518Y455667D01*
G01X55050Y464544D02*
X46979Y456473D01*
G01X66053Y446631D02*
X85210Y465789D01*
G01X84689Y466612D02*
X65514Y447437D01*
G01X82675Y470000D02*
X63322Y450647D01*
G01X83196Y469177D02*
X63861Y449841D01*
G01X87384Y462507D02*
X68282Y443402D01*
G01X67743Y444208D02*
X86863Y463330D01*
G01X120762Y474450D02*
X87384Y462507D01*
G01X86863Y463330D02*
X120597Y475400D01*
G01X80529Y473278D02*
X61091Y453841D01*
G01X81052Y472457D02*
X61630Y453035D01*
G01X120307Y471150D02*
X88807Y459877D01*
G01X120472Y470200D02*
X89328Y459054D01*
G01X88807Y459877D02*
X69868Y440937D01*
G01X89328Y459054D02*
X70407Y440131D01*
G01D02*
X46571Y430259D01*
G01X82404Y479238D02*
X59576Y456410D01*
G01X59037Y457216D02*
X81865Y480044D01*
G01X55050Y471094D02*
Y464544D01*
G01X56000Y470700D02*
Y464150D01*
G01X55050Y464544D02*
X46979Y456473D01*
G01X56000Y464150D02*
X53779Y461928D01*
G01X55050Y464544D02*
X46979Y456473D01*
G01X53779Y461928D02*
X47518Y455667D01*
G01X84689Y466612D02*
X65514Y447437D01*
G01X66053Y446631D02*
X85210Y465789D01*
G01X83196Y469177D02*
X63861Y449841D01*
G01X82675Y470000D02*
X63322Y450647D01*
G01X103799Y431342D02*
X106503Y434045D01*
G01X103799Y431342D02*
X95752Y423298D01*
G01X100287Y426488D02*
X106974Y433172D01*
G01X106503Y434045D02*
X116887Y436200D01*
G01X106974Y433172D02*
X117318Y435319D01*
G01X103799Y431342D02*
X95752Y423298D01*
G01X100287Y426488D02*
X96702Y422904D01*
G01X95752Y423298D02*
Y420375D01*
G01X96702Y422904D02*
Y419981D01*
G01X95752Y420375D02*
X89509Y414133D01*
G01X96702Y419981D02*
X90315Y413594D01*
G01X89509Y414133D02*
X87016Y408117D01*
G01X90315Y413594D02*
X87822Y407578D01*
G01X103220Y440421D02*
X112655Y442254D01*
G01X112285Y443150D02*
X102750Y441298D01*
G01X91900Y429101D02*
X103220Y440421D01*
G01X102750Y441298D02*
X99831Y438379D01*
G01X91900Y429101D02*
X103220Y440421D01*
G01X99831Y438378D02*
X97916Y436463D01*
G01X59651Y404107D02*
X61353Y408218D01*
G01X58845Y404646D02*
X60487Y408613D01*
G01X61353Y408218D02*
X61698Y408909D01*
G01X60487Y408613D02*
X60917Y409472D01*
G01X61698Y408909D02*
X62728Y409937D01*
G01X60917Y409472D02*
X62189Y410742D01*
G01X62728Y409937D02*
X63190Y410130D01*
G01D02*
X75774D01*
G01X62189Y410742D02*
X62999Y411080D01*
G01X63190Y410130D02*
X75774D01*
G01X62999Y411080D02*
X64580D01*
G01X63190Y410130D02*
X75774D01*
G01X66830Y411080D02*
X68180D01*
G01X63190Y410130D02*
X75774D01*
G01X70430Y411080D02*
X71780D01*
G01X63190Y410130D02*
X75774D01*
G01D02*
X88959Y423315D01*
G01X74030Y411080D02*
X75380D01*
G01X75774Y410130D02*
X88959Y423315D01*
G01X75380Y411080D02*
X88009Y423709D01*
G01X88959Y423315D02*
Y426160D01*
G01X88009Y423709D02*
Y426554D01*
G01X91900Y429101D02*
X103220Y440421D01*
G01X88959Y426160D02*
X91900Y429101D01*
G01X88009Y426554D02*
X97916Y436463D01*
G01X110297Y426941D02*
X103808Y420452D01*
G01X110768Y426068D02*
X104758Y420058D01*
G01X103808Y420452D02*
Y417629D01*
G01X104758Y420058D02*
Y417235D01*
G01X103808Y417629D02*
X96111Y409933D01*
G01X104758Y417235D02*
X96917Y409394D01*
G01X110297Y426941D02*
X103808Y420452D01*
G01X110768Y426068D02*
X104758Y420058D01*
G01X103808Y420452D02*
Y417629D01*
G01X104758Y420058D02*
Y417235D01*
G01X103808Y417629D02*
X96111Y409933D01*
G01X104758Y417235D02*
X96917Y409394D01*
G01X92754Y411996D02*
X98521Y417762D01*
G01X93560Y411457D02*
X99193Y417090D01*
G01X98521Y417763D02*
X99984Y419226D01*
G01X99193Y417091D02*
X100934Y418832D01*
G01X99984Y419226D02*
Y422029D01*
G01X100934Y418832D02*
Y421635D01*
G01X99984Y422029D02*
X108387Y430430D01*
G01X100934Y421635D02*
X108858Y429557D01*
G01X100287Y426488D02*
X106974Y433172D01*
G01X103799Y431342D02*
X106503Y434045D01*
G01X106974Y433172D02*
X117318Y435319D01*
G01X106503Y434045D02*
X116887Y436200D01*
G01X100287Y426488D02*
X106974Y433172D01*
G01X100287Y426488D02*
X96702Y422904D01*
G01X103799Y431342D02*
X95752Y423298D01*
G01X96702Y422904D02*
Y419981D01*
G01X95752Y423298D02*
Y420375D01*
G01X96702Y419981D02*
X90315Y413594D01*
G01X95752Y420375D02*
X89509Y414133D01*
G01X90315Y413594D02*
X87822Y407578D01*
G01X89509Y414133D02*
X87016Y408117D01*
G01X102750Y441298D02*
X99831Y438379D01*
G01Y438378D02*
X97916Y436463D01*
G01X88009Y426554D02*
X97916Y436463D01*
G01X91900Y429101D02*
X103220Y440421D01*
G01X112285Y443150D02*
X102750Y441298D01*
G01X103220Y440421D02*
X112655Y442254D01*
G01X58845Y404646D02*
X60487Y408613D01*
G01X59651Y404107D02*
X61353Y408218D01*
G01X60487Y408613D02*
X60917Y409472D01*
G01X61353Y408218D02*
X61698Y408909D01*
G01X60917Y409472D02*
X62189Y410742D01*
G01X61698Y408909D02*
X62728Y409937D01*
G01X62189Y410742D02*
X62999Y411080D01*
G01X62728Y409937D02*
X63190Y410130D01*
G01X62189Y410742D02*
X62999Y411080D01*
G01D02*
X64580D01*
G01X66830D02*
X68180D01*
G01X70430D02*
X71780D01*
G01X74030D02*
X75380D01*
G01X63190Y410130D02*
X75774D01*
G01X74030Y411080D02*
X75380D01*
G01D02*
X88009Y423709D01*
G01X75774Y410130D02*
X88959Y423315D01*
G01X88009Y423709D02*
Y426554D01*
G01X88959Y423315D02*
Y426160D01*
G01X88009Y426554D02*
X97916Y436463D01*
G01X88959Y426160D02*
X91900Y429101D01*
G01X110768Y426068D02*
X104758Y420058D01*
G01X110297Y426941D02*
X103808Y420452D01*
G01X104758Y420058D02*
Y417235D01*
G01X103808Y420452D02*
Y417629D01*
G01X104758Y417235D02*
X96917Y409394D01*
G01X103808Y417629D02*
X96111Y409933D01*
G01X110768Y426068D02*
X104758Y420058D01*
G01X110297Y426941D02*
X103808Y420452D01*
G01X104758Y420058D02*
Y417235D01*
G01X103808Y420452D02*
Y417629D01*
G01X104758Y417235D02*
X96917Y409394D01*
G01X103808Y417629D02*
X96111Y409933D01*
G01X93560Y411457D02*
X99193Y417090D01*
G01X92754Y411996D02*
X98521Y417762D01*
G01X99193Y417091D02*
X100934Y418832D01*
G01X98521Y417763D02*
X99984Y419226D01*
G01X100934Y418832D02*
Y421635D01*
G01X99984Y419226D02*
Y422029D01*
G01X100934Y421635D02*
X108858Y429557D01*
G01X99984Y422029D02*
X108387Y430430D01*
G01X70750Y427050D02*
X71256D01*
G01X70850Y426100D02*
X71650D01*
G01X71256Y427050D02*
X72072Y427866D01*
G01X71650Y426100D02*
X73022Y427472D01*
G01X72072Y427866D02*
Y431462D01*
G01X73022Y427472D02*
Y431068D01*
G01X72072Y431462D02*
X90791Y450181D01*
G01X73022Y431068D02*
X91330Y449375D01*
G01X90791Y450181D02*
X120047Y462300D01*
G01X91330Y449375D02*
X120236Y461350D01*
G01X59190Y420870D02*
X70073D01*
G01X59340Y421820D02*
X69883D01*
G01X70073Y420870D02*
X74033Y422511D01*
G01X69883Y421820D02*
X73494Y423317D01*
G01X74033Y422511D02*
X77950Y426429D01*
G01X73494Y423317D02*
X77000Y426823D01*
G01X77950Y426429D02*
Y430599D01*
G01X77000Y426823D02*
Y430994D01*
G01X77950Y430599D02*
X81387Y434036D01*
G01D02*
X93494Y446145D01*
G01X77000Y430994D02*
X90811Y444806D01*
G01X93494Y446145D02*
X120785Y457450D01*
G01X120596Y458400D02*
X92955Y446951D01*
G01X81387Y434036D02*
X93494Y446145D01*
G01X92955Y446951D02*
X90811Y444806D01*
G01X59190Y420870D02*
X70073D01*
G01X59340Y421820D02*
X69883D01*
G01X70073Y420870D02*
X74033Y422511D01*
G01X69883Y421820D02*
X73494Y423317D01*
G01X74033Y422511D02*
X77950Y426429D01*
G01X73494Y423317D02*
X77000Y426823D01*
G01X77950Y426429D02*
Y430599D01*
G01X77000Y426823D02*
Y430994D01*
G01X77950Y430599D02*
X81387Y434036D01*
G01D02*
X93494Y446145D01*
G01X77000Y430994D02*
X90811Y444806D01*
G01X93494Y446145D02*
X120785Y457450D01*
G01X120596Y458400D02*
X92955Y446951D01*
G01X81387Y434036D02*
X93494Y446145D01*
G01X92955Y446951D02*
X90811Y444806D01*
G01X103799Y431342D02*
X106503Y434045D01*
G01X103799Y431342D02*
X95752Y423298D01*
G01X100287Y426488D02*
X106974Y433172D01*
G01X106503Y434045D02*
X116887Y436200D01*
G01X106974Y433172D02*
X117318Y435319D01*
G01X103799Y431342D02*
X95752Y423298D01*
G01X100287Y426488D02*
X96702Y422904D01*
G01X95752Y423298D02*
Y420375D01*
G01X96702Y422904D02*
Y419981D01*
G01X95752Y420375D02*
X89509Y414133D01*
G01X96702Y419981D02*
X90315Y413594D01*
G01X89509Y414133D02*
X87016Y408117D01*
G01X90315Y413594D02*
X87822Y407578D01*
G01X74833Y416577D02*
X75471D01*
G01X75177Y415627D02*
X75865D01*
G01X74833Y416577D02*
X75471D01*
G01D02*
X84105Y425211D01*
G01X75865Y415627D02*
X85055Y424817D01*
G01X84105Y425211D02*
Y428070D01*
G01X85055Y424817D02*
Y427676D01*
G01X84105Y428070D02*
X102033Y445999D01*
G01X85055Y427676D02*
X102572Y445193D01*
G01X102033Y445999D02*
X122316Y454400D01*
G01X102572Y445193D02*
X122505Y453450D01*
G01X103220Y440421D02*
X112655Y442254D01*
G01X112285Y443150D02*
X102750Y441298D01*
G01X91900Y429101D02*
X103220Y440421D01*
G01X102750Y441298D02*
X99831Y438379D01*
G01X91900Y429101D02*
X103220Y440421D01*
G01X99831Y438378D02*
X97916Y436463D01*
G01X59651Y404107D02*
X61353Y408218D01*
G01X58845Y404646D02*
X60487Y408613D01*
G01X61353Y408218D02*
X61698Y408909D01*
G01X60487Y408613D02*
X60917Y409472D01*
G01X61698Y408909D02*
X62728Y409937D01*
G01X60917Y409472D02*
X62189Y410742D01*
G01X62728Y409937D02*
X63190Y410130D01*
G01D02*
X75774D01*
G01X62189Y410742D02*
X62999Y411080D01*
G01X63190Y410130D02*
X75774D01*
G01X62999Y411080D02*
X64580D01*
G01X63190Y410130D02*
X75774D01*
G01X66830Y411080D02*
X68180D01*
G01X63190Y410130D02*
X75774D01*
G01X70430Y411080D02*
X71780D01*
G01X63190Y410130D02*
X75774D01*
G01D02*
X88959Y423315D01*
G01X74030Y411080D02*
X75380D01*
G01X75774Y410130D02*
X88959Y423315D01*
G01X75380Y411080D02*
X88009Y423709D01*
G01X88959Y423315D02*
Y426160D01*
G01X88009Y423709D02*
Y426554D01*
G01X91900Y429101D02*
X103220Y440421D01*
G01X88959Y426160D02*
X91900Y429101D01*
G01X88009Y426554D02*
X97916Y436463D01*
G01X75138Y405472D02*
X78973D01*
G01X74872Y404522D02*
X79367D01*
G01X78973Y405472D02*
X83695Y410200D01*
G01X79367Y404522D02*
X82048Y407205D01*
G01X78973Y405472D02*
X83695Y410200D01*
G01X82048Y407205D02*
X82464Y407622D01*
G01X78973Y405472D02*
X83695Y410200D01*
G01X82464Y407622D02*
X84501Y409662D01*
G01X83695Y410200D02*
X86241Y416344D01*
G01X84501Y409662D02*
X87047Y415805D01*
G01X86241Y416344D02*
X91889Y421991D01*
G01X87047Y415805D02*
X92839Y421597D01*
G01X91889Y421991D02*
Y424836D01*
G01X92839Y421597D02*
Y424442D01*
G01X91889Y424836D02*
X104654Y437596D01*
G01X92839Y424442D02*
X105125Y436723D01*
G01X104654Y437596D02*
X114005Y439537D01*
G01X105125Y436723D02*
X114379Y438644D01*
G01X75138Y405472D02*
X78973D01*
G01X74872Y404522D02*
X79367D01*
G01X78973Y405472D02*
X83695Y410200D01*
G01X79367Y404522D02*
X82048Y407205D01*
G01X78973Y405472D02*
X83695Y410200D01*
G01X82048Y407205D02*
X82464Y407622D01*
G01X78973Y405472D02*
X83695Y410200D01*
G01X82464Y407622D02*
X84501Y409662D01*
G01X83695Y410200D02*
X86241Y416344D01*
G01X84501Y409662D02*
X87047Y415805D01*
G01X86241Y416344D02*
X91889Y421991D01*
G01X87047Y415805D02*
X92839Y421597D01*
G01X91889Y421991D02*
Y424836D01*
G01X92839Y421597D02*
Y424442D01*
G01X91889Y424836D02*
X104654Y437596D01*
G01X92839Y424442D02*
X105125Y436723D01*
G01X104654Y437596D02*
X114005Y439537D01*
G01X105125Y436723D02*
X114379Y438644D01*
G01X70850Y426100D02*
X71650D01*
G01X70750Y427050D02*
X71256D01*
G01X71650Y426100D02*
X73022Y427472D01*
G01X71256Y427050D02*
X72072Y427866D01*
G01X73022Y427472D02*
Y431068D01*
G01X72072Y427866D02*
Y431462D01*
G01X73022Y431068D02*
X91330Y449375D01*
G01X72072Y431462D02*
X90791Y450181D01*
G01X91330Y449375D02*
X120236Y461350D01*
G01X90791Y450181D02*
X120047Y462300D01*
G01X59340Y421820D02*
X69883D01*
G01X59190Y420870D02*
X70073D01*
G01X69883Y421820D02*
X73494Y423317D01*
G01X70073Y420870D02*
X74033Y422511D01*
G01X73494Y423317D02*
X77000Y426823D01*
G01X74033Y422511D02*
X77950Y426429D01*
G01X77000Y426823D02*
Y430994D01*
G01X77950Y426429D02*
Y430599D01*
G01X77000Y430994D02*
X90811Y444806D01*
G01X77950Y430599D02*
X81387Y434036D01*
G01X77000Y430994D02*
X90811Y444806D01*
G01X92955Y446951D02*
X90811Y444806D01*
G01X81387Y434036D02*
X93494Y446145D01*
G01X120596Y458400D02*
X92955Y446951D01*
G01X93494Y446145D02*
X120785Y457450D01*
G01X59340Y421820D02*
X69883D01*
G01X59190Y420870D02*
X70073D01*
G01X69883Y421820D02*
X73494Y423317D01*
G01X70073Y420870D02*
X74033Y422511D01*
G01X73494Y423317D02*
X77000Y426823D01*
G01X74033Y422511D02*
X77950Y426429D01*
G01X77000Y426823D02*
Y430994D01*
G01X77950Y426429D02*
Y430599D01*
G01X77000Y430994D02*
X90811Y444806D01*
G01X77950Y430599D02*
X81387Y434036D01*
G01X77000Y430994D02*
X90811Y444806D01*
G01X92955Y446951D02*
X90811Y444806D01*
G01X81387Y434036D02*
X93494Y446145D01*
G01X120596Y458400D02*
X92955Y446951D01*
G01X93494Y446145D02*
X120785Y457450D01*
G01X100287Y426488D02*
X106974Y433172D01*
G01X103799Y431342D02*
X106503Y434045D01*
G01X106974Y433172D02*
X117318Y435319D01*
G01X106503Y434045D02*
X116887Y436200D01*
G01X100287Y426488D02*
X106974Y433172D01*
G01X100287Y426488D02*
X96702Y422904D01*
G01X103799Y431342D02*
X95752Y423298D01*
G01X96702Y422904D02*
Y419981D01*
G01X95752Y423298D02*
Y420375D01*
G01X96702Y419981D02*
X90315Y413594D01*
G01X95752Y420375D02*
X89509Y414133D01*
G01X90315Y413594D02*
X87822Y407578D01*
G01X89509Y414133D02*
X87016Y408117D01*
G01X75177Y415627D02*
X75865D01*
G01D02*
X85055Y424817D01*
G01X74833Y416577D02*
X75471D01*
G01X75865Y415627D02*
X85055Y424817D01*
G01X75471Y416577D02*
X84105Y425211D01*
G01X85055Y424817D02*
Y427676D01*
G01X84105Y425211D02*
Y428070D01*
G01X85055Y427676D02*
X102572Y445193D01*
G01X84105Y428070D02*
X102033Y445999D01*
G01X102572Y445193D02*
X122505Y453450D01*
G01X102033Y445999D02*
X122316Y454400D01*
G01X102750Y441298D02*
X99831Y438379D01*
G01Y438378D02*
X97916Y436463D01*
G01X88009Y426554D02*
X97916Y436463D01*
G01X91900Y429101D02*
X103220Y440421D01*
G01X112285Y443150D02*
X102750Y441298D01*
G01X103220Y440421D02*
X112655Y442254D01*
G01X58845Y404646D02*
X60487Y408613D01*
G01X59651Y404107D02*
X61353Y408218D01*
G01X60487Y408613D02*
X60917Y409472D01*
G01X61353Y408218D02*
X61698Y408909D01*
G01X60917Y409472D02*
X62189Y410742D01*
G01X61698Y408909D02*
X62728Y409937D01*
G01X62189Y410742D02*
X62999Y411080D01*
G01X62728Y409937D02*
X63190Y410130D01*
G01X62189Y410742D02*
X62999Y411080D01*
G01D02*
X64580D01*
G01X66830D02*
X68180D01*
G01X70430D02*
X71780D01*
G01X74030D02*
X75380D01*
G01X63190Y410130D02*
X75774D01*
G01X74030Y411080D02*
X75380D01*
G01D02*
X88009Y423709D01*
G01X75774Y410130D02*
X88959Y423315D01*
G01X88009Y423709D02*
Y426554D01*
G01X88959Y423315D02*
Y426160D01*
G01X88009Y426554D02*
X97916Y436463D01*
G01X88959Y426160D02*
X91900Y429101D01*
G01X74872Y404522D02*
X79367D01*
G01X75138Y405472D02*
X78973D01*
G01X79367Y404522D02*
X82048Y407205D01*
G01D02*
X82464Y407622D01*
G01D02*
X84501Y409662D01*
G01X78973Y405472D02*
X83695Y410200D01*
G01X84501Y409662D02*
X87047Y415805D01*
G01X83695Y410200D02*
X86241Y416344D01*
G01X87047Y415805D02*
X92839Y421597D01*
G01X86241Y416344D02*
X91889Y421991D01*
G01X92839Y421597D02*
Y424442D01*
G01X91889Y421991D02*
Y424836D01*
G01X92839Y424442D02*
X105125Y436723D01*
G01X91889Y424836D02*
X104654Y437596D01*
G01X105125Y436723D02*
X114379Y438644D01*
G01X104654Y437596D02*
X114005Y439537D01*
G01X64880Y426330D02*
X61930D01*
G01X65030Y427280D02*
X61920D01*
G01X50120Y421020D02*
X53140D01*
G01X50030Y421970D02*
X53290D01*
G01X69765Y415455D02*
X66900D01*
G01X68955Y416405D02*
X66809D01*
G01X64920Y415455D02*
X63920D01*
G01X61940D02*
X60279D01*
G01D02*
X58859D01*
G01X66809Y416405D02*
X58465D01*
G01X58859Y415455D02*
X58152Y414748D01*
G01X56751Y413347D02*
X56044Y412640D01*
G01X54643Y411239D02*
X53760Y410356D01*
G01X58465Y416405D02*
X52810Y410750D01*
G01X53760Y410356D02*
Y408804D01*
G01X52810Y410750D02*
Y408410D01*
G01X53760Y408804D02*
X54924Y407640D01*
G01D02*
X55860D01*
G01X52810Y408410D02*
X54244Y406976D01*
G01X69765Y415455D02*
X66900D01*
G01X68955Y416405D02*
X66809D01*
G01X64920Y415455D02*
X63920D01*
G01X61940D02*
X60279D01*
G01D02*
X58859D01*
G01X66809Y416405D02*
X58465D01*
G01X58859Y415455D02*
X58152Y414748D01*
G01X56751Y413347D02*
X56044Y412640D01*
G01X54643Y411239D02*
X53760Y410356D01*
G01X58465Y416405D02*
X52810Y410750D01*
G01X53760Y410356D02*
Y408804D01*
G01X52810Y410750D02*
Y408410D01*
G01X53760Y408804D02*
X54924Y407640D01*
G01D02*
X55860D01*
G01X52810Y408410D02*
X54244Y406976D01*
G01X65384Y404983D02*
X65809Y405408D01*
G01D02*
X67749D01*
G01X64693Y405636D02*
X65415Y406358D01*
G01X65809Y405408D02*
X67749D01*
G01X65415Y406358D02*
X68143D01*
G01X65809Y405408D02*
X67749D01*
G01D02*
X68026Y405131D01*
G01X68143Y406358D02*
X68420Y406081D01*
G01X68026Y405131D02*
X69083D01*
G01X68420Y406081D02*
X69431D01*
G01X65030Y427280D02*
X61920D01*
G01X64880Y426330D02*
X61930D01*
G01X50030Y421970D02*
X53290D01*
G01X50120Y421020D02*
X53140D01*
G01X68955Y416405D02*
X66809D01*
G01X69765Y415455D02*
X66900D01*
G01X66809Y416405D02*
X58465D01*
G01X64920Y415455D02*
X63920D01*
G01X66809Y416405D02*
X58465D01*
G01X61940Y415455D02*
X60279D01*
G01X66809Y416405D02*
X58465D01*
G01X60279Y415455D02*
X58859D01*
G01X58465Y416405D02*
X52810Y410750D01*
G01X58859Y415455D02*
X58152Y414748D01*
G01X58465Y416405D02*
X52810Y410750D01*
G01X56751Y413347D02*
X56044Y412640D01*
G01X58465Y416405D02*
X52810Y410750D01*
G01X54643Y411239D02*
X53760Y410356D01*
G01X52810Y410750D02*
Y408410D01*
G01X53760Y410356D02*
Y408804D01*
G01X52810Y408410D02*
X54244Y406976D01*
G01X53760Y408804D02*
X54924Y407640D01*
G01X52810Y408410D02*
X54244Y406976D01*
G01X54924Y407640D02*
X55860D01*
G01X68955Y416405D02*
X66809D01*
G01X69765Y415455D02*
X66900D01*
G01X66809Y416405D02*
X58465D01*
G01X64920Y415455D02*
X63920D01*
G01X66809Y416405D02*
X58465D01*
G01X61940Y415455D02*
X60279D01*
G01X66809Y416405D02*
X58465D01*
G01X60279Y415455D02*
X58859D01*
G01X58465Y416405D02*
X52810Y410750D01*
G01X58859Y415455D02*
X58152Y414748D01*
G01X58465Y416405D02*
X52810Y410750D01*
G01X56751Y413347D02*
X56044Y412640D01*
G01X58465Y416405D02*
X52810Y410750D01*
G01X54643Y411239D02*
X53760Y410356D01*
G01X52810Y410750D02*
Y408410D01*
G01X53760Y410356D02*
Y408804D01*
G01X52810Y408410D02*
X54244Y406976D01*
G01X53760Y408804D02*
X54924Y407640D01*
G01X52810Y408410D02*
X54244Y406976D01*
G01X54924Y407640D02*
X55860D01*
G01X64693Y405636D02*
X65415Y406358D01*
G01X65384Y404983D02*
X65809Y405408D01*
G01X64693Y405636D02*
X65415Y406358D01*
G01D02*
X68143D01*
G01D02*
X68420Y406081D01*
G01X65809Y405408D02*
X67749D01*
G01X68143Y406358D02*
X68420Y406081D01*
G01X67749Y405408D02*
X68026Y405131D01*
G01X68420Y406081D02*
X69431D01*
G01X68026Y405131D02*
X69083D01*
G01X70750Y427050D02*
X71256D01*
G01X70850Y426100D02*
X71650D01*
G01X71256Y427050D02*
X72072Y427866D01*
G01X71650Y426100D02*
X73022Y427472D01*
G01X72072Y427866D02*
Y431462D01*
G01X73022Y427472D02*
Y431068D01*
G01X72072Y431462D02*
X90791Y450181D01*
G01X73022Y431068D02*
X91330Y449375D01*
G01X90791Y450181D02*
X120047Y462300D01*
G01X91330Y449375D02*
X120236Y461350D01*
G01X74833Y416577D02*
X75471D01*
G01X75177Y415627D02*
X75865D01*
G01X74833Y416577D02*
X75471D01*
G01D02*
X84105Y425211D01*
G01X75865Y415627D02*
X85055Y424817D01*
G01X84105Y425211D02*
Y428070D01*
G01X85055Y424817D02*
Y427676D01*
G01X84105Y428070D02*
X102033Y445999D01*
G01X85055Y427676D02*
X102572Y445193D01*
G01X102033Y445999D02*
X122316Y454400D01*
G01X102572Y445193D02*
X122505Y453450D01*
G01X92754Y411996D02*
X98521Y417762D01*
G01X93560Y411457D02*
X99193Y417090D01*
G01X98521Y417763D02*
X99984Y419226D01*
G01X99193Y417091D02*
X100934Y418832D01*
G01X99984Y419226D02*
Y422029D01*
G01X100934Y418832D02*
Y421635D01*
G01X99984Y422029D02*
X108387Y430430D01*
G01X100934Y421635D02*
X108858Y429557D01*
G01X70850Y426100D02*
X71650D01*
G01X70750Y427050D02*
X71256D01*
G01X71650Y426100D02*
X73022Y427472D01*
G01X71256Y427050D02*
X72072Y427866D01*
G01X73022Y427472D02*
Y431068D01*
G01X72072Y427866D02*
Y431462D01*
G01X73022Y431068D02*
X91330Y449375D01*
G01X72072Y431462D02*
X90791Y450181D01*
G01X91330Y449375D02*
X120236Y461350D01*
G01X90791Y450181D02*
X120047Y462300D01*
G01X75177Y415627D02*
X75865D01*
G01D02*
X85055Y424817D01*
G01X74833Y416577D02*
X75471D01*
G01X75865Y415627D02*
X85055Y424817D01*
G01X75471Y416577D02*
X84105Y425211D01*
G01X85055Y424817D02*
Y427676D01*
G01X84105Y425211D02*
Y428070D01*
G01X85055Y427676D02*
X102572Y445193D01*
G01X84105Y428070D02*
X102033Y445999D01*
G01X102572Y445193D02*
X122505Y453450D01*
G01X102033Y445999D02*
X122316Y454400D01*
G01X74872Y404522D02*
X79367D01*
G01X75138Y405472D02*
X78973D01*
G01X79367Y404522D02*
X82048Y407205D01*
G01D02*
X82464Y407622D01*
G01D02*
X84501Y409662D01*
G01X78973Y405472D02*
X83695Y410200D01*
G01X84501Y409662D02*
X87047Y415805D01*
G01X83695Y410200D02*
X86241Y416344D01*
G01X87047Y415805D02*
X92839Y421597D01*
G01X86241Y416344D02*
X91889Y421991D01*
G01X92839Y421597D02*
Y424442D01*
G01X91889Y421991D02*
Y424836D01*
G01X92839Y424442D02*
X105125Y436723D01*
G01X91889Y424836D02*
X104654Y437596D01*
G01X105125Y436723D02*
X114379Y438644D01*
G01X104654Y437596D02*
X114005Y439537D01*
G01X93560Y411457D02*
X99193Y417090D01*
G01X92754Y411996D02*
X98521Y417762D01*
G01X99193Y417091D02*
X100934Y418832D01*
G01X98521Y417763D02*
X99984Y419226D01*
G01X100934Y418832D02*
Y421635D01*
G01X99984Y419226D02*
Y422029D01*
G01X100934Y421635D02*
X108858Y429557D01*
G01X99984Y422029D02*
X108387Y430430D01*
G01X56000Y470700D02*
Y464150D01*
G01X55050Y471094D02*
Y464544D01*
G01X56000Y464150D02*
X53779Y461928D01*
G01D02*
X47518Y455667D01*
G01X55050Y464544D02*
X46979Y456473D01*
G01X55050Y471094D02*
Y464544D01*
G01X56000Y470700D02*
Y464150D01*
G01X55050Y464544D02*
X46979Y456473D01*
G01X56000Y464150D02*
X53779Y461928D01*
G01X55050Y464544D02*
X46979Y456473D01*
G01X53779Y461928D02*
X47518Y455667D01*
G01X118701Y486150D02*
X81052Y472457D01*
G01X118533Y487100D02*
X80529Y473278D01*
G01X81865Y480044D02*
X108193Y490950D01*
G01X108382Y490000D02*
X82404Y479238D01*
G01X145252Y493850D02*
X107732D01*
G01X145299Y494800D02*
X107543D01*
G01X107732Y493850D02*
X77923Y481504D01*
G01X107543Y494800D02*
X77734Y482454D01*
G01X77923Y481504D02*
X69043D01*
G01X77734Y482454D02*
X68853D01*
G01X69043Y481504D02*
X65206Y479906D01*
G01X68853Y482454D02*
X64667Y480711D01*
G01X65206Y479906D02*
X56000Y470700D01*
G01X64667Y480711D02*
X55050Y471094D01*
G01X85210Y465789D02*
X120306Y478350D01*
G01X120141Y479300D02*
X84689Y466612D01*
G01X119559Y483200D02*
X82675Y470000D01*
G01X119724Y482250D02*
X83196Y469177D01*
G01X118533Y487100D02*
X80529Y473278D01*
G01X118701Y486150D02*
X81052Y472457D01*
G01X108382Y490000D02*
X82404Y479238D01*
G01X81865Y480044D02*
X108193Y490950D01*
G01X145299Y494800D02*
X107543D01*
G01X145252Y493850D02*
X107732D01*
G01X107543Y494800D02*
X77734Y482454D01*
G01X107732Y493850D02*
X77923Y481504D01*
G01X77734Y482454D02*
X68853D01*
G01X77923Y481504D02*
X69043D01*
G01X68853Y482454D02*
X64667Y480711D01*
G01X69043Y481504D02*
X65206Y479906D01*
G01X64667Y480711D02*
X55050Y471094D01*
G01X65206Y479906D02*
X56000Y470700D01*
G01X120141Y479300D02*
X84689Y466612D01*
G01X85210Y465789D02*
X120306Y478350D01*
G01X119724Y482250D02*
X83196Y469177D01*
G01X119559Y483200D02*
X82675Y470000D01*
G01X145252Y493850D02*
X107732D01*
G01X145299Y494800D02*
X107543D01*
G01X107732Y493850D02*
X77923Y481504D01*
G01X107543Y494800D02*
X77734Y482454D01*
G01X77923Y481504D02*
X69043D01*
G01X77734Y482454D02*
X68853D01*
G01X69043Y481504D02*
X65206Y479906D01*
G01X68853Y482454D02*
X64667Y480711D01*
G01X65206Y479906D02*
X56000Y470700D01*
G01X64667Y480711D02*
X55050Y471094D01*
G01X145299Y494800D02*
X107543D01*
G01X145252Y493850D02*
X107732D01*
G01X107543Y494800D02*
X77734Y482454D01*
G01X107732Y493850D02*
X77923Y481504D01*
G01X77734Y482454D02*
X68853D01*
G01X77923Y481504D02*
X69043D01*
G01X68853Y482454D02*
X64667Y480711D01*
G01X69043Y481504D02*
X65206Y479906D01*
G01X64667Y480711D02*
X55050Y471094D01*
G01X65206Y479906D02*
X56000Y470700D01*
G01X108370Y644149D02*
X107553Y645315D01*
G01D02*
X109058Y653856D01*
G01X106755Y654261D02*
X105046Y644559D01*
G01X105887Y654814D02*
X104178Y645113D01*
G01X105046Y644559D02*
X103877Y643744D01*
G01X104178Y645113D02*
X103655Y644748D01*
G01X105046Y644559D02*
X103877Y643744D01*
G01D02*
X101685Y644129D01*
G01X103655Y644748D02*
X102237Y644997D01*
G01X101685Y644129D02*
X100868Y645295D01*
G01X102237Y644997D02*
X101872Y645518D01*
G01X100868Y645295D02*
X102365Y653790D01*
G01X101872Y645518D02*
X103369Y654013D01*
G01X100061Y654194D02*
X98367Y644574D01*
G01X99193Y654747D02*
X97499Y645127D01*
G01X98367Y644574D02*
X97199Y643757D01*
G01X97499Y645127D02*
X96976Y644761D01*
G01X98367Y644574D02*
X97199Y643757D01*
G01D02*
X95005Y644142D01*
G01X96976Y644761D02*
X95559Y645010D01*
G01X95005Y644142D02*
X94190Y645311D01*
G01X95559Y645010D02*
X95194Y645533D01*
G01X94190Y645311D02*
X95684Y653794D01*
G01X95194Y645533D02*
X96689Y654017D01*
G01X93382Y654200D02*
X91684Y644553D01*
G01X92514Y654753D02*
X90816Y645107D01*
G01X91684Y644553D02*
X90516Y643738D01*
G01X90816Y645107D02*
X90293Y644742D01*
G01X91684Y644553D02*
X90516Y643738D01*
G01D02*
X88320Y644122D01*
G01X90293Y644742D02*
X88873Y644990D01*
G01X88320Y644122D02*
X87505Y645289D01*
G01X88873Y644990D02*
X88509Y645511D01*
G01X87505Y645289D02*
X89002Y653783D01*
G01X88509Y645511D02*
X90006Y654006D01*
G01X86698Y654188D02*
X84986Y644471D01*
G01X85830Y654741D02*
X84118Y645024D01*
G01X84986Y644471D02*
X83818Y643654D01*
G01X84118Y645024D02*
X83595Y644658D01*
G01X84986Y644471D02*
X83818Y643654D01*
G01D02*
X81624Y644039D01*
G01X83595Y644658D02*
X82178Y644907D01*
G01X81624Y644039D02*
X80809Y645208D01*
G01X82178Y644907D02*
X81813Y645430D01*
G01X80809Y645208D02*
X82319Y653779D01*
G01X81813Y645430D02*
X83324Y654002D01*
G01X80017Y654186D02*
X78308Y644485D01*
G01X79149Y654739D02*
X77440Y645038D01*
G01X78308Y644485D02*
X77140Y643668D01*
G01X77440Y645038D02*
X76917Y644672D01*
G01X78308Y644485D02*
X77140Y643668D01*
G01D02*
X74946Y644053D01*
G01X76917Y644672D02*
X75498Y644921D01*
G01X74946Y644053D02*
X74129Y645219D01*
G01X75498Y644921D02*
X75133Y645442D01*
G01X74129Y645219D02*
X75655Y653874D01*
G01X75133Y645442D02*
X76659Y654097D01*
G01X73014Y652372D02*
X70871Y649736D01*
G01D02*
X65542Y648844D01*
G01X70360Y650614D02*
X65500Y649801D01*
G01X65542Y648844D02*
X61193Y649181D01*
G01X65500Y649801D02*
X61230Y650131D01*
G01X61193Y649181D02*
X59179D01*
G01X108370Y644149D02*
X107553Y645315D01*
G01D02*
X109058Y653856D01*
G01X105887Y654814D02*
X104178Y645113D01*
G01X106755Y654261D02*
X105046Y644559D01*
G01X104178Y645113D02*
X103655Y644748D01*
G01D02*
X102237Y644997D01*
G01X105046Y644559D02*
X103877Y643744D01*
G01X103655Y644748D02*
X102237Y644997D01*
G01X103877Y643744D02*
X101685Y644129D01*
G01X102237Y644997D02*
X101872Y645518D01*
G01X101685Y644129D02*
X100868Y645295D01*
G01X101872Y645518D02*
X103369Y654013D01*
G01X100868Y645295D02*
X102365Y653790D01*
G01X99193Y654747D02*
X97499Y645127D01*
G01X100061Y654194D02*
X98367Y644574D01*
G01X97499Y645127D02*
X96976Y644761D01*
G01D02*
X95559Y645010D01*
G01X98367Y644574D02*
X97199Y643757D01*
G01X96976Y644761D02*
X95559Y645010D01*
G01X97199Y643757D02*
X95005Y644142D01*
G01X95559Y645010D02*
X95194Y645533D01*
G01X95005Y644142D02*
X94190Y645311D01*
G01X95194Y645533D02*
X96689Y654017D01*
G01X94190Y645311D02*
X95684Y653794D01*
G01X92514Y654753D02*
X90816Y645107D01*
G01X93382Y654200D02*
X91684Y644553D01*
G01X90816Y645107D02*
X90293Y644742D01*
G01D02*
X88873Y644990D01*
G01X91684Y644553D02*
X90516Y643738D01*
G01X90293Y644742D02*
X88873Y644990D01*
G01X90516Y643738D02*
X88320Y644122D01*
G01X88873Y644990D02*
X88509Y645511D01*
G01X88320Y644122D02*
X87505Y645289D01*
G01X88509Y645511D02*
X90006Y654006D01*
G01X87505Y645289D02*
X89002Y653783D01*
G01X85830Y654741D02*
X84118Y645024D01*
G01X86698Y654188D02*
X84986Y644471D01*
G01X84118Y645024D02*
X83595Y644658D01*
G01D02*
X82178Y644907D01*
G01X84986Y644471D02*
X83818Y643654D01*
G01X83595Y644658D02*
X82178Y644907D01*
G01X83818Y643654D02*
X81624Y644039D01*
G01X82178Y644907D02*
X81813Y645430D01*
G01X81624Y644039D02*
X80809Y645208D01*
G01X81813Y645430D02*
X83324Y654002D01*
G01X80809Y645208D02*
X82319Y653779D01*
G01X79149Y654739D02*
X77440Y645038D01*
G01X80017Y654186D02*
X78308Y644485D01*
G01X77440Y645038D02*
X76917Y644672D01*
G01D02*
X75498Y644921D01*
G01X78308Y644485D02*
X77140Y643668D01*
G01X76917Y644672D02*
X75498Y644921D01*
G01X77140Y643668D02*
X74946Y644053D01*
G01X75498Y644921D02*
X75133Y645442D01*
G01X74946Y644053D02*
X74129Y645219D01*
G01X75133Y645442D02*
X76659Y654097D01*
G01X74129Y645219D02*
X75655Y653874D01*
G01X73014Y652372D02*
X70871Y649736D01*
G01X70360Y650614D02*
X65500Y649801D01*
G01X70871Y649736D02*
X65542Y648844D01*
G01X65500Y649801D02*
X61230Y650131D01*
G01X65542Y648844D02*
X61193Y649181D01*
G01D02*
X59179D01*
G01X108694Y654376D02*
X107274Y654624D01*
G01X109246Y655244D02*
X107052Y655629D01*
G01X108694Y654376D02*
X107274Y654624D01*
G01D02*
X106755Y654261D01*
G01X107052Y655629D02*
X105887Y654814D01*
G01X102365Y653790D02*
X102001Y654310D01*
G01X103369Y654013D02*
X102553Y655178D01*
G01X102001Y654310D02*
X100581Y654558D01*
G01X102553Y655178D02*
X100359Y655563D01*
G01X102001Y654310D02*
X100581Y654558D01*
G01D02*
X100061Y654194D01*
G01X100359Y655563D02*
X99193Y654747D01*
G01X95684Y653794D02*
X95320Y654315D01*
G01X96689Y654017D02*
X95873Y655183D01*
G01X95320Y654315D02*
X93902Y654565D01*
G01X95873Y655183D02*
X93679Y655569D01*
G01X95320Y654315D02*
X93902Y654565D01*
G01D02*
X93382Y654200D01*
G01X93679Y655569D02*
X92514Y654753D01*
G01X89002Y653783D02*
X88637Y654302D01*
G01X90006Y654006D02*
X89190Y655170D01*
G01X88637Y654302D02*
X87218Y654552D01*
G01X89190Y655170D02*
X86996Y655557D01*
G01X88637Y654302D02*
X87218Y654552D01*
G01D02*
X86698Y654188D01*
G01X86996Y655557D02*
X85830Y654741D01*
G01X82319Y653779D02*
X81955Y654300D01*
G01X83324Y654002D02*
X82508Y655168D01*
G01X81955Y654300D02*
X80537Y654550D01*
G01X82508Y655168D02*
X80314Y655555D01*
G01X81955Y654300D02*
X80537Y654550D01*
G01D02*
X80017Y654186D01*
G01X80314Y655555D02*
X79149Y654739D01*
G01X75655Y653874D02*
X75290Y654394D01*
G01X76659Y654097D02*
X75843Y655262D01*
G01X75290Y654394D02*
X73871Y654644D01*
G01X75843Y655262D02*
X73649Y655648D01*
G01X75290Y654394D02*
X73871Y654644D01*
G01D02*
X73351Y654281D01*
G01X73649Y655648D02*
X72483Y654835D01*
G01X73351Y654281D02*
X73014Y652372D01*
G01X72483Y654835D02*
X72121Y652780D01*
G01D02*
X70360Y650614D01*
G01X61230Y650131D02*
X59179D01*
G01X109246Y655244D02*
X107052Y655629D01*
G01D02*
X105887Y654814D01*
G01X108694Y654376D02*
X107274Y654624D01*
G01X107052Y655629D02*
X105887Y654814D01*
G01X107274Y654624D02*
X106755Y654261D01*
G01X103369Y654013D02*
X102553Y655178D01*
G01X102365Y653790D02*
X102001Y654310D01*
G01X102553Y655178D02*
X100359Y655563D01*
G01D02*
X99193Y654747D01*
G01X102001Y654310D02*
X100581Y654558D01*
G01X100359Y655563D02*
X99193Y654747D01*
G01X100581Y654558D02*
X100061Y654194D01*
G01X96689Y654017D02*
X95873Y655183D01*
G01X95684Y653794D02*
X95320Y654315D01*
G01X95873Y655183D02*
X93679Y655569D01*
G01D02*
X92514Y654753D01*
G01X95320Y654315D02*
X93902Y654565D01*
G01X93679Y655569D02*
X92514Y654753D01*
G01X93902Y654565D02*
X93382Y654200D01*
G01X90006Y654006D02*
X89190Y655170D01*
G01X89002Y653783D02*
X88637Y654302D01*
G01X89190Y655170D02*
X86996Y655557D01*
G01D02*
X85830Y654741D01*
G01X88637Y654302D02*
X87218Y654552D01*
G01X86996Y655557D02*
X85830Y654741D01*
G01X87218Y654552D02*
X86698Y654188D01*
G01X83324Y654002D02*
X82508Y655168D01*
G01X82319Y653779D02*
X81955Y654300D01*
G01X82508Y655168D02*
X80314Y655555D01*
G01D02*
X79149Y654739D01*
G01X81955Y654300D02*
X80537Y654550D01*
G01X80314Y655555D02*
X79149Y654739D01*
G01X80537Y654550D02*
X80017Y654186D01*
G01X76659Y654097D02*
X75843Y655262D01*
G01X75655Y653874D02*
X75290Y654394D01*
G01X75843Y655262D02*
X73649Y655648D01*
G01D02*
X72483Y654835D01*
G01X75290Y654394D02*
X73871Y654644D01*
G01X73649Y655648D02*
X72483Y654835D01*
G01X73871Y654644D02*
X73351Y654281D01*
G01X72483Y654835D02*
X72121Y652780D01*
G01X73351Y654281D02*
X73014Y652372D01*
G01X72121Y652780D02*
X70360Y650614D01*
G01X61230Y650131D02*
X59179D01*
G01X176891Y462445D02*
X141513Y465929D01*
G01X212410Y459902D02*
X141560Y466879D01*
G01X212410Y459902D02*
X141560Y466879D01*
G01X212410Y459902D02*
X141560Y466879D01*
G01X176891Y462445D02*
X141513Y465929D01*
G01X116887Y436200D02*
X120484Y439258D01*
G01D02*
X120483D01*
G01D02*
X120597Y439355D01*
G01X117318Y435319D02*
X121100Y438534D01*
G01X120597Y439355D02*
X120788Y439435D01*
G01D02*
X120791Y439436D01*
G01D02*
X120799Y439439D01*
G01D02*
X120812Y439444D01*
G01X121100Y438534D02*
X121108Y438537D01*
G01X120597Y439355D02*
X120788Y439435D01*
G01X120791Y439436D02*
X120799Y439439D01*
G01D02*
X120812Y439444D01*
G01D02*
X128102Y442464D01*
G01X121108Y438537D02*
X121156Y438558D01*
G01X120597Y439355D02*
X120788Y439435D01*
G01X120791Y439436D02*
X120799Y439439D01*
G01D02*
X120812Y439444D01*
G01D02*
X128102Y442464D01*
G01X121156Y438558D02*
X121161Y438560D01*
G01X120799Y439439D02*
X120812Y439444D01*
G01D02*
X128102Y442464D01*
G01X121165Y438562D02*
X121176Y438566D01*
G01X120597Y439355D02*
X120788Y439435D01*
G01X120799Y439439D02*
X120812Y439444D01*
G01D02*
X128102Y442464D01*
G01X121176Y438566D02*
X128291Y441514D01*
G01X128102Y442464D02*
X143174D01*
G01X128291Y441514D02*
X143127D01*
G01X143174Y442464D02*
X209771Y435904D01*
G01X143127Y441514D02*
X209631Y434963D01*
G01X142816Y449549D02*
X208331Y443095D01*
G01X208471Y444036D02*
X142863Y450499D01*
G01X127451Y449549D02*
X142815D01*
G01X142863Y450499D02*
X127262D01*
G01X117204Y445304D02*
X127451Y449549D01*
G01X127262Y450499D02*
X116753Y446146D01*
G01X112655Y442254D02*
X117204Y445304D01*
G01X116753Y446146D02*
X112285Y443150D01*
G01X213368Y427295D02*
X136660Y434851D01*
G01X213228Y426354D02*
X136613Y433901D01*
G01X136660Y434851D02*
X130169D01*
G01X136613Y433901D02*
X130359D01*
G01X130169Y434851D02*
X124357Y432443D01*
G01X130359Y433901D02*
X124896Y431637D01*
G01X124357Y432443D02*
X121094Y429180D01*
G01X124896Y431637D02*
X121565Y428307D01*
G01X121094Y429180D02*
X110297Y426941D01*
G01X121565Y428307D02*
X110768Y426068D01*
G01X213368Y427295D02*
X136660Y434851D01*
G01X213228Y426354D02*
X136613Y433901D01*
G01X136660Y434851D02*
X130169D01*
G01X136613Y433901D02*
X130359D01*
G01X130169Y434851D02*
X124357Y432443D01*
G01X130359Y433901D02*
X124896Y431637D01*
G01X124357Y432443D02*
X121094Y429180D01*
G01X124896Y431637D02*
X121565Y428307D01*
G01X121094Y429180D02*
X110297Y426941D01*
G01X121565Y428307D02*
X110768Y426068D01*
G01X132100Y438654D02*
X141293D01*
G01X139776Y437704D02*
X141246D01*
G01X141293Y438654D02*
X210528Y431835D01*
G01X141246Y437704D02*
X210388Y430894D01*
G01X108387Y430430D02*
X119171Y432670D01*
G01X108858Y429557D02*
X119643Y431797D01*
G01X119171Y432670D02*
X122352Y435851D01*
G01X119643Y431797D02*
X122891Y435045D01*
G01X122352Y435851D02*
X129117Y438654D01*
G01X122891Y435045D02*
X129307Y437704D01*
G01X132100Y438654D02*
X141293D01*
G01X129117D02*
X132100D01*
G01X129307Y437704D02*
X139776D01*
G01X117318Y435319D02*
X121100Y438534D01*
G01X116887Y436200D02*
X120484Y439258D01*
G01X117318Y435319D02*
X121100Y438534D01*
G01X120484Y439258D02*
X120483D01*
G01X117318Y435319D02*
X121100Y438534D01*
G01X120483Y439258D02*
X120597Y439355D01*
G01X121100Y438534D02*
X121108Y438537D01*
G01D02*
X121156Y438558D01*
G01D02*
X121161Y438560D01*
G01X121176Y438566D02*
X128291Y441514D01*
G01X120597Y439355D02*
X120788Y439435D01*
G01X121100Y438534D02*
X121108Y438537D01*
G01X120788Y439435D02*
X120791Y439436D01*
G01X121100Y438534D02*
X121108Y438537D01*
G01D02*
X121156Y438558D01*
G01D02*
X121161Y438560D01*
G01X120791Y439436D02*
X120799Y439439D01*
G01X121100Y438534D02*
X121108Y438537D01*
G01D02*
X121156Y438558D01*
G01D02*
X121161Y438560D01*
G01X121165Y438562D02*
X121176Y438566D01*
G01D02*
X128291Y441514D01*
G01X120799Y439439D02*
X120812Y439444D01*
G01X121108Y438537D02*
X121156Y438558D01*
G01D02*
X121161Y438560D01*
G01X121165Y438562D02*
X121176Y438566D01*
G01D02*
X128291Y441514D01*
G01X120812Y439444D02*
X128102Y442464D01*
G01X128291Y441514D02*
X143127D01*
G01X128102Y442464D02*
X143174D01*
G01X143127Y441514D02*
X209631Y434963D01*
G01X143174Y442464D02*
X209771Y435904D01*
G01X116753Y446146D02*
X112285Y443150D01*
G01X112655Y442254D02*
X117204Y445304D01*
G01X127262Y450499D02*
X116753Y446146D01*
G01X117204Y445304D02*
X127451Y449549D01*
G01X142863Y450499D02*
X127262D01*
G01X127451Y449549D02*
X142815D01*
G01X208471Y444036D02*
X142863Y450499D01*
G01X142816Y449549D02*
X208331Y443095D01*
G01X213228Y426354D02*
X136613Y433901D01*
G01X213368Y427295D02*
X136660Y434851D01*
G01X136613Y433901D02*
X130359D01*
G01X136660Y434851D02*
X130169D01*
G01X130359Y433901D02*
X124896Y431637D01*
G01X130169Y434851D02*
X124357Y432443D01*
G01X124896Y431637D02*
X121565Y428307D01*
G01X124357Y432443D02*
X121094Y429180D01*
G01X121565Y428307D02*
X110768Y426068D01*
G01X121094Y429180D02*
X110297Y426941D01*
G01X213228Y426354D02*
X136613Y433901D01*
G01X213368Y427295D02*
X136660Y434851D01*
G01X136613Y433901D02*
X130359D01*
G01X136660Y434851D02*
X130169D01*
G01X130359Y433901D02*
X124896Y431637D01*
G01X130169Y434851D02*
X124357Y432443D01*
G01X124896Y431637D02*
X121565Y428307D01*
G01X124357Y432443D02*
X121094Y429180D01*
G01X121565Y428307D02*
X110768Y426068D01*
G01X121094Y429180D02*
X110297Y426941D01*
G01X139776Y437704D02*
X141246D01*
G01X129307D02*
X139776D01*
G01X132100Y438654D02*
X141293D01*
G01X141246Y437704D02*
X210388Y430894D01*
G01X141293Y438654D02*
X210528Y431835D01*
G01X108858Y429557D02*
X119643Y431797D01*
G01X108387Y430430D02*
X119171Y432670D01*
G01X119643Y431797D02*
X122891Y435045D01*
G01X119171Y432670D02*
X122352Y435851D01*
G01X122891Y435045D02*
X129307Y437704D01*
G01X122352Y435851D02*
X129117Y438654D01*
G01X129307Y437704D02*
X139776D01*
G01X129117Y438654D02*
X132100D01*
G01X210321Y455687D02*
X143180Y462300D01*
G01X210182Y454746D02*
X143133Y461350D01*
G01X143180Y462300D02*
X121800D01*
G01X143133Y461350D02*
X134000D01*
G01X143180Y462300D02*
X121800D01*
G01X120047D02*
X121800D01*
G01X120236Y461350D02*
X134000D01*
G01X142263Y457450D02*
X209631Y450815D01*
G01X209771Y451756D02*
X142310Y458400D01*
G01X120785Y457450D02*
X142263D01*
G01X142310Y458400D02*
X120596D01*
G01X142263Y457450D02*
X209631Y450815D01*
G01X209771Y451756D02*
X142310Y458400D01*
G01X120785Y457450D02*
X142263D01*
G01X142310Y458400D02*
X120596D01*
G01X116887Y436200D02*
X120484Y439258D01*
G01D02*
X120483D01*
G01D02*
X120597Y439355D01*
G01X117318Y435319D02*
X121100Y438534D01*
G01X120597Y439355D02*
X120788Y439435D01*
G01D02*
X120791Y439436D01*
G01D02*
X120799Y439439D01*
G01D02*
X120812Y439444D01*
G01X121100Y438534D02*
X121108Y438537D01*
G01X120597Y439355D02*
X120788Y439435D01*
G01X120791Y439436D02*
X120799Y439439D01*
G01D02*
X120812Y439444D01*
G01D02*
X128102Y442464D01*
G01X121108Y438537D02*
X121156Y438558D01*
G01X120597Y439355D02*
X120788Y439435D01*
G01X120791Y439436D02*
X120799Y439439D01*
G01D02*
X120812Y439444D01*
G01D02*
X128102Y442464D01*
G01X121156Y438558D02*
X121161Y438560D01*
G01X120799Y439439D02*
X120812Y439444D01*
G01D02*
X128102Y442464D01*
G01X121165Y438562D02*
X121176Y438566D01*
G01X120597Y439355D02*
X120788Y439435D01*
G01X120799Y439439D02*
X120812Y439444D01*
G01D02*
X128102Y442464D01*
G01X121176Y438566D02*
X128291Y441514D01*
G01X128102Y442464D02*
X143174D01*
G01X128291Y441514D02*
X143127D01*
G01X143174Y442464D02*
X209771Y435904D01*
G01X143127Y441514D02*
X209631Y434963D01*
G01X126700Y454400D02*
X143358D01*
G01X139300Y453450D02*
X143311D01*
G01X143358Y454400D02*
X209175Y447918D01*
G01X143311Y453450D02*
X209035Y446977D01*
G01X126700Y454400D02*
X143358D01*
G01X122316D02*
X126700D01*
G01X122505Y453450D02*
X139300D01*
G01X142816Y449549D02*
X208331Y443095D01*
G01X208471Y444036D02*
X142863Y450499D01*
G01X127451Y449549D02*
X142815D01*
G01X142863Y450499D02*
X127262D01*
G01X117204Y445304D02*
X127451Y449549D01*
G01X127262Y450499D02*
X116753Y446146D01*
G01X112655Y442254D02*
X117204Y445304D01*
G01X116753Y446146D02*
X112285Y443150D01*
G01X114005Y439537D02*
X119253Y443044D01*
G01X114379Y438644D02*
X119703Y442202D01*
G01X119253Y443044D02*
X127835Y446600D01*
G01X119703Y442202D02*
X128025Y445650D01*
G01X130000Y446600D02*
X140388D01*
G01X127835D02*
X130000D01*
G01X128025Y445650D02*
X140341D01*
G01X140388Y446600D02*
X210195Y439725D01*
G01X140341Y445650D02*
X210055Y438784D01*
G01X114005Y439537D02*
X119253Y443044D01*
G01X114379Y438644D02*
X119703Y442202D01*
G01X119253Y443044D02*
X127835Y446600D01*
G01X119703Y442202D02*
X128025Y445650D01*
G01X130000Y446600D02*
X140388D01*
G01X127835D02*
X130000D01*
G01X128025Y445650D02*
X140341D01*
G01X140388Y446600D02*
X210195Y439725D01*
G01X140341Y445650D02*
X210055Y438784D01*
G01X210182Y454746D02*
X143133Y461350D01*
G01X210321Y455687D02*
X143180Y462300D01*
G01X143133Y461350D02*
X134000D01*
G01X120236D02*
X134000D01*
G01X143180Y462300D02*
X121800D01*
G01X120236Y461350D02*
X134000D01*
G01X120047Y462300D02*
X121800D01*
G01X142310Y458400D02*
X120596D01*
G01X120785Y457450D02*
X142263D01*
G01X209771Y451756D02*
X142310Y458400D01*
G01X142263Y457450D02*
X209631Y450815D01*
G01X142310Y458400D02*
X120596D01*
G01X120785Y457450D02*
X142263D01*
G01X209771Y451756D02*
X142310Y458400D01*
G01X142263Y457450D02*
X209631Y450815D01*
G01X117318Y435319D02*
X121100Y438534D01*
G01X116887Y436200D02*
X120484Y439258D01*
G01X117318Y435319D02*
X121100Y438534D01*
G01X120484Y439258D02*
X120483D01*
G01X117318Y435319D02*
X121100Y438534D01*
G01X120483Y439258D02*
X120597Y439355D01*
G01X121100Y438534D02*
X121108Y438537D01*
G01D02*
X121156Y438558D01*
G01D02*
X121161Y438560D01*
G01X121176Y438566D02*
X128291Y441514D01*
G01X120597Y439355D02*
X120788Y439435D01*
G01X121100Y438534D02*
X121108Y438537D01*
G01X120788Y439435D02*
X120791Y439436D01*
G01X121100Y438534D02*
X121108Y438537D01*
G01D02*
X121156Y438558D01*
G01D02*
X121161Y438560D01*
G01X120791Y439436D02*
X120799Y439439D01*
G01X121100Y438534D02*
X121108Y438537D01*
G01D02*
X121156Y438558D01*
G01D02*
X121161Y438560D01*
G01X121165Y438562D02*
X121176Y438566D01*
G01D02*
X128291Y441514D01*
G01X120799Y439439D02*
X120812Y439444D01*
G01X121108Y438537D02*
X121156Y438558D01*
G01D02*
X121161Y438560D01*
G01X121165Y438562D02*
X121176Y438566D01*
G01D02*
X128291Y441514D01*
G01X120812Y439444D02*
X128102Y442464D01*
G01X128291Y441514D02*
X143127D01*
G01X128102Y442464D02*
X143174D01*
G01X143127Y441514D02*
X209631Y434963D01*
G01X143174Y442464D02*
X209771Y435904D01*
G01X139300Y453450D02*
X143311D01*
G01X122505D02*
X139300D01*
G01X126700Y454400D02*
X143358D01*
G01X143311Y453450D02*
X209035Y446977D01*
G01X143358Y454400D02*
X209175Y447918D01*
G01X122505Y453450D02*
X139300D01*
G01X122316Y454400D02*
X126700D01*
G01X116753Y446146D02*
X112285Y443150D01*
G01X112655Y442254D02*
X117204Y445304D01*
G01X127262Y450499D02*
X116753Y446146D01*
G01X117204Y445304D02*
X127451Y449549D01*
G01X142863Y450499D02*
X127262D01*
G01X127451Y449549D02*
X142815D01*
G01X208471Y444036D02*
X142863Y450499D01*
G01X142816Y449549D02*
X208331Y443095D01*
G01X128025Y445650D02*
X140341D01*
G01X130000Y446600D02*
X140388D01*
G01X140341Y445650D02*
X210055Y438784D01*
G01X140388Y446600D02*
X210195Y439725D01*
G01X114379Y438644D02*
X119703Y442202D01*
G01X114005Y439537D02*
X119253Y443044D01*
G01X119703Y442202D02*
X128025Y445650D01*
G01X119253Y443044D02*
X127835Y446600D01*
G01X128025Y445650D02*
X140341D01*
G01X127835Y446600D02*
X130000D01*
G01X210321Y455687D02*
X143180Y462300D01*
G01X210182Y454746D02*
X143133Y461350D01*
G01X143180Y462300D02*
X121800D01*
G01X143133Y461350D02*
X134000D01*
G01X143180Y462300D02*
X121800D01*
G01X120047D02*
X121800D01*
G01X120236Y461350D02*
X134000D01*
G01X126700Y454400D02*
X143358D01*
G01X139300Y453450D02*
X143311D01*
G01X143358Y454400D02*
X209175Y447918D01*
G01X143311Y453450D02*
X209035Y446977D01*
G01X126700Y454400D02*
X143358D01*
G01X122316D02*
X126700D01*
G01X122505Y453450D02*
X139300D01*
G01X132100Y438654D02*
X141293D01*
G01X139776Y437704D02*
X141246D01*
G01X141293Y438654D02*
X210528Y431835D01*
G01X141246Y437704D02*
X210388Y430894D01*
G01X108387Y430430D02*
X119171Y432670D01*
G01X108858Y429557D02*
X119643Y431797D01*
G01X119171Y432670D02*
X122352Y435851D01*
G01X119643Y431797D02*
X122891Y435045D01*
G01X122352Y435851D02*
X129117Y438654D01*
G01X122891Y435045D02*
X129307Y437704D01*
G01X132100Y438654D02*
X141293D01*
G01X129117D02*
X132100D01*
G01X129307Y437704D02*
X139776D01*
G01X210182Y454746D02*
X143133Y461350D01*
G01X210321Y455687D02*
X143180Y462300D01*
G01X143133Y461350D02*
X134000D01*
G01X120236D02*
X134000D01*
G01X143180Y462300D02*
X121800D01*
G01X120236Y461350D02*
X134000D01*
G01X120047Y462300D02*
X121800D01*
G01X139300Y453450D02*
X143311D01*
G01X122505D02*
X139300D01*
G01X126700Y454400D02*
X143358D01*
G01X143311Y453450D02*
X209035Y446977D01*
G01X143358Y454400D02*
X209175Y447918D01*
G01X122505Y453450D02*
X139300D01*
G01X122316Y454400D02*
X126700D01*
G01X128025Y445650D02*
X140341D01*
G01X130000Y446600D02*
X140388D01*
G01X140341Y445650D02*
X210055Y438784D01*
G01X140388Y446600D02*
X210195Y439725D01*
G01X114379Y438644D02*
X119703Y442202D01*
G01X114005Y439537D02*
X119253Y443044D01*
G01X119703Y442202D02*
X128025Y445650D01*
G01X119253Y443044D02*
X127835Y446600D01*
G01X128025Y445650D02*
X140341D01*
G01X127835Y446600D02*
X130000D01*
G01X139776Y437704D02*
X141246D01*
G01X129307D02*
X139776D01*
G01X132100Y438654D02*
X141293D01*
G01X141246Y437704D02*
X210388Y430894D01*
G01X141293Y438654D02*
X210528Y431835D01*
G01X108858Y429557D02*
X119643Y431797D01*
G01X108387Y430430D02*
X119171Y432670D01*
G01X119643Y431797D02*
X122891Y435045D01*
G01X119171Y432670D02*
X122352Y435851D01*
G01X122891Y435045D02*
X129307Y437704D01*
G01X122352Y435851D02*
X129117Y438654D01*
G01X129307Y437704D02*
X139776D01*
G01X129117Y438654D02*
X132100D01*
G01X141513Y465929D02*
X119826D01*
G01X141560Y466879D02*
X119661D01*
G01X141560D02*
X119661D01*
G01X141513Y465929D02*
X119826D01*
G01X135640Y475400D02*
X239102Y465211D01*
G01X239150Y464251D02*
X135593Y474450D01*
G01X120597Y475400D02*
X135640D01*
G01X135593Y474450D02*
X120762D01*
G01X237310Y476498D02*
X139313Y486150D01*
G01X237262Y477458D02*
X139360Y487100D01*
G01X139313Y486150D02*
X118701D01*
G01X139360Y487100D02*
X118533D01*
G01X210706Y463159D02*
X139242Y470200D01*
G01X210846Y464100D02*
X139289Y471150D01*
G01X139242Y470200D02*
X120472D01*
G01X139289Y471150D02*
X120307D01*
G01X142327Y490950D02*
X189999Y486255D01*
G01X237722Y480599D02*
X142280Y490000D01*
G01X108193Y490950D02*
X142327D01*
G01X142280Y490000D02*
X108382D01*
G01X237729Y484742D02*
X145252Y493850D01*
G01X237681Y485702D02*
X145299Y494800D01*
G01X134954Y478350D02*
X237842Y468216D01*
G01X237794Y469176D02*
X135001Y479300D01*
G01X120306Y478350D02*
X134954D01*
G01X135001Y479300D02*
X120141D01*
G01X236849Y473416D02*
X137504Y483200D01*
G01X236897Y472456D02*
X137457Y482250D01*
G01X137504Y483200D02*
X119559D01*
G01X137457Y482250D02*
X119724D01*
G01X135593Y474450D02*
X120762D01*
G01X120597Y475400D02*
X135640D01*
G01X239150Y464251D02*
X135593Y474450D01*
G01X135640Y475400D02*
X239102Y465211D01*
G01X237262Y477458D02*
X139360Y487100D01*
G01X237310Y476498D02*
X139313Y486150D01*
G01X139360Y487100D02*
X118533D01*
G01X139313Y486150D02*
X118701D01*
G01X210846Y464100D02*
X139289Y471150D01*
G01X210706Y463159D02*
X139242Y470200D01*
G01X139289Y471150D02*
X120307D01*
G01X139242Y470200D02*
X120472D01*
G01X142280Y490000D02*
X108382D01*
G01X108193Y490950D02*
X142327D01*
G01X237722Y480599D02*
X142280Y490000D01*
G01X142327Y490950D02*
X189999Y486255D01*
G01X237722Y480599D02*
X142280Y490000D01*
G01X237722Y480599D02*
X142280Y490000D01*
G01X237681Y485702D02*
X145299Y494800D01*
G01X237729Y484742D02*
X145252Y493850D01*
G01X135001Y479300D02*
X120141D01*
G01X120306Y478350D02*
X134954D01*
G01X237794Y469176D02*
X135001Y479300D01*
G01X134954Y478350D02*
X237842Y468216D01*
G01X236897Y472456D02*
X137457Y482250D01*
G01X236849Y473416D02*
X137504Y483200D01*
G01X137457Y482250D02*
X119724D01*
G01X137504Y483200D02*
X119559D01*
G01X237729Y484742D02*
X145252Y493850D01*
G01X237681Y485702D02*
X145299Y494800D01*
G01X237681Y485702D02*
X145299Y494800D01*
G01X237729Y484742D02*
X145252Y493850D01*
G01X170690Y643698D02*
X168496Y644084D01*
G01X170467Y644702D02*
X169049Y644952D01*
G01X168496Y644084D02*
X167680Y645250D01*
G01X169049Y644952D02*
X168685Y645473D01*
G01X167680Y645250D02*
X169175Y653734D01*
G01X168685Y645473D02*
X170179Y653956D01*
G01X166870Y654140D02*
X165176Y644520D01*
G01X166002Y654693D02*
X164308Y645073D01*
G01X165176Y644520D02*
X164010Y643704D01*
G01X164308Y645073D02*
X163788Y644709D01*
G01X165176Y644520D02*
X164010Y643704D01*
G01D02*
X161816Y644089D01*
G01X163788Y644709D02*
X162368Y644957D01*
G01X161816Y644089D02*
X161000Y645254D01*
G01X162368Y644957D02*
X162004Y645477D01*
G01X161000Y645254D02*
X162497Y653749D01*
G01X162004Y645477D02*
X163501Y653972D01*
G01X160191Y654154D02*
X158482Y644453D01*
G01X159323Y654708D02*
X157614Y645006D01*
G01X158482Y644453D02*
X157317Y643638D01*
G01X157614Y645006D02*
X157095Y644643D01*
G01X158482Y644453D02*
X157317Y643638D01*
G01D02*
X155123Y644023D01*
G01X157095Y644643D02*
X155675Y644891D01*
G01X155123Y644023D02*
X154307Y645188D01*
G01X155675Y644891D02*
X155311Y645411D01*
G01X154307Y645188D02*
X155812Y653729D01*
G01X155311Y645411D02*
X156816Y653952D01*
G01X153506Y654133D02*
X151802Y644461D01*
G01X152638Y654686D02*
X150934Y645014D01*
G01X151802Y644461D02*
X150624Y643636D01*
G01X150934Y645014D02*
X150401Y644641D01*
G01X151802Y644461D02*
X150624Y643636D01*
G01D02*
X148453Y644019D01*
G01X150401Y644641D02*
X149005Y644887D01*
G01X148453Y644019D02*
X147624Y645198D01*
G01X149005Y644887D02*
X148629Y645422D01*
G01X147624Y645198D02*
X149132Y653752D01*
G01X148629Y645422D02*
X150136Y653974D01*
G01X146827Y654156D02*
X145119Y644447D01*
G01X145959Y654709D02*
X144251Y645000D01*
G01X145119Y644447D02*
X143954Y643632D01*
G01X144251Y645000D02*
X143731Y644636D01*
G01X145119Y644447D02*
X143954Y643632D01*
G01D02*
X141756Y644018D01*
G01X143731Y644636D02*
X142310Y644886D01*
G01X141756Y644018D02*
X140943Y645184D01*
G01X142310Y644886D02*
X141947Y645406D01*
G01X140943Y645184D02*
X142451Y653750D01*
G01X141947Y645406D02*
X143455Y653973D01*
G01X140146Y654153D02*
X138442Y644480D01*
G01X139278Y654706D02*
X137574Y645033D01*
G01X138442Y644480D02*
X137277Y643665D01*
G01X137574Y645033D02*
X137054Y644669D01*
G01X138442Y644480D02*
X137277Y643665D01*
G01D02*
X135082Y644050D01*
G01X137054Y644669D02*
X135634Y644918D01*
G01X135082Y644050D02*
X134265Y645217D01*
G01X135634Y644918D02*
X135269Y645440D01*
G01X134265Y645217D02*
X135767Y653735D01*
G01X135269Y645440D02*
X136771Y653957D01*
G01X133463Y654141D02*
X131774Y644573D01*
G01X132595Y654694D02*
X130906Y645126D01*
G01X131774Y644573D02*
X130606Y643756D01*
G01X130906Y645126D02*
X130383Y644760D01*
G01X131774Y644573D02*
X130606Y643756D01*
G01D02*
X128413Y644141D01*
G01X130383Y644760D02*
X128967Y645009D01*
G01X128413Y644141D02*
X127598Y645310D01*
G01X128967Y645009D02*
X128602Y645532D01*
G01X127598Y645310D02*
X129100Y653827D01*
G01X128602Y645532D02*
X130104Y654050D01*
G01X126795Y654234D02*
X125091Y644561D01*
G01X125927Y654787D02*
X124223Y645114D01*
G01X125091Y644561D02*
X123922Y643744D01*
G01X124223Y645114D02*
X123699Y644748D01*
G01X125091Y644561D02*
X123922Y643744D01*
G01D02*
X121731Y644128D01*
G01X123699Y644748D02*
X122283Y644996D01*
G01X121731Y644128D02*
X120914Y645294D01*
G01X122283Y644996D02*
X121918Y645517D01*
G01X120914Y645294D02*
X122422Y653861D01*
G01X121918Y645517D02*
X123426Y654083D01*
G01X120118Y654267D02*
X118410Y644558D01*
G01X119250Y654820D02*
X117542Y645111D01*
G01X118410Y644558D02*
X117241Y643741D01*
G01X117542Y645111D02*
X117019Y644745D01*
G01X118410Y644558D02*
X117241Y643741D01*
G01D02*
X115049Y644126D01*
G01X117019Y644745D02*
X115602Y644994D01*
G01X115049Y644126D02*
X114233Y645293D01*
G01X115602Y644994D02*
X115237Y645515D01*
G01X114233Y645293D02*
X115740Y653845D01*
G01X115237Y645515D02*
X116745Y654069D01*
G01X113435Y654253D02*
X111731Y644581D01*
G01X112567Y654806D02*
X110863Y645134D01*
G01X111731Y644581D02*
X110563Y643764D01*
G01X110863Y645134D02*
X110340Y644768D01*
G01X111731Y644581D02*
X110563Y643764D01*
G01D02*
X108370Y644149D01*
G01X110340Y644768D02*
X108922Y645017D01*
G01D02*
X108557Y645538D01*
G01D02*
X110062Y654079D01*
G01X170467Y644702D02*
X169049Y644952D01*
G01X170467Y644702D02*
X169049Y644952D01*
G01X170690Y643698D02*
X168496Y644084D01*
G01X169049Y644952D02*
X168685Y645473D01*
G01X168496Y644084D02*
X167680Y645250D01*
G01X168685Y645473D02*
X170179Y653956D01*
G01X167680Y645250D02*
X169175Y653734D01*
G01X166002Y654693D02*
X164308Y645073D01*
G01X166870Y654140D02*
X165176Y644520D01*
G01X164308Y645073D02*
X163788Y644709D01*
G01D02*
X162368Y644957D01*
G01X165176Y644520D02*
X164010Y643704D01*
G01X163788Y644709D02*
X162368Y644957D01*
G01X164010Y643704D02*
X161816Y644089D01*
G01X162368Y644957D02*
X162004Y645477D01*
G01X161816Y644089D02*
X161000Y645254D01*
G01X162004Y645477D02*
X163501Y653972D01*
G01X161000Y645254D02*
X162497Y653749D01*
G01X159323Y654708D02*
X157614Y645006D01*
G01X160191Y654154D02*
X158482Y644453D01*
G01X157614Y645006D02*
X157095Y644643D01*
G01D02*
X155675Y644891D01*
G01X158482Y644453D02*
X157317Y643638D01*
G01X157095Y644643D02*
X155675Y644891D01*
G01X157317Y643638D02*
X155123Y644023D01*
G01X155675Y644891D02*
X155311Y645411D01*
G01X155123Y644023D02*
X154307Y645188D01*
G01X155311Y645411D02*
X156816Y653952D01*
G01X154307Y645188D02*
X155812Y653729D01*
G01X152638Y654686D02*
X150934Y645014D01*
G01X153506Y654133D02*
X151802Y644461D01*
G01X150934Y645014D02*
X150401Y644641D01*
G01D02*
X149005Y644887D01*
G01X151802Y644461D02*
X150624Y643636D01*
G01X150401Y644641D02*
X149005Y644887D01*
G01X150624Y643636D02*
X148453Y644019D01*
G01X149005Y644887D02*
X148629Y645422D01*
G01X148453Y644019D02*
X147624Y645198D01*
G01X148629Y645422D02*
X150136Y653974D01*
G01X147624Y645198D02*
X149132Y653752D01*
G01X145959Y654709D02*
X144251Y645000D01*
G01X146827Y654156D02*
X145119Y644447D01*
G01X144251Y645000D02*
X143731Y644636D01*
G01D02*
X142310Y644886D01*
G01X145119Y644447D02*
X143954Y643632D01*
G01X143731Y644636D02*
X142310Y644886D01*
G01X143954Y643632D02*
X141756Y644018D01*
G01X142310Y644886D02*
X141947Y645406D01*
G01X141756Y644018D02*
X140943Y645184D01*
G01X141947Y645406D02*
X143455Y653973D01*
G01X140943Y645184D02*
X142451Y653750D01*
G01X139278Y654706D02*
X137574Y645033D01*
G01X140146Y654153D02*
X138442Y644480D01*
G01X137574Y645033D02*
X137054Y644669D01*
G01D02*
X135634Y644918D01*
G01X138442Y644480D02*
X137277Y643665D01*
G01X137054Y644669D02*
X135634Y644918D01*
G01X137277Y643665D02*
X135082Y644050D01*
G01X135634Y644918D02*
X135269Y645440D01*
G01X135082Y644050D02*
X134265Y645217D01*
G01X135269Y645440D02*
X136771Y653957D01*
G01X134265Y645217D02*
X135767Y653735D01*
G01X132595Y654694D02*
X130906Y645126D01*
G01X133463Y654141D02*
X131774Y644573D01*
G01X130906Y645126D02*
X130383Y644760D01*
G01D02*
X128967Y645009D01*
G01X131774Y644573D02*
X130606Y643756D01*
G01X130383Y644760D02*
X128967Y645009D01*
G01X130606Y643756D02*
X128413Y644141D01*
G01X128967Y645009D02*
X128602Y645532D01*
G01X128413Y644141D02*
X127598Y645310D01*
G01X128602Y645532D02*
X130104Y654050D01*
G01X127598Y645310D02*
X129100Y653827D01*
G01X125927Y654787D02*
X124223Y645114D01*
G01X126795Y654234D02*
X125091Y644561D01*
G01X124223Y645114D02*
X123699Y644748D01*
G01D02*
X122283Y644996D01*
G01X125091Y644561D02*
X123922Y643744D01*
G01X123699Y644748D02*
X122283Y644996D01*
G01X123922Y643744D02*
X121731Y644128D01*
G01X122283Y644996D02*
X121918Y645517D01*
G01X121731Y644128D02*
X120914Y645294D01*
G01X121918Y645517D02*
X123426Y654083D01*
G01X120914Y645294D02*
X122422Y653861D01*
G01X119250Y654820D02*
X117542Y645111D01*
G01X120118Y654267D02*
X118410Y644558D01*
G01X117542Y645111D02*
X117019Y644745D01*
G01D02*
X115602Y644994D01*
G01X118410Y644558D02*
X117241Y643741D01*
G01X117019Y644745D02*
X115602Y644994D01*
G01X117241Y643741D02*
X115049Y644126D01*
G01X115602Y644994D02*
X115237Y645515D01*
G01X115049Y644126D02*
X114233Y645293D01*
G01X115237Y645515D02*
X116745Y654069D01*
G01X114233Y645293D02*
X115740Y653845D01*
G01X112567Y654806D02*
X110863Y645134D01*
G01X113435Y654253D02*
X111731Y644581D01*
G01X110863Y645134D02*
X110340Y644768D01*
G01D02*
X108922Y645017D01*
G01X111731Y644581D02*
X110563Y643764D01*
G01X110340Y644768D02*
X108922Y645017D01*
G01X110563Y643764D02*
X108370Y644149D01*
G01X108922Y645017D02*
X108557Y645538D01*
G01D02*
X110062Y654079D01*
G01X169175Y653734D02*
X168810Y654257D01*
G01X170179Y653956D02*
X169364Y655125D01*
G01X168810Y654257D02*
X167393Y654506D01*
G01X169364Y655125D02*
X167170Y655510D01*
G01X168810Y654257D02*
X167393Y654506D01*
G01D02*
X166870Y654140D01*
G01X167170Y655510D02*
X166002Y654693D01*
G01X162497Y653749D02*
X162132Y654270D01*
G01X163501Y653972D02*
X162684Y655138D01*
G01X162132Y654270D02*
X160714Y654519D01*
G01X162684Y655138D02*
X160492Y655523D01*
G01X162132Y654270D02*
X160714Y654519D01*
G01D02*
X160191Y654154D01*
G01X160492Y655523D02*
X159323Y654708D01*
G01X155812Y653729D02*
X155447Y654250D01*
G01X156816Y653952D02*
X155999Y655118D01*
G01X155447Y654250D02*
X154029Y654499D01*
G01X155999Y655118D02*
X153806Y655503D01*
G01X155447Y654250D02*
X154029Y654499D01*
G01D02*
X153506Y654133D01*
G01X153806Y655503D02*
X152638Y654686D01*
G01X149132Y653752D02*
X148767Y654273D01*
G01X150136Y653974D02*
X149320Y655141D01*
G01X148767Y654273D02*
X147350Y654522D01*
G01X149320Y655141D02*
X147128Y655526D01*
G01X148767Y654273D02*
X147350Y654522D01*
G01D02*
X146827Y654156D01*
G01X147128Y655526D02*
X145959Y654709D01*
G01X142451Y653750D02*
X142086Y654271D01*
G01X143455Y653973D02*
X142638Y655139D01*
G01X142086Y654271D02*
X140670Y654519D01*
G01X142638Y655139D02*
X140447Y655523D01*
G01X142086Y654271D02*
X140670Y654519D01*
G01D02*
X140146Y654153D01*
G01X140447Y655523D02*
X139278Y654706D01*
G01X135767Y653735D02*
X135402Y654258D01*
G01X136771Y653957D02*
X135956Y655126D01*
G01X135402Y654258D02*
X133986Y654507D01*
G01X135956Y655126D02*
X133763Y655511D01*
G01X135402Y654258D02*
X133986Y654507D01*
G01D02*
X133463Y654141D01*
G01X133763Y655511D02*
X132595Y654694D01*
G01X129100Y653827D02*
X128735Y654349D01*
G01X130104Y654050D02*
X129287Y655217D01*
G01X128735Y654349D02*
X127315Y654598D01*
G01X129287Y655217D02*
X127092Y655602D01*
G01X128735Y654349D02*
X127315Y654598D01*
G01D02*
X126795Y654234D01*
G01X127092Y655602D02*
X125927Y654787D01*
G01X122422Y653861D02*
X122059Y654381D01*
G01X123426Y654083D02*
X122613Y655249D01*
G01X122059Y654381D02*
X120638Y654631D01*
G01X122613Y655249D02*
X120415Y655635D01*
G01X122059Y654381D02*
X120638Y654631D01*
G01D02*
X120118Y654267D01*
G01X120415Y655635D02*
X119250Y654820D01*
G01X115740Y653845D02*
X115364Y654380D01*
G01X116745Y654069D02*
X115916Y655248D01*
G01X115364Y654380D02*
X113968Y654626D01*
G01X115916Y655248D02*
X113745Y655631D01*
G01X115364Y654380D02*
X113968Y654626D01*
G01D02*
X113435Y654253D01*
G01X113745Y655631D02*
X112567Y654806D01*
G01X109058Y653856D02*
X108694Y654376D01*
G01X110062Y654079D02*
X109246Y655244D01*
G01X170179Y653956D02*
X169364Y655125D01*
G01X169175Y653734D02*
X168810Y654257D01*
G01X169364Y655125D02*
X167170Y655510D01*
G01D02*
X166002Y654693D01*
G01X168810Y654257D02*
X167393Y654506D01*
G01X167170Y655510D02*
X166002Y654693D01*
G01X167393Y654506D02*
X166870Y654140D01*
G01X163501Y653972D02*
X162684Y655138D01*
G01X162497Y653749D02*
X162132Y654270D01*
G01X162684Y655138D02*
X160492Y655523D01*
G01D02*
X159323Y654708D01*
G01X162132Y654270D02*
X160714Y654519D01*
G01X160492Y655523D02*
X159323Y654708D01*
G01X160714Y654519D02*
X160191Y654154D01*
G01X156816Y653952D02*
X155999Y655118D01*
G01X155812Y653729D02*
X155447Y654250D01*
G01X155999Y655118D02*
X153806Y655503D01*
G01D02*
X152638Y654686D01*
G01X155447Y654250D02*
X154029Y654499D01*
G01X153806Y655503D02*
X152638Y654686D01*
G01X154029Y654499D02*
X153506Y654133D01*
G01X150136Y653974D02*
X149320Y655141D01*
G01X149132Y653752D02*
X148767Y654273D01*
G01X149320Y655141D02*
X147128Y655526D01*
G01D02*
X145959Y654709D01*
G01X148767Y654273D02*
X147350Y654522D01*
G01X147128Y655526D02*
X145959Y654709D01*
G01X147350Y654522D02*
X146827Y654156D01*
G01X143455Y653973D02*
X142638Y655139D01*
G01X142451Y653750D02*
X142086Y654271D01*
G01X142638Y655139D02*
X140447Y655523D01*
G01D02*
X139278Y654706D01*
G01X142086Y654271D02*
X140670Y654519D01*
G01X140447Y655523D02*
X139278Y654706D01*
G01X140670Y654519D02*
X140146Y654153D01*
G01X136771Y653957D02*
X135956Y655126D01*
G01X135767Y653735D02*
X135402Y654258D01*
G01X135956Y655126D02*
X133763Y655511D01*
G01D02*
X132595Y654694D01*
G01X135402Y654258D02*
X133986Y654507D01*
G01X133763Y655511D02*
X132595Y654694D01*
G01X133986Y654507D02*
X133463Y654141D01*
G01X130104Y654050D02*
X129287Y655217D01*
G01X129100Y653827D02*
X128735Y654349D01*
G01X129287Y655217D02*
X127092Y655602D01*
G01D02*
X125927Y654787D01*
G01X128735Y654349D02*
X127315Y654598D01*
G01X127092Y655602D02*
X125927Y654787D01*
G01X127315Y654598D02*
X126795Y654234D01*
G01X123426Y654083D02*
X122613Y655249D01*
G01X122422Y653861D02*
X122059Y654381D01*
G01X122613Y655249D02*
X120415Y655635D01*
G01D02*
X119250Y654820D01*
G01X122059Y654381D02*
X120638Y654631D01*
G01X120415Y655635D02*
X119250Y654820D01*
G01X120638Y654631D02*
X120118Y654267D01*
G01X116745Y654069D02*
X115916Y655248D01*
G01X115740Y653845D02*
X115364Y654380D01*
G01X115916Y655248D02*
X113745Y655631D01*
G01D02*
X112567Y654806D01*
G01X115364Y654380D02*
X113968Y654626D01*
G01X113745Y655631D02*
X112567Y654806D01*
G01X113968Y654626D02*
X113435Y654253D01*
G01X110062Y654079D02*
X109246Y655244D01*
G01X109058Y653856D02*
X108694Y654376D01*
G01X274858Y446443D02*
X212270Y458961D01*
G01X274858Y447413D02*
X212410Y459902D01*
G01X212270Y458961D02*
X176891Y462445D01*
G01X274858Y447413D02*
X212410Y459902D01*
G01X274858Y446443D02*
X212270Y458961D01*
G01D02*
X176891Y462445D01*
G01X273474Y450605D02*
X210706Y463159D01*
G01X273474Y451575D02*
X210846Y464100D01*
G01X273474Y451575D02*
X210846Y464100D01*
G01X273474Y450605D02*
X210706Y463159D01*
G01X209771Y435904D02*
X330238Y411827D01*
G01X209631Y434963D02*
X330238Y410858D01*
G01X208331Y443095D02*
X329084Y418955D01*
G01Y419924D02*
X208471Y444036D01*
G01X330675Y403848D02*
X213368Y427295D01*
G01X330675Y403848D02*
X213368Y427295D01*
G01X271836Y414639D02*
X213228Y426354D01*
G01X330675Y403848D02*
X213368Y427295D01*
G01X330675Y403848D02*
X213368Y427295D01*
G01X271836Y414639D02*
X213228Y426354D01*
G01X210528Y431835D02*
X270397Y419868D01*
G01X210388Y430894D02*
X330268Y406929D01*
G01X209631Y434963D02*
X330238Y410858D01*
G01X209771Y435904D02*
X330238Y411827D01*
G01X329084Y419924D02*
X208471Y444036D01*
G01X208331Y443095D02*
X329084Y418955D01*
G01X271836Y414639D02*
X213228Y426354D01*
G01X330675Y403848D02*
X213368Y427295D01*
G01X271836Y414639D02*
X213228Y426354D01*
G01X330675Y403848D02*
X213368Y427295D01*
G01X210388Y430894D02*
X330268Y406929D01*
G01X210528Y431835D02*
X270397Y419868D01*
G01X210388Y430894D02*
X330268Y406929D01*
G01X277963Y442308D02*
X210321Y455687D01*
G01X277964Y441339D02*
X210182Y454746D01*
G01X209631Y450815D02*
X328513Y427057D01*
G01Y428026D02*
X209771Y451756D01*
G01X209631Y450815D02*
X328513Y427057D01*
G01Y428026D02*
X209771Y451756D01*
G01Y435904D02*
X330238Y411827D01*
G01X209631Y434963D02*
X330238Y410858D01*
G01X209175Y447918D02*
X329286Y423911D01*
G01X209035Y446977D02*
X329286Y422942D01*
G01X208331Y443095D02*
X329084Y418955D01*
G01Y419924D02*
X208471Y444036D01*
G01X210195Y439725D02*
X329926Y415793D01*
G01X210055Y438784D02*
X329926Y414824D01*
G01X210195Y439725D02*
X329926Y415793D01*
G01X210055Y438784D02*
X329926Y414824D01*
G01X277964Y441339D02*
X210182Y454746D01*
G01X277963Y442308D02*
X210321Y455687D01*
G01X328513Y428026D02*
X209771Y451756D01*
G01X209631Y450815D02*
X328513Y427057D01*
G01Y428026D02*
X209771Y451756D01*
G01X209631Y450815D02*
X328513Y427057D01*
G01X209631Y434963D02*
X330238Y410858D01*
G01X209771Y435904D02*
X330238Y411827D01*
G01X209035Y446977D02*
X329286Y422942D01*
G01X209175Y447918D02*
X329286Y423911D01*
G01X329084Y419924D02*
X208471Y444036D01*
G01X208331Y443095D02*
X329084Y418955D01*
G01X210055Y438784D02*
X329926Y414824D01*
G01X210195Y439725D02*
X329926Y415793D01*
G01X277963Y442308D02*
X210321Y455687D01*
G01X277964Y441339D02*
X210182Y454746D01*
G01X209175Y447918D02*
X329286Y423911D01*
G01X209035Y446977D02*
X329286Y422942D01*
G01X210528Y431835D02*
X270397Y419868D01*
G01X210388Y430894D02*
X330268Y406929D01*
G01X277964Y441339D02*
X210182Y454746D01*
G01X277963Y442308D02*
X210321Y455687D01*
G01X209035Y446977D02*
X329286Y422942D01*
G01X209175Y447918D02*
X329286Y423911D01*
G01X210055Y438784D02*
X329926Y414824D01*
G01X210195Y439725D02*
X329926Y415793D01*
G01X210388Y430894D02*
X330268Y406929D01*
G01X210528Y431835D02*
X270397Y419868D01*
G01X210388Y430894D02*
X330268Y406929D01*
G01X189999Y486255D02*
X190000D01*
G01D02*
X237674Y481559D01*
G01X189999Y486255D02*
X190000D01*
G01D02*
X237674Y481559D01*
G01X205190Y649136D02*
X203139D01*
G01D02*
X198869Y649466D01*
G01D02*
X194009Y648653D01*
G01X198827Y650423D02*
X193498Y649531D01*
G01X194009Y648653D02*
X192248Y646487D01*
G01X193498Y649531D02*
X191355Y646895D01*
G01X192248Y646487D02*
X191886Y644432D01*
G01X191355Y646895D02*
X191018Y644986D01*
G01X191886Y644432D02*
X190720Y643619D01*
G01X191018Y644986D02*
X190498Y644623D01*
G01X191886Y644432D02*
X190720Y643619D01*
G01D02*
X188526Y644005D01*
G01X190498Y644623D02*
X189079Y644873D01*
G01X188526Y644005D02*
X187710Y645170D01*
G01X189079Y644873D02*
X188714Y645393D01*
G01X187710Y645170D02*
X189236Y653825D01*
G01X188714Y645393D02*
X190240Y654048D01*
G01X186929Y654229D02*
X185220Y644528D01*
G01X186061Y654782D02*
X184352Y645081D01*
G01X185220Y644528D02*
X184055Y643712D01*
G01X184352Y645081D02*
X183832Y644717D01*
G01X185220Y644528D02*
X184055Y643712D01*
G01D02*
X181861Y644099D01*
G01X183832Y644717D02*
X182414Y644967D01*
G01X181861Y644099D02*
X181045Y645265D01*
G01X182414Y644967D02*
X182050Y645488D01*
G01X181045Y645265D02*
X182556Y653837D01*
G01X182050Y645488D02*
X183560Y654059D01*
G01X180251Y654243D02*
X178539Y644526D01*
G01X179383Y654796D02*
X177671Y645079D01*
G01X178539Y644526D02*
X177373Y643710D01*
G01X177671Y645079D02*
X177151Y644715D01*
G01X178539Y644526D02*
X177373Y643710D01*
G01D02*
X175179Y644097D01*
G01X177151Y644715D02*
X175732Y644965D01*
G01X175179Y644097D02*
X174363Y645261D01*
G01X175732Y644965D02*
X175367Y645484D01*
G01X174363Y645261D02*
X175860Y653756D01*
G01X175367Y645484D02*
X176864Y653978D01*
G01X173553Y654160D02*
X171855Y644514D01*
G01X172685Y654714D02*
X170987Y645067D01*
G01X171855Y644514D02*
X170690Y643698D01*
G01X170987Y645067D02*
X170467Y644702D01*
G01X171855Y644514D02*
X170690Y643698D01*
G01X205190Y649136D02*
X203139D01*
G01D02*
X198869Y649466D01*
G01X198827Y650423D02*
X193498Y649531D01*
G01X198869Y649466D02*
X194009Y648653D01*
G01X193498Y649531D02*
X191355Y646895D01*
G01X194009Y648653D02*
X192248Y646487D01*
G01X191355Y646895D02*
X191018Y644986D01*
G01X192248Y646487D02*
X191886Y644432D01*
G01X191018Y644986D02*
X190498Y644623D01*
G01D02*
X189079Y644873D01*
G01X191886Y644432D02*
X190720Y643619D01*
G01X190498Y644623D02*
X189079Y644873D01*
G01X190720Y643619D02*
X188526Y644005D01*
G01X189079Y644873D02*
X188714Y645393D01*
G01X188526Y644005D02*
X187710Y645170D01*
G01X188714Y645393D02*
X190240Y654048D01*
G01X187710Y645170D02*
X189236Y653825D01*
G01X186061Y654782D02*
X184352Y645081D01*
G01X186929Y654229D02*
X185220Y644528D01*
G01X184352Y645081D02*
X183832Y644717D01*
G01D02*
X182414Y644967D01*
G01X185220Y644528D02*
X184055Y643712D01*
G01X183832Y644717D02*
X182414Y644967D01*
G01X184055Y643712D02*
X181861Y644099D01*
G01X182414Y644967D02*
X182050Y645488D01*
G01X181861Y644099D02*
X181045Y645265D01*
G01X182050Y645488D02*
X183560Y654059D01*
G01X181045Y645265D02*
X182556Y653837D01*
G01X179383Y654796D02*
X177671Y645079D01*
G01X180251Y654243D02*
X178539Y644526D01*
G01X177671Y645079D02*
X177151Y644715D01*
G01D02*
X175732Y644965D01*
G01X178539Y644526D02*
X177373Y643710D01*
G01X177151Y644715D02*
X175732Y644965D01*
G01X177373Y643710D02*
X175179Y644097D01*
G01X175732Y644965D02*
X175367Y645484D01*
G01X175179Y644097D02*
X174363Y645261D01*
G01X175367Y645484D02*
X176864Y653978D01*
G01X174363Y645261D02*
X175860Y653756D01*
G01X172685Y654714D02*
X170987Y645067D01*
G01X173553Y654160D02*
X171855Y644514D01*
G01X170987Y645067D02*
X170467Y644702D01*
G01X171855Y644514D02*
X170690Y643698D01*
G01X205190Y650086D02*
X203176D01*
G01D02*
X198827Y650423D01*
G01X189236Y653825D02*
X188871Y654346D01*
G01X190240Y654048D02*
X189423Y655214D01*
G01X188871Y654346D02*
X187452Y654595D01*
G01X189423Y655214D02*
X187229Y655599D01*
G01X188871Y654346D02*
X187452Y654595D01*
G01D02*
X186929Y654229D01*
G01X187229Y655599D02*
X186061Y654782D01*
G01X182556Y653837D02*
X182191Y654360D01*
G01X183560Y654059D02*
X182745Y655228D01*
G01X182191Y654360D02*
X180774Y654609D01*
G01X182745Y655228D02*
X180551Y655613D01*
G01X182191Y654360D02*
X180774Y654609D01*
G01D02*
X180251Y654243D01*
G01X180551Y655613D02*
X179383Y654796D01*
G01X175860Y653756D02*
X175496Y654277D01*
G01X176864Y653978D02*
X176049Y655145D01*
G01X175496Y654277D02*
X174076Y654525D01*
G01X176049Y655145D02*
X173853Y655529D01*
G01X175496Y654277D02*
X174076Y654525D01*
G01D02*
X173553Y654160D01*
G01X173853Y655529D02*
X172685Y654714D01*
G01X205190Y650086D02*
X203176D01*
G01D02*
X198827Y650423D01*
G01X190240Y654048D02*
X189423Y655214D01*
G01X189236Y653825D02*
X188871Y654346D01*
G01X189423Y655214D02*
X187229Y655599D01*
G01D02*
X186061Y654782D01*
G01X188871Y654346D02*
X187452Y654595D01*
G01X187229Y655599D02*
X186061Y654782D01*
G01X187452Y654595D02*
X186929Y654229D01*
G01X183560Y654059D02*
X182745Y655228D01*
G01X182556Y653837D02*
X182191Y654360D01*
G01X182745Y655228D02*
X180551Y655613D01*
G01D02*
X179383Y654796D01*
G01X182191Y654360D02*
X180774Y654609D01*
G01X180551Y655613D02*
X179383Y654796D01*
G01X180774Y654609D02*
X180251Y654243D01*
G01X176864Y653978D02*
X176049Y655145D01*
G01X175860Y653756D02*
X175496Y654277D01*
G01X176049Y655145D02*
X173853Y655529D01*
G01D02*
X172685Y654714D01*
G01X175496Y654277D02*
X174076Y654525D01*
G01X173853Y655529D02*
X172685Y654714D01*
G01X174076Y654525D02*
X173553Y654160D01*
G01X320971Y455665D02*
X274858Y446443D01*
G01X320971Y456634D02*
X274858Y447412D01*
G01X320971Y456634D02*
X274858Y447412D01*
G01X320971Y455665D02*
X274858Y446443D01*
G01X290178Y459892D02*
X323832Y466623D01*
G01Y465654D02*
X290178Y458923D01*
G01X257765Y466374D02*
X290178Y459892D01*
G01Y458923D02*
X257965Y465365D01*
G01X256121Y463291D02*
X256581Y465585D01*
G01X257436Y465012D02*
X257131Y463491D01*
G01X256912Y462107D02*
X256121Y463291D01*
G01X257131Y463491D02*
X257484Y462962D01*
G01X272759Y458938D02*
X256912Y462107D01*
G01X257484Y462962D02*
X273332Y459793D01*
G01X273111Y458410D02*
X272759Y458938D01*
G01X273332Y459793D02*
X274121Y458610D01*
G01X272805Y456884D02*
X273111Y458410D01*
G01X274121Y458610D02*
X273660Y456311D01*
G01X272277Y456531D02*
X272805Y456884D01*
G01X273660Y456311D02*
X272477Y455522D01*
G01X253477Y460292D02*
X272277Y456531D01*
G01X272477Y455522D02*
X252904Y459437D01*
G01X253124Y460820D02*
X253477Y460292D01*
G01X252904Y459437D02*
X252115Y460620D01*
G01X254175Y466067D02*
X253124Y460820D01*
G01X252115Y460620D02*
X253166Y465867D01*
G01X251345Y466690D02*
X239150Y464251D01*
G01X322337Y460379D02*
X273474Y450605D01*
G01X322337Y461348D02*
X273474Y451574D01*
G01X291169Y463515D02*
X326468Y470575D01*
G01Y471544D02*
X291169Y464484D01*
G01X252751Y471199D02*
X291169Y463515D01*
G01Y464484D02*
X252751Y472168D01*
G01X251345Y466690D02*
X239150Y464251D01*
G01X252115Y460620D02*
X253166Y465867D01*
G01X254175Y466067D02*
X253124Y460820D01*
G01X252904Y459437D02*
X252115Y460620D01*
G01X253124Y460820D02*
X253477Y460292D01*
G01X272477Y455522D02*
X252904Y459437D01*
G01X253477Y460292D02*
X272277Y456531D01*
G01X273660Y456311D02*
X272477Y455522D01*
G01X272277Y456531D02*
X272805Y456884D01*
G01X274121Y458610D02*
X273660Y456311D01*
G01X272805Y456884D02*
X273111Y458410D01*
G01X273332Y459793D02*
X274121Y458610D01*
G01X273111Y458410D02*
X272759Y458938D01*
G01X257484Y462962D02*
X273332Y459793D01*
G01X272759Y458938D02*
X256912Y462107D01*
G01X257131Y463491D02*
X257484Y462962D01*
G01X256912Y462107D02*
X256121Y463291D01*
G01X257436Y465012D02*
X257131Y463491D01*
G01X256121Y463291D02*
X256581Y465585D01*
G01X290178Y458923D02*
X257965Y465365D01*
G01X257765Y466374D02*
X290178Y459892D01*
G01X323832Y465654D02*
X290178Y458923D01*
G01Y459892D02*
X323832Y466623D01*
G01X322337Y461348D02*
X273474Y451574D01*
G01X322337Y460379D02*
X273474Y450605D01*
G01X291169Y464484D02*
X252751Y472168D01*
G01Y471199D02*
X291169Y463515D01*
G01X326468Y471544D02*
X291169Y464484D01*
G01Y463515D02*
X326468Y470575D01*
G01X330675Y402879D02*
X271836Y414639D01*
G01X330675Y402879D02*
X271836Y414639D01*
G01X270397Y419867D02*
X330268Y407898D01*
G01X330675Y402879D02*
X271836Y414639D01*
G01X330675Y402879D02*
X271836Y414639D01*
G01X270397Y419867D02*
X330268Y407898D01*
G01X324149Y451547D02*
X277963Y442308D01*
G01X324149Y450578D02*
X277964Y441339D01*
G01X324149Y450578D02*
X277964Y441339D01*
G01X324149Y451547D02*
X277963Y442308D01*
G01X324149Y451547D02*
X277963Y442308D01*
G01X324149Y450578D02*
X277964Y441339D01*
G01X270397Y419867D02*
X330268Y407898D01*
G01X324149Y450578D02*
X277964Y441339D01*
G01X324149Y451547D02*
X277963Y442308D01*
G01X270397Y419867D02*
X330268Y407898D01*
G01X256581Y465585D02*
X257765Y466374D01*
G01X257965Y465365D02*
X257436Y465012D01*
G01X253386Y467251D02*
X254175Y466067D01*
G01X253166Y465867D02*
X252813Y466396D01*
G01X251345Y467659D02*
X253386Y467251D01*
G01X252813Y466396D02*
X251345Y466690D01*
G01X239102Y465211D02*
X251345Y467659D01*
G01X323448Y479053D02*
X291471Y472658D01*
G01X323448Y480022D02*
X291471Y473627D01*
G01Y472658D02*
X254790Y479995D01*
G01X291471Y473627D02*
X254790Y480964D01*
G01Y479995D02*
X237310Y476498D01*
G01X254790Y480964D02*
X237262Y477458D01*
G01X291047Y477790D02*
X323151Y484210D01*
G01Y483241D02*
X291047Y476821D01*
G01X254937Y485011D02*
X291047Y477790D01*
G01Y476821D02*
X254937Y484042D01*
G01X237674Y481559D02*
X254937Y485011D01*
G01Y484042D02*
X246330Y482321D01*
G01X237674Y481559D02*
X254937Y485011D01*
G01X246330Y482321D02*
X237722Y480599D01*
G01X323815Y487448D02*
X290838Y480852D01*
G01X323815Y488417D02*
X290838Y481821D01*
G01Y480852D02*
X254556Y488107D01*
G01X290838Y481821D02*
X254556Y489076D01*
G01Y488107D02*
X237729Y484742D01*
G01X254556Y489076D02*
X237681Y485702D01*
G01X237842Y468216D02*
X245295Y469706D01*
G01Y469707D02*
X252751Y471199D01*
G01Y472168D02*
X237794Y469176D01*
G01X324967Y475793D02*
X291308Y469061D01*
G01X324967Y474824D02*
X291308Y468092D01*
G01Y469061D02*
X253190Y476684D01*
G01X291308Y468092D02*
X253190Y475715D01*
G01Y476684D02*
X236849Y473416D01*
G01X253190Y475715D02*
X236897Y472456D01*
G01X239102Y465211D02*
X251345Y467659D01*
G01X252813Y466396D02*
X251345Y466690D01*
G01Y467659D02*
X253386Y467251D01*
G01X253166Y465867D02*
X252813Y466396D01*
G01X253386Y467251D02*
X254175Y466067D01*
G01X257965Y465365D02*
X257436Y465012D01*
G01X256581Y465585D02*
X257765Y466374D01*
G01X323448Y480022D02*
X291471Y473627D01*
G01X323448Y479053D02*
X291471Y472658D01*
G01Y473627D02*
X254790Y480964D01*
G01X291471Y472658D02*
X254790Y479995D01*
G01Y480964D02*
X237262Y477458D01*
G01X254790Y479995D02*
X237310Y476498D01*
G01X254937Y484042D02*
X246330Y482321D01*
G01D02*
X237722Y480599D01*
G01X237674Y481559D02*
X254937Y485011D01*
G01X291047Y476821D02*
X254937Y484042D01*
G01Y485011D02*
X291047Y477790D01*
G01X323151Y483241D02*
X291047Y476821D01*
G01Y477790D02*
X323151Y484210D01*
G01X323815Y488417D02*
X290838Y481821D01*
G01X323815Y487448D02*
X290838Y480852D01*
G01Y481821D02*
X254556Y489076D01*
G01X290838Y480852D02*
X254556Y488107D01*
G01Y489076D02*
X237681Y485702D01*
G01X254556Y488107D02*
X237729Y484742D01*
G01X252751Y472168D02*
X237794Y469176D01*
G01X237842Y468216D02*
X245295Y469706D01*
G01X252751Y472168D02*
X237794Y469176D01*
G01X245295Y469707D02*
X252751Y471199D01*
G01X324967Y474824D02*
X291308Y468092D01*
G01X324967Y475793D02*
X291308Y469061D01*
G01Y468092D02*
X253190Y475715D01*
G01X291308Y469061D02*
X253190Y476684D01*
G01Y475715D02*
X236897Y472456D01*
G01X253190Y476684D02*
X236849Y473416D01*
G01X323815Y487448D02*
X290838Y480852D01*
G01X323815Y488417D02*
X290838Y481821D01*
G01Y480852D02*
X254556Y488107D01*
G01X290838Y481821D02*
X254556Y489076D01*
G01Y488107D02*
X237729Y484742D01*
G01X254556Y489076D02*
X237681Y485702D01*
G01X323815Y488417D02*
X290838Y481821D01*
G01X323815Y487448D02*
X290838Y480852D01*
G01Y481821D02*
X254556Y489076D01*
G01X290838Y480852D02*
X254556Y488107D01*
G01Y489076D02*
X237681Y485702D01*
G01X254556Y488107D02*
X237729Y484742D01*
G01X350504Y406844D02*
X330675Y402879D01*
G01X350504Y406844D02*
X330675Y402879D01*
G01X350504Y406844D02*
X330675Y402879D01*
G01X350504Y406844D02*
X330675Y402879D01*
G01X356683Y448522D02*
X320971Y455665D01*
G01X356683Y449491D02*
X320971Y456634D01*
G01X356683Y449491D02*
X320971Y456634D01*
G01X356683Y448522D02*
X320971Y455665D01*
G01X323832Y466623D02*
X357500Y459890D01*
G01Y458921D02*
X323832Y465654D01*
G01X357861Y453274D02*
X322337Y460379D01*
G01X357861Y454243D02*
X322337Y461348D01*
G01X357500Y458921D02*
X323832Y465654D01*
G01Y466623D02*
X357500Y459890D01*
G01X357861Y454243D02*
X322337Y461348D01*
G01X357861Y453274D02*
X322337Y460379D01*
G01X330238Y411827D02*
X345058Y414798D01*
G01X330238Y410858D02*
X345429Y413903D01*
G01X345058Y414798D02*
X350806Y418631D01*
G01X345429Y413903D02*
X351177Y417736D01*
G01X350806Y418631D02*
X384980Y425464D01*
G01X351177Y417736D02*
X384980Y424495D01*
G01X348585Y426282D02*
X382960Y433157D01*
G01Y434126D02*
X348214Y427177D01*
G01X341243Y421387D02*
X348585Y426282D01*
G01X348214Y427177D02*
X340872Y422282D01*
G01X329084Y418955D02*
X341243Y421387D01*
G01X340872Y422282D02*
X329084Y419924D01*
G01X356239Y411809D02*
X350133Y407739D01*
G01X356610Y410914D02*
X350504Y406844D01*
G01X350133Y407739D02*
X330675Y403848D01*
G01X356239Y411809D02*
X350133Y407739D01*
G01X356610Y410914D02*
X350504Y406844D01*
G01X350133Y407739D02*
X330675Y403848D01*
G01X330268Y407898D02*
X348106Y411464D01*
G01X330268Y406929D02*
X348477Y410569D01*
G01X348106Y411464D02*
X353991Y415388D01*
G01X348477Y410569D02*
X354362Y414493D01*
G01X353991Y415388D02*
X382999Y421188D01*
G01X354362Y414493D02*
X382999Y420219D01*
G01X330238Y410858D02*
X345429Y413903D01*
G01X330238Y411827D02*
X345058Y414798D01*
G01X345429Y413903D02*
X351177Y417736D01*
G01X345058Y414798D02*
X350806Y418631D01*
G01X351177Y417736D02*
X384980Y424495D01*
G01X350806Y418631D02*
X384980Y425464D01*
G01X340872Y422282D02*
X329084Y419924D01*
G01Y418955D02*
X341243Y421387D01*
G01X348214Y427177D02*
X340872Y422282D01*
G01X341243Y421387D02*
X348585Y426282D01*
G01X382960Y434126D02*
X348214Y427177D01*
G01X348585Y426282D02*
X382960Y433157D01*
G01X356610Y410914D02*
X350504Y406844D01*
G01X356239Y411809D02*
X350133Y407739D01*
G01D02*
X330675Y403848D01*
G01X356610Y410914D02*
X350504Y406844D01*
G01X356239Y411809D02*
X350133Y407739D01*
G01D02*
X330675Y403848D01*
G01X330268Y406929D02*
X348477Y410569D01*
G01X330268Y407898D02*
X348106Y411464D01*
G01X348477Y410569D02*
X354362Y414493D01*
G01X348106Y411464D02*
X353991Y415388D01*
G01X354362Y414493D02*
X382999Y420219D01*
G01X353991Y415388D02*
X382999Y421188D01*
G01X359911Y444394D02*
X324149Y451547D01*
G01X359911Y443425D02*
X324149Y450578D01*
G01X344509Y434494D02*
X382812Y442156D01*
G01X344509Y434494D02*
X382812Y442156D01*
G01X353667Y437295D02*
X352343Y437030D01*
G01X344509Y434494D02*
X382812Y442156D01*
G01X350137Y436589D02*
X344138Y435389D01*
G01X335429Y428440D02*
X344509Y434494D01*
G01X344138Y435389D02*
X335058Y429335D01*
G01X328513Y427057D02*
X335429Y428440D01*
G01X335058Y429335D02*
X328513Y428026D01*
G01X344509Y434494D02*
X382812Y442156D01*
G01X344509Y434494D02*
X382812Y442156D01*
G01X353667Y437295D02*
X352343Y437030D01*
G01X344509Y434494D02*
X382812Y442156D01*
G01X350137Y436589D02*
X344138Y435389D01*
G01X335429Y428440D02*
X344509Y434494D01*
G01X344138Y435389D02*
X335058Y429335D01*
G01X328513Y427057D02*
X335429Y428440D01*
G01X335058Y429335D02*
X328513Y428026D01*
G01X330238Y411827D02*
X345058Y414798D01*
G01X330238Y410858D02*
X345429Y413903D01*
G01X345058Y414798D02*
X350806Y418631D01*
G01X345429Y413903D02*
X351177Y417736D01*
G01X350806Y418631D02*
X384980Y425464D01*
G01X351177Y417736D02*
X384980Y424495D01*
G01X329286Y423911D02*
X338342Y425721D01*
G01X329286Y422942D02*
X338713Y424826D01*
G01X338342Y425721D02*
X346250Y430993D01*
G01X338713Y424826D02*
X346621Y430098D01*
G01X346250Y430993D02*
X383411Y438424D01*
G01X346621Y430098D02*
X383411Y437455D01*
G01X348585Y426282D02*
X382960Y433157D01*
G01Y434126D02*
X348214Y427177D01*
G01X341243Y421387D02*
X348585Y426282D01*
G01X348214Y427177D02*
X340872Y422282D01*
G01X329084Y418955D02*
X341243Y421387D01*
G01X340872Y422282D02*
X329084Y419924D01*
G01X329926Y415793D02*
X342546Y418319D01*
G01X329926Y414824D02*
X342917Y417424D01*
G01X342546Y418319D02*
X349564Y423000D01*
G01X342917Y417424D02*
X349935Y422105D01*
G01X349564Y423000D02*
X383158Y429718D01*
G01X349935Y422105D02*
X359955Y424109D01*
G01X349564Y423000D02*
X383158Y429718D01*
G01X349564Y423000D02*
X383158Y429718D01*
G01X329926Y415793D02*
X342546Y418319D01*
G01X329926Y414824D02*
X342917Y417424D01*
G01X342546Y418319D02*
X349564Y423000D01*
G01X342917Y417424D02*
X349935Y422105D01*
G01X349564Y423000D02*
X383158Y429718D01*
G01X349935Y422105D02*
X359955Y424109D01*
G01X349564Y423000D02*
X383158Y429718D01*
G01X349564Y423000D02*
X383158Y429718D01*
G01X359911Y443425D02*
X324149Y450578D01*
G01X359911Y444394D02*
X324149Y451547D01*
G01X335058Y429335D02*
X328513Y428026D01*
G01Y427057D02*
X335429Y428440D01*
G01X344138Y435389D02*
X335058Y429335D01*
G01X335429Y428440D02*
X344509Y434494D01*
G01X353667Y437295D02*
X352343Y437030D01*
G01X350137Y436589D02*
X344138Y435389D01*
G01X344509Y434494D02*
X382812Y442156D01*
G01X335058Y429335D02*
X328513Y428026D01*
G01Y427057D02*
X335429Y428440D01*
G01X344138Y435389D02*
X335058Y429335D01*
G01X335429Y428440D02*
X344509Y434494D01*
G01X353667Y437295D02*
X352343Y437030D01*
G01X350137Y436589D02*
X344138Y435389D01*
G01X344509Y434494D02*
X382812Y442156D01*
G01X330238Y410858D02*
X345429Y413903D01*
G01X330238Y411827D02*
X345058Y414798D01*
G01X345429Y413903D02*
X351177Y417736D01*
G01X345058Y414798D02*
X350806Y418631D01*
G01X351177Y417736D02*
X384980Y424495D01*
G01X350806Y418631D02*
X384980Y425464D01*
G01X329286Y422942D02*
X338713Y424826D01*
G01X329286Y423911D02*
X338342Y425721D01*
G01X338713Y424826D02*
X346621Y430098D01*
G01X338342Y425721D02*
X346250Y430993D01*
G01X346621Y430098D02*
X383411Y437455D01*
G01X346250Y430993D02*
X383411Y438424D01*
G01X340872Y422282D02*
X329084Y419924D01*
G01Y418955D02*
X341243Y421387D01*
G01X348214Y427177D02*
X340872Y422282D01*
G01X341243Y421387D02*
X348585Y426282D01*
G01X382960Y434126D02*
X348214Y427177D01*
G01X348585Y426282D02*
X382960Y433157D01*
G01X329926Y414824D02*
X342917Y417424D01*
G01X329926Y415793D02*
X342546Y418319D01*
G01X342917Y417424D02*
X349935Y422105D01*
G01X342546Y418319D02*
X349564Y423000D01*
G01X349935Y422105D02*
X359955Y424109D01*
G01X349564Y423000D02*
X383158Y429718D01*
G01X359911Y444394D02*
X324149Y451547D01*
G01X359911Y443425D02*
X324149Y450578D01*
G01X329286Y423911D02*
X338342Y425721D01*
G01X329286Y422942D02*
X338713Y424826D01*
G01X338342Y425721D02*
X346250Y430993D01*
G01X338713Y424826D02*
X346621Y430098D01*
G01X346250Y430993D02*
X383411Y438424D01*
G01X346621Y430098D02*
X383411Y437455D01*
G01X330268Y407898D02*
X348106Y411464D01*
G01X330268Y406929D02*
X348477Y410569D01*
G01X348106Y411464D02*
X353991Y415388D01*
G01X348477Y410569D02*
X354362Y414493D01*
G01X353991Y415388D02*
X382999Y421188D01*
G01X354362Y414493D02*
X382999Y420219D01*
G01X359911Y443425D02*
X324149Y450578D01*
G01X359911Y444394D02*
X324149Y451547D01*
G01X329286Y422942D02*
X338713Y424826D01*
G01X329286Y423911D02*
X338342Y425721D01*
G01X338713Y424826D02*
X346621Y430098D01*
G01X338342Y425721D02*
X346250Y430993D01*
G01X346621Y430098D02*
X383411Y437455D01*
G01X346250Y430993D02*
X383411Y438424D01*
G01X329926Y414824D02*
X342917Y417424D01*
G01X329926Y415793D02*
X342546Y418319D01*
G01X342917Y417424D02*
X349935Y422105D01*
G01X342546Y418319D02*
X349564Y423000D01*
G01X349935Y422105D02*
X359955Y424109D01*
G01X349564Y423000D02*
X383158Y429718D01*
G01X330268Y406929D02*
X348477Y410569D01*
G01X330268Y407898D02*
X348106Y411464D01*
G01X348477Y410569D02*
X354362Y414493D01*
G01X348106Y411464D02*
X353991Y415388D01*
G01X354362Y414493D02*
X382999Y420219D01*
G01X353991Y415388D02*
X382999Y421188D01*
G01X355771Y472589D02*
X323448Y479053D01*
G01X355771Y473558D02*
X323448Y480022D01*
G01X323151Y484210D02*
X355286Y477783D01*
G01Y476814D02*
X323151Y483241D01*
G01X356033Y481004D02*
X323815Y487448D01*
G01X356033Y481973D02*
X323815Y488417D01*
G01X326468Y470575D02*
X359256Y464018D01*
G01Y464987D02*
X326468Y471544D01*
G01X357761Y469234D02*
X324967Y475793D01*
G01X357761Y468265D02*
X324967Y474824D01*
G01X355771Y473558D02*
X323448Y480022D01*
G01X355771Y472589D02*
X323448Y479053D01*
G01X355286Y476814D02*
X323151Y483241D01*
G01Y484210D02*
X355286Y477783D01*
G01X356033Y481973D02*
X323815Y488417D01*
G01X356033Y481004D02*
X323815Y487448D01*
G01X359256Y464987D02*
X326468Y471544D01*
G01Y470575D02*
X359256Y464018D01*
G01X357761Y468265D02*
X324967Y474824D01*
G01X357761Y469234D02*
X324967Y475793D01*
G01X356033Y481004D02*
X323815Y487448D01*
G01X356033Y481973D02*
X323815Y488417D01*
G01X356033Y481973D02*
X323815Y488417D01*
G01X356033Y481004D02*
X323815Y487448D01*
G01X420925Y450414D02*
X414376Y449104D01*
G01X432541Y453706D02*
X414376Y450073D01*
G01Y449104D02*
X412192Y449541D01*
G01X409986Y449982D02*
X386987Y454582D01*
G01X414376Y450073D02*
X386987Y455551D01*
G01Y454582D02*
X356683Y448522D01*
G01X386987Y455551D02*
X356683Y449491D01*
G01X432541Y453706D02*
X414376Y450073D01*
G01X432541Y453706D02*
X414376Y450073D01*
G01X432541Y453706D02*
X414376Y450073D01*
G01X432541Y453706D02*
X414376Y450073D01*
G01X420925Y450414D02*
X414376Y449104D01*
G01Y450073D02*
X386987Y455551D01*
G01X414376Y449104D02*
X412192Y449541D01*
G01X414376Y450073D02*
X386987Y455551D01*
G01X409986Y449982D02*
X386987Y454582D01*
G01Y455551D02*
X356683Y449491D01*
G01X386987Y454582D02*
X356683Y448522D01*
G01X405354Y460975D02*
X428691Y465642D01*
G01Y464673D02*
X405354Y460006D01*
G01X384142Y465218D02*
X405354Y460975D01*
G01Y460006D02*
X384142Y464249D01*
G01X357500Y459890D02*
X384142Y465218D01*
G01Y464249D02*
X357500Y458921D01*
G01X432264Y457882D02*
X411590Y453747D01*
G01X432264Y458851D02*
X411590Y454716D01*
G01Y453747D02*
X385908Y458883D01*
G01X411590Y454716D02*
X385908Y459852D01*
G01Y458883D02*
X357861Y453274D01*
G01X385908Y459852D02*
X357861Y454243D01*
G01X359256Y464018D02*
X383643Y468895D01*
G01X384142Y464249D02*
X357500Y458921D01*
G01Y459890D02*
X384142Y465218D01*
G01X405354Y460006D02*
X384142Y464249D01*
G01Y465218D02*
X405354Y460975D01*
G01X428691Y464673D02*
X405354Y460006D01*
G01Y460975D02*
X428691Y465642D01*
G01X432264Y458851D02*
X411590Y454716D01*
G01X432264Y457882D02*
X411590Y453747D01*
G01Y454716D02*
X385908Y459852D01*
G01X411590Y453747D02*
X385908Y458883D01*
G01Y459852D02*
X357861Y454243D01*
G01X385908Y458883D02*
X357861Y453274D01*
G01X359256Y464018D02*
X383643Y468895D01*
G01X384980Y425464D02*
X403977Y421665D01*
G01X384980Y424495D02*
X395921Y422307D01*
G01X384980Y425464D02*
X403977Y421665D01*
G01X398127Y421866D02*
X399451Y421601D01*
G01X384980Y425464D02*
X403977Y421665D01*
G01X401657Y421160D02*
X403977Y420696D01*
G01Y421665D02*
X416314Y424133D01*
G01X403977Y420696D02*
X416314Y423164D01*
G01Y424133D02*
X429627Y421469D01*
G01X416314Y423164D02*
X429627Y420500D01*
G01X416241Y431213D02*
X428705Y428720D01*
G01Y429689D02*
X416241Y432182D01*
G01X404459Y428857D02*
X416241Y431213D01*
G01Y432182D02*
X404459Y429826D01*
G01X382960Y433157D02*
X404459Y428857D01*
G01Y429826D02*
X382960Y434126D01*
G01X428975Y413358D02*
X415856Y415982D01*
G01X428975Y413358D02*
X415856Y415982D01*
G01X428975Y413358D02*
X415856Y415982D01*
G01X417180Y414748D02*
X415856Y415013D01*
G01Y415982D02*
X402090Y413228D01*
G01X415856Y415013D02*
X409150Y413671D01*
G01X415856Y415982D02*
X402090Y413228D01*
G01X406944Y413230D02*
X405620Y412965D01*
G01X415856Y415982D02*
X402090Y413228D01*
G01X403414Y412524D02*
X402090Y412259D01*
G01Y413228D02*
X382713Y417103D01*
G01X402090Y412259D02*
X391023Y414472D01*
G01X402090Y413228D02*
X382713Y417103D01*
G01X388817Y414913D02*
X387493Y415178D01*
G01X402090Y413228D02*
X382713Y417103D01*
G01X385287Y415619D02*
X382713Y416134D01*
G01Y417103D02*
X356239Y411809D01*
G01X382713Y416134D02*
X356610Y410914D01*
G01X428975Y413358D02*
X415856Y415982D01*
G01X428975Y413358D02*
X415856Y415982D01*
G01X428975Y413358D02*
X415856Y415982D01*
G01X417180Y414748D02*
X415856Y415013D01*
G01Y415982D02*
X402090Y413228D01*
G01X415856Y415013D02*
X409150Y413671D01*
G01X415856Y415982D02*
X402090Y413228D01*
G01X406944Y413230D02*
X405620Y412965D01*
G01X415856Y415982D02*
X402090Y413228D01*
G01X403414Y412524D02*
X402090Y412259D01*
G01Y413228D02*
X382713Y417103D01*
G01X402090Y412259D02*
X391023Y414472D01*
G01X402090Y413228D02*
X382713Y417103D01*
G01X388817Y414913D02*
X387493Y415178D01*
G01X402090Y413228D02*
X382713Y417103D01*
G01X385287Y415619D02*
X382713Y416134D01*
G01Y417103D02*
X356239Y411809D01*
G01X382713Y416134D02*
X356610Y410914D01*
G01X382999Y421188D02*
X402407Y417307D01*
G01X382999Y420219D02*
X402407Y416338D01*
G01Y417307D02*
X416658Y420157D01*
G01X402407Y416338D02*
X416658Y419188D01*
G01X384980Y424495D02*
X395921Y422307D01*
G01X398127Y421866D02*
X399451Y421601D01*
G01X401657Y421160D02*
X403977Y420696D01*
G01X384980Y425464D02*
X403977Y421665D01*
G01Y420696D02*
X416314Y423164D01*
G01X403977Y421665D02*
X416314Y424133D01*
G01Y423164D02*
X429627Y420500D01*
G01X416314Y424133D02*
X429627Y421469D01*
G01X404459Y429826D02*
X382960Y434126D01*
G01Y433157D02*
X404459Y428857D01*
G01X416241Y432182D02*
X404459Y429826D01*
G01Y428857D02*
X416241Y431213D01*
G01X428705Y429689D02*
X416241Y432182D01*
G01Y431213D02*
X428705Y428720D01*
G01X417180Y414748D02*
X415856Y415013D01*
G01X428975Y413358D02*
X415856Y415982D01*
G01Y415013D02*
X409150Y413671D01*
G01X406944Y413230D02*
X405620Y412965D01*
G01X403414Y412524D02*
X402090Y412259D01*
G01X415856Y415982D02*
X402090Y413228D01*
G01Y412259D02*
X391023Y414472D01*
G01X388817Y414913D02*
X387493Y415178D01*
G01X385287Y415619D02*
X382713Y416134D01*
G01X402090Y413228D02*
X382713Y417103D01*
G01Y416134D02*
X356610Y410914D01*
G01X382713Y417103D02*
X356239Y411809D01*
G01X417180Y414748D02*
X415856Y415013D01*
G01X428975Y413358D02*
X415856Y415982D01*
G01Y415013D02*
X409150Y413671D01*
G01X406944Y413230D02*
X405620Y412965D01*
G01X403414Y412524D02*
X402090Y412259D01*
G01X415856Y415982D02*
X402090Y413228D01*
G01Y412259D02*
X391023Y414472D01*
G01X388817Y414913D02*
X387493Y415178D01*
G01X385287Y415619D02*
X382713Y416134D01*
G01X402090Y413228D02*
X382713Y417103D01*
G01Y416134D02*
X356610Y410914D01*
G01X382713Y417103D02*
X356239Y411809D01*
G01X382999Y420219D02*
X402407Y416338D01*
G01X382999Y421188D02*
X402407Y417307D01*
G01Y416338D02*
X416658Y419188D01*
G01X402407Y417307D02*
X416658Y420157D01*
G01X427979Y442285D02*
X413936Y445093D01*
G01X427979Y441316D02*
X413936Y444124D01*
G01Y445093D02*
X404646Y443235D01*
G01X413936Y444124D02*
X404647Y442266D01*
G01X404646Y443235D02*
X379383Y448288D01*
G01X404647Y442266D02*
X403863Y442422D01*
G01X404646Y443235D02*
X379383Y448288D01*
G01X403863Y442422D02*
X379383Y447319D01*
G01Y448288D02*
X359911Y444394D01*
G01X379383Y447319D02*
X359911Y443425D01*
G01X414027Y440154D02*
X429065Y437146D01*
G01X429064Y438116D02*
X414027Y441123D01*
G01X403422Y438034D02*
X414027Y440154D01*
G01Y441123D02*
X403422Y439003D01*
G01X382812Y442156D02*
X403422Y438034D01*
G01Y439003D02*
X382812Y443125D01*
G01D02*
X355873Y437736D01*
G01X414027Y440154D02*
X429065Y437146D01*
G01X429064Y438116D02*
X414027Y441123D01*
G01X403422Y438034D02*
X414027Y440154D01*
G01Y441123D02*
X403422Y439003D01*
G01X382812Y442156D02*
X403422Y438034D01*
G01Y439003D02*
X382812Y443125D01*
G01D02*
X355873Y437736D01*
G01X384980Y425464D02*
X403977Y421665D01*
G01X384980Y424495D02*
X395921Y422307D01*
G01X384980Y425464D02*
X403977Y421665D01*
G01X398127Y421866D02*
X399451Y421601D01*
G01X384980Y425464D02*
X403977Y421665D01*
G01X401657Y421160D02*
X403977Y420696D01*
G01Y421665D02*
X416314Y424133D01*
G01X403977Y420696D02*
X416314Y423164D01*
G01Y424133D02*
X429627Y421469D01*
G01X416314Y423164D02*
X429627Y420500D01*
G01X383411Y438424D02*
X404311Y434244D01*
G01X383411Y437455D02*
X404311Y433275D01*
G01Y434244D02*
X415036Y436390D01*
G01X404311Y433275D02*
X415036Y435421D01*
G01Y436390D02*
X427643Y433870D01*
G01X415036Y435421D02*
X427643Y432901D01*
G01X416241Y431213D02*
X428705Y428720D01*
G01Y429689D02*
X416241Y432182D01*
G01X404459Y428857D02*
X416241Y431213D01*
G01Y432182D02*
X404459Y429826D01*
G01X382960Y433157D02*
X404459Y428857D01*
G01Y429826D02*
X382960Y434126D01*
G01X362161Y424550D02*
X363485Y424815D01*
G01X365691Y425256D02*
X383158Y428749D01*
G01Y429718D02*
X403850Y425580D01*
G01X383158Y428749D02*
X403850Y424611D01*
G01Y425580D02*
X416211Y428052D01*
G01X403850Y424611D02*
X416211Y427083D01*
G01Y428052D02*
X428122Y425673D01*
G01X416211Y427083D02*
X428122Y424704D01*
G01X362161Y424550D02*
X363485Y424815D01*
G01X365691Y425256D02*
X383158Y428749D01*
G01Y429718D02*
X403850Y425580D01*
G01X383158Y428749D02*
X403850Y424611D01*
G01Y425580D02*
X416211Y428052D01*
G01X403850Y424611D02*
X416211Y427083D01*
G01Y428052D02*
X428122Y425673D01*
G01X416211Y427083D02*
X428122Y424704D01*
G01X427979Y441316D02*
X413936Y444124D01*
G01X427979Y442285D02*
X413936Y445093D01*
G01Y444124D02*
X404647Y442266D01*
G01X413936Y445093D02*
X404646Y443235D01*
G01X404647Y442266D02*
X403863Y442422D01*
G01D02*
X379383Y447319D01*
G01X404646Y443235D02*
X379383Y448288D01*
G01Y447319D02*
X359911Y443425D01*
G01X379383Y448288D02*
X359911Y444394D01*
G01X382812Y443125D02*
X355873Y437736D01*
G01X403422Y439003D02*
X382812Y443125D01*
G01Y442156D02*
X403422Y438034D01*
G01X414027Y441123D02*
X403422Y439003D01*
G01Y438034D02*
X414027Y440154D01*
G01X429064Y438116D02*
X414027Y441123D01*
G01Y440154D02*
X429065Y437146D01*
G01X382812Y443125D02*
X355873Y437736D01*
G01X403422Y439003D02*
X382812Y443125D01*
G01Y442156D02*
X403422Y438034D01*
G01X414027Y441123D02*
X403422Y439003D01*
G01Y438034D02*
X414027Y440154D01*
G01X429064Y438116D02*
X414027Y441123D01*
G01Y440154D02*
X429065Y437146D01*
G01X384980Y424495D02*
X395921Y422307D01*
G01X398127Y421866D02*
X399451Y421601D01*
G01X401657Y421160D02*
X403977Y420696D01*
G01X384980Y425464D02*
X403977Y421665D01*
G01Y420696D02*
X416314Y423164D01*
G01X403977Y421665D02*
X416314Y424133D01*
G01Y423164D02*
X429627Y420500D01*
G01X416314Y424133D02*
X429627Y421469D01*
G01X383411Y437455D02*
X404311Y433275D01*
G01X383411Y438424D02*
X404311Y434244D01*
G01Y433275D02*
X415036Y435421D01*
G01X404311Y434244D02*
X415036Y436390D01*
G01Y435421D02*
X427643Y432901D01*
G01X415036Y436390D02*
X427643Y433870D01*
G01X404459Y429826D02*
X382960Y434126D01*
G01Y433157D02*
X404459Y428857D01*
G01X416241Y432182D02*
X404459Y429826D01*
G01Y428857D02*
X416241Y431213D01*
G01X428705Y429689D02*
X416241Y432182D01*
G01Y431213D02*
X428705Y428720D01*
G01X362161Y424550D02*
X363485Y424815D01*
G01X365691Y425256D02*
X383158Y428749D01*
G01D02*
X403850Y424611D01*
G01X383158Y429718D02*
X403850Y425580D01*
G01Y424611D02*
X416211Y427083D01*
G01X403850Y425580D02*
X416211Y428052D01*
G01Y427083D02*
X428122Y424704D01*
G01X416211Y428052D02*
X428122Y425673D01*
G01X427979Y442285D02*
X413936Y445093D01*
G01X427979Y441316D02*
X413936Y444124D01*
G01Y445093D02*
X404646Y443235D01*
G01X413936Y444124D02*
X404647Y442266D01*
G01X404646Y443235D02*
X379383Y448288D01*
G01X404647Y442266D02*
X403863Y442422D01*
G01X404646Y443235D02*
X379383Y448288D01*
G01X403863Y442422D02*
X379383Y447319D01*
G01Y448288D02*
X359911Y444394D01*
G01X379383Y447319D02*
X359911Y443425D01*
G01X383411Y438424D02*
X404311Y434244D01*
G01X383411Y437455D02*
X404311Y433275D01*
G01Y434244D02*
X415036Y436390D01*
G01X404311Y433275D02*
X415036Y435421D01*
G01Y436390D02*
X427643Y433870D01*
G01X415036Y435421D02*
X427643Y432901D01*
G01X382999Y421188D02*
X402407Y417307D01*
G01X382999Y420219D02*
X402407Y416338D01*
G01Y417307D02*
X416658Y420157D01*
G01X402407Y416338D02*
X416658Y419188D01*
G01X427979Y441316D02*
X413936Y444124D01*
G01X427979Y442285D02*
X413936Y445093D01*
G01Y444124D02*
X404647Y442266D01*
G01X413936Y445093D02*
X404646Y443235D01*
G01X404647Y442266D02*
X403863Y442422D01*
G01D02*
X379383Y447319D01*
G01X404646Y443235D02*
X379383Y448288D01*
G01Y447319D02*
X359911Y443425D01*
G01X379383Y448288D02*
X359911Y444394D01*
G01X383411Y437455D02*
X404311Y433275D01*
G01X383411Y438424D02*
X404311Y434244D01*
G01Y433275D02*
X415036Y435421D01*
G01X404311Y434244D02*
X415036Y436390D01*
G01Y435421D02*
X427643Y432901D01*
G01X415036Y436390D02*
X427643Y433870D01*
G01X362161Y424550D02*
X363485Y424815D01*
G01X365691Y425256D02*
X383158Y428749D01*
G01D02*
X403850Y424611D01*
G01X383158Y429718D02*
X403850Y425580D01*
G01Y424611D02*
X416211Y427083D01*
G01X403850Y425580D02*
X416211Y428052D01*
G01Y427083D02*
X428122Y424704D01*
G01X416211Y428052D02*
X428122Y425673D01*
G01X382999Y420219D02*
X402407Y416338D01*
G01X382999Y421188D02*
X402407Y417307D01*
G01Y416338D02*
X416658Y419188D01*
G01X402407Y417307D02*
X416658Y420157D01*
G01X429311Y479419D02*
X402144Y473986D01*
G01X429311Y480388D02*
X402144Y474955D01*
G01Y473986D02*
X382450Y477925D01*
G01X402144Y474955D02*
X382450Y478894D01*
G01Y477925D02*
X355771Y472589D01*
G01X382450Y478894D02*
X355771Y473558D01*
G01X401316Y479159D02*
X430046Y484905D01*
G01Y483936D02*
X401316Y478190D01*
G01X381741Y483074D02*
X401316Y479159D01*
G01Y478190D02*
X381741Y482105D01*
G01X355286Y477783D02*
X381741Y483074D01*
G01Y482105D02*
X355286Y476814D01*
G01X431285Y488898D02*
X399508Y482543D01*
G01X431285Y489867D02*
X399508Y483512D01*
G01Y482543D02*
X381620Y486121D01*
G01X399508Y483512D02*
X381620Y487090D01*
G01Y486121D02*
X356033Y481004D01*
G01X381620Y487090D02*
X356033Y481973D01*
G01X404414Y464741D02*
X429705Y469800D01*
G01Y470769D02*
X404414Y465710D01*
G01X383643Y468895D02*
X404414Y464741D01*
G01Y465710D02*
X383643Y469864D01*
G01D02*
X359256Y464987D01*
G01X430517Y475491D02*
X404316Y470251D01*
G01X430517Y474522D02*
X404316Y469282D01*
G01Y470251D02*
X383582Y474398D01*
G01X404316Y469282D02*
X383582Y473429D01*
G01Y474398D02*
X357761Y469234D01*
G01X383582Y473429D02*
X357761Y468265D01*
G01X429311Y480388D02*
X402144Y474955D01*
G01X429311Y479419D02*
X402144Y473986D01*
G01Y474955D02*
X382450Y478894D01*
G01X402144Y473986D02*
X382450Y477925D01*
G01Y478894D02*
X355771Y473558D01*
G01X382450Y477925D02*
X355771Y472589D01*
G01X381741Y482105D02*
X355286Y476814D01*
G01Y477783D02*
X381741Y483074D01*
G01X401316Y478190D02*
X381741Y482105D01*
G01Y483074D02*
X401316Y479159D01*
G01X430046Y483936D02*
X401316Y478190D01*
G01Y479159D02*
X430046Y484905D01*
G01X431285Y489867D02*
X399508Y483512D01*
G01X431285Y488898D02*
X399508Y482543D01*
G01Y483512D02*
X381620Y487090D01*
G01X399508Y482543D02*
X381620Y486121D01*
G01Y487090D02*
X356033Y481973D01*
G01X381620Y486121D02*
X356033Y481004D01*
G01X383643Y469864D02*
X359256Y464987D01*
G01X404414Y465710D02*
X383643Y469864D01*
G01Y468895D02*
X404414Y464741D01*
G01X429705Y470769D02*
X404414Y465710D01*
G01Y464741D02*
X429705Y469800D01*
G01X430517Y474522D02*
X404316Y469282D01*
G01X430517Y475491D02*
X404316Y470251D01*
G01Y469282D02*
X383582Y473429D01*
G01X404316Y470251D02*
X383582Y474398D01*
G01Y473429D02*
X357761Y468265D01*
G01X383582Y474398D02*
X357761Y469234D01*
G01X431285Y488898D02*
X399508Y482543D01*
G01X431285Y489867D02*
X399508Y483512D01*
G01Y482543D02*
X381620Y486121D01*
G01X399508Y483512D02*
X381620Y487090D01*
G01Y486121D02*
X356033Y481004D01*
G01X381620Y487090D02*
X356033Y481973D01*
G01X431285Y489867D02*
X399508Y483512D01*
G01X431285Y488898D02*
X399508Y482543D01*
G01Y483512D02*
X381620Y487090D01*
G01X399508Y482543D02*
X381620Y486121D01*
G01Y487090D02*
X356033Y481973D01*
G01X381620Y486121D02*
X356033Y481004D01*
G01X472081Y156754D02*
X479853Y145235D01*
G01X472977Y157125D02*
X480538Y145919D01*
G01X477634Y156494D02*
X482761Y148892D01*
G01X472977Y157125D02*
X480538Y145919D01*
G01X472081Y156754D02*
X479853Y145235D01*
G01X477634Y156494D02*
X482761Y148892D01*
G01X477634Y156494D02*
X482761Y148892D01*
G01X468250Y199807D02*
Y176472D01*
G01X469200Y199793D02*
Y176564D01*
G01X468250Y176472D02*
X472081Y156754D01*
G01X469200Y176564D02*
X470125Y171803D01*
G01X468250Y176472D02*
X472081Y156754D01*
G01X470536Y169692D02*
X472977Y157125D01*
G01X473740Y181508D02*
Y183933D01*
G01Y186083D02*
Y187433D01*
G01Y189583D02*
Y190933D01*
G01Y193083D02*
Y194433D01*
G01Y196583D02*
Y197933D01*
G01X472790D02*
Y181415D01*
G01X478530Y156865D02*
X473741Y181507D01*
G01X472790Y181415D02*
X477634Y156494D01*
G01X469200Y199793D02*
Y176564D01*
G01X468250Y199807D02*
Y176472D01*
G01X469200Y176564D02*
X470125Y171803D01*
G01X470536Y169692D02*
X472977Y157125D01*
G01X468250Y176472D02*
X472081Y156754D01*
G01X472790Y181415D02*
X477634Y156494D01*
G01X478530Y156865D02*
X473741Y181507D01*
G01X472790Y197933D02*
Y181415D01*
G01X473740Y181508D02*
Y183933D01*
G01X472790Y197933D02*
Y181415D01*
G01X473740Y186083D02*
Y187433D01*
G01X472790Y197933D02*
Y181415D01*
G01X473740Y189583D02*
Y190933D01*
G01X472790Y197933D02*
Y181415D01*
G01X473740Y193083D02*
Y194433D01*
G01X472790Y197933D02*
Y181415D01*
G01X473740Y196583D02*
Y197933D01*
G01X481767Y201609D02*
X477657Y180451D01*
G01D02*
X481927Y158479D01*
G01X477657Y180451D02*
X481927Y158479D01*
G01X477657Y180451D02*
X481927Y158479D01*
G01X477657Y180451D02*
X481927Y158479D01*
G01X477657Y180451D02*
X481927Y158479D01*
G01X477657Y180451D02*
X481927Y158479D01*
G01X477657Y180451D02*
X481927Y158479D01*
G01X481767Y201609D02*
X477657Y180451D01*
G01X481767Y201609D02*
X477657Y180451D01*
G01X481767Y201609D02*
X477657Y180451D01*
G01X481767Y201609D02*
X477657Y180451D01*
G01X472790Y181415D02*
X477634Y156494D01*
G01X478530Y156865D02*
X473741Y181507D01*
G01X472790Y197933D02*
Y181415D01*
G01X473740Y181508D02*
Y183933D01*
G01X472790Y197933D02*
Y181415D01*
G01X473740Y186083D02*
Y187433D01*
G01X472790Y197933D02*
Y181415D01*
G01X473740Y189583D02*
Y190933D01*
G01X472790Y197933D02*
Y181415D01*
G01X473740Y193083D02*
Y194433D01*
G01X472790Y197933D02*
Y181415D01*
G01X473740Y196583D02*
Y197933D01*
G01X477657Y180451D02*
X481927Y158479D01*
G01X477657Y180451D02*
X481927Y158479D01*
G01X477657Y180451D02*
X481927Y158479D01*
G01X477657Y180451D02*
X481927Y158479D01*
G01X477657Y180451D02*
X481927Y158479D01*
G01X477657Y180451D02*
X481927Y158479D01*
G01X481767Y201609D02*
X477657Y180451D01*
G01X481767Y201609D02*
X477657Y180451D01*
G01X481767Y201609D02*
X477657Y180451D01*
G01X481767Y201609D02*
X477657Y180451D01*
G01X484511Y453241D02*
X467855Y449909D01*
G01X465649Y449469D02*
X464325Y449204D01*
G01X462119Y448763D02*
X460795Y448498D01*
G01X458589Y448057D02*
X457265Y447792D01*
G01X484513Y454211D02*
X457265Y448761D01*
G01Y447792D02*
X449184Y449408D01*
G01X446978Y449850D02*
X445654Y450114D01*
G01X443448Y450556D02*
X442124Y450820D01*
G01X439917Y451262D02*
X438594Y451526D01*
G01X436387Y451968D02*
X432541Y452737D01*
G01X457265Y448761D02*
X432541Y453706D01*
G01Y452737D02*
X430192Y452267D01*
G01X427986Y451826D02*
X426662Y451561D01*
G01X424455Y451120D02*
X423132Y450855D01*
G01X484513Y454211D02*
X457265Y448761D01*
G01X484511Y453241D02*
X467855Y449909D01*
G01X484513Y454211D02*
X457265Y448761D01*
G01X465649Y449469D02*
X464325Y449204D01*
G01X484513Y454211D02*
X457265Y448761D01*
G01X462119Y448763D02*
X460795Y448498D01*
G01X484513Y454211D02*
X457265Y448761D01*
G01X458589Y448057D02*
X457265Y447792D01*
G01Y448761D02*
X432541Y453706D01*
G01X457265Y447792D02*
X449184Y449408D01*
G01X457265Y448761D02*
X432541Y453706D01*
G01X446978Y449850D02*
X445654Y450114D01*
G01X457265Y448761D02*
X432541Y453706D01*
G01X443448Y450556D02*
X442124Y450820D01*
G01X457265Y448761D02*
X432541Y453706D01*
G01X439917Y451262D02*
X438594Y451526D01*
G01X457265Y448761D02*
X432541Y453706D01*
G01X436387Y451968D02*
X432541Y452737D01*
G01D02*
X430192Y452267D01*
G01X427986Y451826D02*
X426662Y451561D01*
G01X424455Y451120D02*
X423132Y450855D01*
G01X459350Y459511D02*
X481699Y463979D01*
G01Y463010D02*
X459350Y458542D01*
G01X428691Y465642D02*
X459350Y459511D01*
G01Y458542D02*
X428691Y464673D01*
G01X484260Y457803D02*
X458459Y452643D01*
G01X484260Y458772D02*
X458459Y453612D01*
G01Y452643D02*
X432264Y457882D01*
G01X458459Y453612D02*
X432264Y458851D01*
G01X460088Y463723D02*
X480437Y467793D01*
G01Y468762D02*
X460088Y464692D01*
G01X429705Y469800D02*
X460088Y463723D01*
G01Y464692D02*
X429705Y470769D01*
G01X459350Y458542D02*
X428691Y464673D01*
G01Y465642D02*
X459350Y459511D01*
G01X481699Y463010D02*
X459350Y458542D01*
G01Y459511D02*
X481699Y463979D01*
G01X484260Y458772D02*
X458459Y453612D01*
G01X484260Y457803D02*
X458459Y452643D01*
G01Y453612D02*
X432264Y458851D01*
G01X458459Y452643D02*
X432264Y457882D01*
G01X460088Y464692D02*
X429705Y470769D01*
G01Y469800D02*
X460088Y463723D01*
G01X480437Y468762D02*
X460088Y464692D01*
G01Y463723D02*
X480437Y467793D01*
G01X429627Y421469D02*
X445240Y424591D01*
G01X429627Y420500D02*
X445240Y423622D01*
G01Y424591D02*
X473490Y418972D01*
G01X445240Y423622D02*
X446564Y423359D01*
G01X445240Y424591D02*
X473490Y418972D01*
G01X448771Y422920D02*
X450095Y422656D01*
G01X445240Y424591D02*
X473490Y418972D01*
G01X452302Y422217D02*
X453626Y421954D01*
G01X445240Y424591D02*
X473490Y418972D01*
G01X455833Y421515D02*
X457157Y421252D01*
G01X445240Y424591D02*
X473490Y418972D01*
G01X459363Y420813D02*
X464215Y419848D01*
G01X445240Y424591D02*
X473490Y418972D01*
G01X466421Y419409D02*
X467745Y419146D01*
G01X445240Y424591D02*
X473490Y418972D01*
G01X469952Y418707D02*
X473305Y418040D01*
G01X445286Y432037D02*
X478702Y425389D01*
G01X479170Y426265D02*
X445285Y433006D01*
G01X428705Y428720D02*
X445286Y432037D01*
G01X445285Y433006D02*
X428705Y429689D01*
G01X467030Y411335D02*
X442587Y416080D01*
G01X466849Y410402D02*
X462421Y411261D01*
G01X467030Y411335D02*
X442587Y416080D01*
G01X460213Y411690D02*
X458887Y411947D01*
G01X467030Y411335D02*
X442587Y416080D01*
G01X456679Y412376D02*
X455353Y412633D01*
G01X467030Y411335D02*
X442587Y416080D01*
G01X453144Y413062D02*
X451819Y413319D01*
G01X467030Y411335D02*
X442587Y416080D01*
G01X449610Y413748D02*
X442590Y415111D01*
G01X442587Y416080D02*
X428975Y413358D01*
G01X442590Y415111D02*
X439770Y414547D01*
G01X442587Y416080D02*
X428975Y413358D01*
G01X437563Y414106D02*
X436239Y413841D01*
G01X442587Y416080D02*
X428975Y413358D01*
G01X434033Y413400D02*
X428975Y412389D01*
G01D02*
X422916Y413601D01*
G01X420710Y414042D02*
X419386Y414307D01*
G01X467030Y411335D02*
X442587Y416080D01*
G01X466849Y410402D02*
X462421Y411261D01*
G01X467030Y411335D02*
X442587Y416080D01*
G01X460213Y411690D02*
X458887Y411947D01*
G01X467030Y411335D02*
X442587Y416080D01*
G01X456679Y412376D02*
X455353Y412633D01*
G01X467030Y411335D02*
X442587Y416080D01*
G01X453144Y413062D02*
X451819Y413319D01*
G01X467030Y411335D02*
X442587Y416080D01*
G01X449610Y413748D02*
X442590Y415111D01*
G01X442587Y416080D02*
X428975Y413358D01*
G01X442590Y415111D02*
X439770Y414547D01*
G01X442587Y416080D02*
X428975Y413358D01*
G01X437563Y414106D02*
X436239Y413841D01*
G01X442587Y416080D02*
X428975Y413358D01*
G01X434033Y413400D02*
X428975Y412389D01*
G01D02*
X422916Y413601D01*
G01X420710Y414042D02*
X419386Y414307D01*
G01X416658Y420157D02*
X429746Y417541D01*
G01X416658Y419188D02*
X429746Y416572D01*
G01Y417541D02*
X444266Y420445D01*
G01X429746Y416572D02*
X444266Y419476D01*
G01Y420445D02*
X471622Y414976D01*
G01X444266Y419476D02*
X445590Y419211D01*
G01X444266Y420445D02*
X471622Y414976D01*
G01X447796Y418770D02*
X449120Y418505D01*
G01X444266Y420445D02*
X471622Y414976D01*
G01X451326Y418064D02*
X457032Y416923D01*
G01X444266Y420445D02*
X471622Y414976D01*
G01X459239Y416482D02*
X460563Y416218D01*
G01X444266Y420445D02*
X471622Y414976D01*
G01X462769Y415776D02*
X464093Y415512D01*
G01X444266Y420445D02*
X471622Y414976D01*
G01X466299Y415071D02*
X467623Y414806D01*
G01X444266Y420445D02*
X471622Y414976D01*
G01X469829Y414365D02*
X471153Y414100D01*
G01X471622Y414976D02*
X475501Y411097D01*
G01X471153Y414100D02*
X471213Y414040D01*
G01X471622Y414976D02*
X475501Y411097D01*
G01X471214Y414040D02*
X474829Y410425D01*
G01X429627Y420500D02*
X445240Y423622D01*
G01X429627Y421469D02*
X445240Y424591D01*
G01Y423622D02*
X446564Y423359D01*
G01X448771Y422920D02*
X450095Y422656D01*
G01X452302Y422217D02*
X453626Y421954D01*
G01X455833Y421515D02*
X457157Y421252D01*
G01X459363Y420813D02*
X464215Y419848D01*
G01X466421Y419409D02*
X467745Y419146D01*
G01X469952Y418707D02*
X473305Y418040D01*
G01X445240Y424591D02*
X473490Y418972D01*
G01X445285Y433006D02*
X428705Y429689D01*
G01Y428720D02*
X445286Y432037D01*
G01X479170Y426265D02*
X445285Y433006D01*
G01X445286Y432037D02*
X478702Y425389D01*
G01X466849Y410402D02*
X462421Y411261D01*
G01X460213Y411690D02*
X458887Y411947D01*
G01X456679Y412376D02*
X455353Y412633D01*
G01X453144Y413062D02*
X451819Y413319D01*
G01X449610Y413748D02*
X442590Y415111D01*
G01X467030Y411335D02*
X442587Y416080D01*
G01X442590Y415111D02*
X439770Y414547D01*
G01X437563Y414106D02*
X436239Y413841D01*
G01X434033Y413400D02*
X428975Y412389D01*
G01X442587Y416080D02*
X428975Y413358D01*
G01Y412389D02*
X422916Y413601D01*
G01X420710Y414042D02*
X419386Y414307D01*
G01X466849Y410402D02*
X462421Y411261D01*
G01X460213Y411690D02*
X458887Y411947D01*
G01X456679Y412376D02*
X455353Y412633D01*
G01X453144Y413062D02*
X451819Y413319D01*
G01X449610Y413748D02*
X442590Y415111D01*
G01X467030Y411335D02*
X442587Y416080D01*
G01X442590Y415111D02*
X439770Y414547D01*
G01X437563Y414106D02*
X436239Y413841D01*
G01X434033Y413400D02*
X428975Y412389D01*
G01X442587Y416080D02*
X428975Y413358D01*
G01Y412389D02*
X422916Y413601D01*
G01X420710Y414042D02*
X419386Y414307D01*
G01X416658Y419188D02*
X429746Y416572D01*
G01X416658Y420157D02*
X429746Y417541D01*
G01Y416572D02*
X444266Y419476D01*
G01X429746Y417541D02*
X444266Y420445D01*
G01Y419476D02*
X445590Y419211D01*
G01X447796Y418770D02*
X449120Y418505D01*
G01X451326Y418064D02*
X457032Y416923D01*
G01X459239Y416482D02*
X460563Y416218D01*
G01X462769Y415776D02*
X464093Y415512D01*
G01X466299Y415071D02*
X467623Y414806D01*
G01X469829Y414365D02*
X471153Y414100D01*
G01X444266Y420445D02*
X471622Y414976D01*
G01X471153Y414100D02*
X471213Y414040D01*
G01X471214D02*
X474829Y410425D01*
G01X471622Y414976D02*
X475501Y411097D01*
G01X484349Y438285D02*
X476868Y439773D01*
G01X474661Y440212D02*
X473337Y440475D01*
G01X471130Y440914D02*
X469806Y441177D01*
G01X467599Y441616D02*
X446056Y445900D01*
G01X483881Y437409D02*
X446057Y444931D01*
G01X446056Y445900D02*
X444187Y445526D01*
G01X441981Y445085D02*
X440657Y444820D01*
G01X438451Y444379D02*
X438450D01*
G01D02*
X427979Y442285D01*
G01X446057Y444931D02*
X427979Y441316D01*
G01X447278Y440809D02*
X481093Y434084D01*
G01X481561Y434960D02*
X447277Y441778D01*
G01X429065Y437146D02*
X447278Y440809D01*
G01X447277Y441778D02*
X429064Y438116D01*
G01X447278Y440809D02*
X481093Y434084D01*
G01X481561Y434960D02*
X447277Y441778D01*
G01X429065Y437146D02*
X447278Y440809D01*
G01X447277Y441778D02*
X429064Y438116D01*
G01X429627Y421469D02*
X445240Y424591D01*
G01X429627Y420500D02*
X445240Y423622D01*
G01Y424591D02*
X473490Y418972D01*
G01X445240Y423622D02*
X446564Y423359D01*
G01X445240Y424591D02*
X473490Y418972D01*
G01X448771Y422920D02*
X450095Y422656D01*
G01X445240Y424591D02*
X473490Y418972D01*
G01X452302Y422217D02*
X453626Y421954D01*
G01X445240Y424591D02*
X473490Y418972D01*
G01X455833Y421515D02*
X457157Y421252D01*
G01X445240Y424591D02*
X473490Y418972D01*
G01X459363Y420813D02*
X464215Y419848D01*
G01X445240Y424591D02*
X473490Y418972D01*
G01X466421Y419409D02*
X467745Y419146D01*
G01X445240Y424591D02*
X473490Y418972D01*
G01X469952Y418707D02*
X473305Y418040D01*
G01X427643Y433870D02*
X445656Y437473D01*
G01X427643Y432901D02*
X431537Y433680D01*
G01X427643Y433870D02*
X445656Y437473D01*
G01X433743Y434121D02*
X435067Y434386D01*
G01X427643Y433870D02*
X445656Y437473D01*
G01X437273Y434827D02*
X438597Y435092D01*
G01X427643Y433870D02*
X445656Y437473D01*
G01X440803Y435533D02*
X442127Y435798D01*
G01X427643Y433870D02*
X445656Y437473D01*
G01X444333Y436239D02*
X445657Y436504D01*
G01X445656Y437473D02*
X480433Y430555D01*
G01X445657Y436504D02*
X454052Y434834D01*
G01X445656Y437473D02*
X480433Y430555D01*
G01X456259Y434395D02*
X479965Y429679D01*
G01X445286Y432037D02*
X478702Y425389D01*
G01X479170Y426265D02*
X445285Y433006D01*
G01X428705Y428720D02*
X445286Y432037D01*
G01X445285Y433006D02*
X428705Y429689D01*
G01X428122Y425673D02*
X445326Y429113D01*
G01X428122Y424704D02*
X429446Y424969D01*
G01X428122Y425673D02*
X445326Y429113D01*
G01X431652Y425410D02*
X432976Y425675D01*
G01X428122Y425673D02*
X445326Y429113D01*
G01X435182Y426116D02*
X436506Y426380D01*
G01X428122Y425673D02*
X445326Y429113D01*
G01X438712Y426822D02*
X440036Y427086D01*
G01X428122Y425673D02*
X445326Y429113D01*
G01X442243Y427527D02*
X445326Y428144D01*
G01Y429113D02*
X477040Y422805D01*
G01X445326Y428144D02*
X450489Y427117D01*
G01X445326Y429113D02*
X477040Y422805D01*
G01X452696Y426678D02*
X454020Y426415D01*
G01X445326Y429113D02*
X477040Y422805D01*
G01X456227Y425976D02*
X462449Y424738D01*
G01X445326Y429113D02*
X477040Y422805D01*
G01X464655Y424299D02*
X465980Y424036D01*
G01X445326Y429113D02*
X477040Y422805D01*
G01X468186Y423597D02*
X469510Y423334D01*
G01X445326Y429113D02*
X477040Y422805D01*
G01X471717Y422895D02*
X473041Y422631D01*
G01X445326Y429113D02*
X477040Y422805D01*
G01D02*
X479312Y420533D01*
G01X475248Y422192D02*
X476572Y421929D01*
G01X477040Y422805D02*
X479312Y420533D01*
G01X476572Y421929D02*
X478640Y419861D01*
G01X428122Y425673D02*
X445326Y429113D01*
G01X428122Y424704D02*
X429446Y424969D01*
G01X428122Y425673D02*
X445326Y429113D01*
G01X431652Y425410D02*
X432976Y425675D01*
G01X428122Y425673D02*
X445326Y429113D01*
G01X435182Y426116D02*
X436506Y426380D01*
G01X428122Y425673D02*
X445326Y429113D01*
G01X438712Y426822D02*
X440036Y427086D01*
G01X428122Y425673D02*
X445326Y429113D01*
G01X442243Y427527D02*
X445326Y428144D01*
G01Y429113D02*
X477040Y422805D01*
G01X445326Y428144D02*
X450489Y427117D01*
G01X445326Y429113D02*
X477040Y422805D01*
G01X452696Y426678D02*
X454020Y426415D01*
G01X445326Y429113D02*
X477040Y422805D01*
G01X456227Y425976D02*
X462449Y424738D01*
G01X445326Y429113D02*
X477040Y422805D01*
G01X464655Y424299D02*
X465980Y424036D01*
G01X445326Y429113D02*
X477040Y422805D01*
G01X468186Y423597D02*
X469510Y423334D01*
G01X445326Y429113D02*
X477040Y422805D01*
G01X471717Y422895D02*
X473041Y422631D01*
G01X445326Y429113D02*
X477040Y422805D01*
G01D02*
X479312Y420533D01*
G01X475248Y422192D02*
X476572Y421929D01*
G01X477040Y422805D02*
X479312Y420533D01*
G01X476572Y421929D02*
X478640Y419861D01*
G01X483881Y437409D02*
X446057Y444931D01*
G01X484349Y438285D02*
X476868Y439773D01*
G01X483881Y437409D02*
X446057Y444931D01*
G01X474661Y440212D02*
X473337Y440475D01*
G01X483881Y437409D02*
X446057Y444931D01*
G01X471130Y440914D02*
X469806Y441177D01*
G01X483881Y437409D02*
X446057Y444931D01*
G01X467599Y441616D02*
X446056Y445900D01*
G01X446057Y444931D02*
X427979Y441316D01*
G01X446056Y445900D02*
X444187Y445526D01*
G01X446057Y444931D02*
X427979Y441316D01*
G01X441981Y445085D02*
X440657Y444820D01*
G01X446057Y444931D02*
X427979Y441316D01*
G01X438451Y444379D02*
X438450D01*
G01X446057Y444931D02*
X427979Y441316D01*
G01X438450Y444379D02*
X427979Y442285D01*
G01X447277Y441778D02*
X429064Y438116D01*
G01X429065Y437146D02*
X447278Y440809D01*
G01X481561Y434960D02*
X447277Y441778D01*
G01X447278Y440809D02*
X481093Y434084D01*
G01X447277Y441778D02*
X429064Y438116D01*
G01X429065Y437146D02*
X447278Y440809D01*
G01X481561Y434960D02*
X447277Y441778D01*
G01X447278Y440809D02*
X481093Y434084D01*
G01X429627Y420500D02*
X445240Y423622D01*
G01X429627Y421469D02*
X445240Y424591D01*
G01Y423622D02*
X446564Y423359D01*
G01X448771Y422920D02*
X450095Y422656D01*
G01X452302Y422217D02*
X453626Y421954D01*
G01X455833Y421515D02*
X457157Y421252D01*
G01X459363Y420813D02*
X464215Y419848D01*
G01X466421Y419409D02*
X467745Y419146D01*
G01X469952Y418707D02*
X473305Y418040D01*
G01X445240Y424591D02*
X473490Y418972D01*
G01X427643Y432901D02*
X431537Y433680D01*
G01X433743Y434121D02*
X435067Y434386D01*
G01X437273Y434827D02*
X438597Y435092D01*
G01X440803Y435533D02*
X442127Y435798D01*
G01X444333Y436239D02*
X445657Y436504D01*
G01X427643Y433870D02*
X445656Y437473D01*
G01X445657Y436504D02*
X454052Y434834D01*
G01X456259Y434395D02*
X479965Y429679D01*
G01X445656Y437473D02*
X480433Y430555D01*
G01X445285Y433006D02*
X428705Y429689D01*
G01Y428720D02*
X445286Y432037D01*
G01X479170Y426265D02*
X445285Y433006D01*
G01X445286Y432037D02*
X478702Y425389D01*
G01X428122Y424704D02*
X429446Y424969D01*
G01X431652Y425410D02*
X432976Y425675D01*
G01X435182Y426116D02*
X436506Y426380D01*
G01X438712Y426822D02*
X440036Y427086D01*
G01X442243Y427527D02*
X445326Y428144D01*
G01X428122Y425673D02*
X445326Y429113D01*
G01Y428144D02*
X450489Y427117D01*
G01X452696Y426678D02*
X454020Y426415D01*
G01X456227Y425976D02*
X462449Y424738D01*
G01X464655Y424299D02*
X465980Y424036D01*
G01X468186Y423597D02*
X469510Y423334D01*
G01X471717Y422895D02*
X473041Y422631D01*
G01X475248Y422192D02*
X476572Y421929D01*
G01X445326Y429113D02*
X477040Y422805D01*
G01X475248Y422192D02*
X476572Y421929D01*
G01D02*
X478640Y419861D01*
G01X477040Y422805D02*
X479312Y420533D01*
G01X484349Y438285D02*
X476868Y439773D01*
G01X474661Y440212D02*
X473337Y440475D01*
G01X471130Y440914D02*
X469806Y441177D01*
G01X467599Y441616D02*
X446056Y445900D01*
G01X483881Y437409D02*
X446057Y444931D01*
G01X446056Y445900D02*
X444187Y445526D01*
G01X441981Y445085D02*
X440657Y444820D01*
G01X438451Y444379D02*
X438450D01*
G01D02*
X427979Y442285D01*
G01X446057Y444931D02*
X427979Y441316D01*
G01X427643Y433870D02*
X445656Y437473D01*
G01X427643Y432901D02*
X431537Y433680D01*
G01X427643Y433870D02*
X445656Y437473D01*
G01X433743Y434121D02*
X435067Y434386D01*
G01X427643Y433870D02*
X445656Y437473D01*
G01X437273Y434827D02*
X438597Y435092D01*
G01X427643Y433870D02*
X445656Y437473D01*
G01X440803Y435533D02*
X442127Y435798D01*
G01X427643Y433870D02*
X445656Y437473D01*
G01X444333Y436239D02*
X445657Y436504D01*
G01X445656Y437473D02*
X480433Y430555D01*
G01X445657Y436504D02*
X454052Y434834D01*
G01X445656Y437473D02*
X480433Y430555D01*
G01X456259Y434395D02*
X479965Y429679D01*
G01X416658Y420157D02*
X429746Y417541D01*
G01X416658Y419188D02*
X429746Y416572D01*
G01Y417541D02*
X444266Y420445D01*
G01X429746Y416572D02*
X444266Y419476D01*
G01Y420445D02*
X471622Y414976D01*
G01X444266Y419476D02*
X445590Y419211D01*
G01X444266Y420445D02*
X471622Y414976D01*
G01X447796Y418770D02*
X449120Y418505D01*
G01X444266Y420445D02*
X471622Y414976D01*
G01X451326Y418064D02*
X457032Y416923D01*
G01X444266Y420445D02*
X471622Y414976D01*
G01X459239Y416482D02*
X460563Y416218D01*
G01X444266Y420445D02*
X471622Y414976D01*
G01X462769Y415776D02*
X464093Y415512D01*
G01X444266Y420445D02*
X471622Y414976D01*
G01X466299Y415071D02*
X467623Y414806D01*
G01X444266Y420445D02*
X471622Y414976D01*
G01X469829Y414365D02*
X471153Y414100D01*
G01X471622Y414976D02*
X475501Y411097D01*
G01X471153Y414100D02*
X471213Y414040D01*
G01X471622Y414976D02*
X475501Y411097D01*
G01X471214Y414040D02*
X474829Y410425D01*
G01X483881Y437409D02*
X446057Y444931D01*
G01X484349Y438285D02*
X476868Y439773D01*
G01X483881Y437409D02*
X446057Y444931D01*
G01X474661Y440212D02*
X473337Y440475D01*
G01X483881Y437409D02*
X446057Y444931D01*
G01X471130Y440914D02*
X469806Y441177D01*
G01X483881Y437409D02*
X446057Y444931D01*
G01X467599Y441616D02*
X446056Y445900D01*
G01X446057Y444931D02*
X427979Y441316D01*
G01X446056Y445900D02*
X444187Y445526D01*
G01X446057Y444931D02*
X427979Y441316D01*
G01X441981Y445085D02*
X440657Y444820D01*
G01X446057Y444931D02*
X427979Y441316D01*
G01X438451Y444379D02*
X438450D01*
G01X446057Y444931D02*
X427979Y441316D01*
G01X438450Y444379D02*
X427979Y442285D01*
G01X427643Y432901D02*
X431537Y433680D01*
G01X433743Y434121D02*
X435067Y434386D01*
G01X437273Y434827D02*
X438597Y435092D01*
G01X440803Y435533D02*
X442127Y435798D01*
G01X444333Y436239D02*
X445657Y436504D01*
G01X427643Y433870D02*
X445656Y437473D01*
G01X445657Y436504D02*
X454052Y434834D01*
G01X456259Y434395D02*
X479965Y429679D01*
G01X445656Y437473D02*
X480433Y430555D01*
G01X428122Y424704D02*
X429446Y424969D01*
G01X431652Y425410D02*
X432976Y425675D01*
G01X435182Y426116D02*
X436506Y426380D01*
G01X438712Y426822D02*
X440036Y427086D01*
G01X442243Y427527D02*
X445326Y428144D01*
G01X428122Y425673D02*
X445326Y429113D01*
G01Y428144D02*
X450489Y427117D01*
G01X452696Y426678D02*
X454020Y426415D01*
G01X456227Y425976D02*
X462449Y424738D01*
G01X464655Y424299D02*
X465980Y424036D01*
G01X468186Y423597D02*
X469510Y423334D01*
G01X471717Y422895D02*
X473041Y422631D01*
G01X475248Y422192D02*
X476572Y421929D01*
G01X445326Y429113D02*
X477040Y422805D01*
G01X475248Y422192D02*
X476572Y421929D01*
G01D02*
X478640Y419861D01*
G01X477040Y422805D02*
X479312Y420533D01*
G01X416658Y419188D02*
X429746Y416572D01*
G01X416658Y420157D02*
X429746Y417541D01*
G01Y416572D02*
X444266Y419476D01*
G01X429746Y417541D02*
X444266Y420445D01*
G01Y419476D02*
X445590Y419211D01*
G01X447796Y418770D02*
X449120Y418505D01*
G01X451326Y418064D02*
X457032Y416923D01*
G01X459239Y416482D02*
X460563Y416218D01*
G01X462769Y415776D02*
X464093Y415512D01*
G01X466299Y415071D02*
X467623Y414806D01*
G01X469829Y414365D02*
X471153Y414100D01*
G01X444266Y420445D02*
X471622Y414976D01*
G01X471153Y414100D02*
X471213Y414040D01*
G01X471214D02*
X474829Y410425D01*
G01X471622Y414976D02*
X475501Y411097D01*
G01X483142Y477628D02*
X460699Y473141D01*
G01X483140Y478597D02*
X460699Y474110D01*
G01Y473141D02*
X429311Y479419D01*
G01X460699Y474111D02*
X429311Y480388D01*
G01X461005Y478714D02*
X481995Y482912D01*
G01Y481943D02*
X461005Y477745D01*
G01X430046Y484905D02*
X461005Y478714D01*
G01Y477745D02*
X430046Y483936D01*
G01X483163Y486683D02*
X462767Y482602D01*
G01X483163Y487652D02*
X462767Y483571D01*
G01X462765Y482602D02*
X431285Y488898D01*
G01X462767Y483571D02*
X431285Y489867D01*
G01X482756Y473849D02*
X460740Y469446D01*
G01X482756Y472880D02*
X470348Y470398D01*
G01X482756Y473849D02*
X460740Y469446D01*
G01X468141Y469957D02*
X466818Y469692D01*
G01X482756Y473849D02*
X460740Y469446D01*
G01X464611Y469251D02*
X460740Y468477D01*
G01Y469446D02*
X430517Y475491D01*
G01X460740Y468477D02*
X430517Y474522D01*
G01X483140Y478597D02*
X460699Y474110D01*
G01X483142Y477628D02*
X460699Y473141D01*
G01Y474111D02*
X429311Y480388D01*
G01X460699Y473141D02*
X429311Y479419D01*
G01X461005Y477745D02*
X430046Y483936D01*
G01Y484905D02*
X461005Y478714D01*
G01X481995Y481943D02*
X461005Y477745D01*
G01Y478714D02*
X481995Y482912D01*
G01X483163Y487652D02*
X462767Y483571D01*
G01X483163Y486683D02*
X462767Y482602D01*
G01Y483571D02*
X431285Y489867D01*
G01X462765Y482602D02*
X431285Y488898D01*
G01X482756Y472880D02*
X470348Y470398D01*
G01X468141Y469957D02*
X466818Y469692D01*
G01X464611Y469251D02*
X460740Y468477D01*
G01X482756Y473849D02*
X460740Y469446D01*
G01Y468477D02*
X430517Y474522D01*
G01X460740Y469446D02*
X430517Y475491D01*
G01X483163Y486683D02*
X462767Y482602D01*
G01X483163Y487652D02*
X462767Y483571D01*
G01X462765Y482602D02*
X431285Y488898D01*
G01X462767Y483571D02*
X431285Y489867D01*
G01X483163Y487652D02*
X462767Y483571D01*
G01X483163Y486683D02*
X462767Y482602D01*
G01Y483571D02*
X431285Y489867D01*
G01X462765Y482602D02*
X431285Y488898D01*
G01X479853Y145235D02*
X503791Y129085D01*
G01X480538Y145919D02*
X480539D01*
G01X479853Y145235D02*
X503791Y129085D01*
G01X480539Y145919D02*
X504162Y129981D01*
G01X503791Y129085D02*
X564361Y117311D01*
G01X504162Y129981D02*
X564666Y118220D01*
G01X483446Y149577D02*
X478530Y156865D01*
G01X503389Y136125D02*
X502196Y136929D01*
G01D02*
X483446Y149577D01*
G01X482761Y148892D02*
X502857Y135337D01*
G01X503389Y136125D02*
X506309Y134156D01*
G01X503389Y136125D02*
X502196Y136929D01*
G01X502857Y135337D02*
X502858D01*
G01X503389Y136125D02*
X506309Y134156D01*
G01X502858Y135337D02*
X505938Y133260D01*
G01X506309Y134156D02*
X591766Y117543D01*
G01X505938Y133260D02*
X591523Y116622D01*
G01X480538Y145919D02*
X480539D01*
G01D02*
X504162Y129981D01*
G01X479853Y145235D02*
X503791Y129085D01*
G01X504162Y129981D02*
X564666Y118220D01*
G01X503791Y129085D02*
X564361Y117311D01*
G01X502857Y135337D02*
X502858D01*
G01D02*
X505938Y133260D01*
G01X503389Y136125D02*
X506309Y134156D01*
G01X505938Y133260D02*
X591523Y116622D01*
G01X506309Y134156D02*
X591766Y117543D01*
G01X482761Y148892D02*
X502857Y135337D01*
G01D02*
X502858D01*
G01X503389Y136125D02*
X502196Y136929D01*
G01X482761Y148892D02*
X502857Y135337D01*
G01X502196Y136929D02*
X483446Y149577D01*
G01D02*
X478530Y156865D01*
G01X487154Y152429D02*
X482823Y158850D01*
G01X481927Y158479D02*
X486469Y151744D01*
G01X508204Y138229D02*
X487154Y152429D01*
G01X486469Y151744D02*
X507833Y137333D01*
G01X543984Y131274D02*
X508204Y138229D01*
G01X507833Y137333D02*
X592799Y120815D01*
G01X523392Y163815D02*
X544460Y149605D01*
G01X524077Y164500D02*
X544829Y150503D01*
G01X541818Y146606D02*
X521164Y160538D01*
G01X541445Y145711D02*
X521000Y159502D01*
G01X541818Y146606D02*
X521164Y160538D01*
G01X518229Y157109D02*
X539840Y142533D01*
G01X517544Y156424D02*
X539469Y141636D01*
G01D02*
X540555Y141427D01*
G01X486620Y159935D02*
X490168Y154675D01*
G01X486620Y159935D02*
X490168Y154675D01*
G01X489474Y157404D02*
X490853Y155360D01*
G01X490168Y154675D02*
X499943Y148081D01*
G01D02*
X499944D01*
G01D02*
X509727Y141481D01*
G01X490853Y155360D02*
X510098Y142377D01*
G01X509727Y141481D02*
X595343Y124838D01*
G01X510098Y142377D02*
X595344Y125806D01*
G01X507833Y137333D02*
X592799Y120815D01*
G01X507833Y137333D02*
X592799Y120815D01*
G01X543984Y131274D02*
X508204Y138229D01*
G01X486469Y151744D02*
X507833Y137333D01*
G01X508204Y138229D02*
X487154Y152429D01*
G01X481927Y158479D02*
X486469Y151744D01*
G01X487154Y152429D02*
X482823Y158850D01*
G01X502857Y135337D02*
X502858D01*
G01D02*
X505938Y133260D01*
G01X503389Y136125D02*
X506309Y134156D01*
G01X505938Y133260D02*
X591523Y116622D01*
G01X506309Y134156D02*
X591766Y117543D01*
G01X482761Y148892D02*
X502857Y135337D01*
G01D02*
X502858D01*
G01X503389Y136125D02*
X502196Y136929D01*
G01X482761Y148892D02*
X502857Y135337D01*
G01X502196Y136929D02*
X483446Y149577D01*
G01D02*
X478530Y156865D01*
G01X524077Y164500D02*
X544829Y150503D01*
G01X523392Y163815D02*
X544460Y149605D01*
G01X541445Y145711D02*
X521000Y159502D01*
G01X541818Y146606D02*
X521164Y160538D01*
G01X517544Y156424D02*
X539469Y141636D01*
G01X518229Y157109D02*
X539840Y142533D01*
G01X517544Y156424D02*
X539469Y141636D01*
G01D02*
X540555Y141427D01*
G01X489474Y157404D02*
X490853Y155360D01*
G01X486620Y159935D02*
X490168Y154675D01*
G01X490853Y155360D02*
X510098Y142377D01*
G01X490168Y154675D02*
X499943Y148081D01*
G01X490853Y155360D02*
X510098Y142377D01*
G01X499943Y148081D02*
X499944D01*
G01X490853Y155360D02*
X510098Y142377D01*
G01X499944Y148081D02*
X509727Y141481D01*
G01X510098Y142377D02*
X595344Y125806D01*
G01X509727Y141481D02*
X595343Y124838D01*
G01X541818Y146606D02*
X521164Y160538D01*
G01X541445Y145711D02*
X521000Y159502D01*
G01X541818Y146606D02*
X521164Y160538D01*
G01X507833Y137333D02*
X592799Y120815D01*
G01X507833Y137333D02*
X592799Y120815D01*
G01X543984Y131274D02*
X508204Y138229D01*
G01X486469Y151744D02*
X507833Y137333D01*
G01X508204Y138229D02*
X487154Y152429D01*
G01X481927Y158479D02*
X486469Y151744D01*
G01X487154Y152429D02*
X482823Y158850D01*
G01X518229Y157109D02*
X539840Y142533D01*
G01X517544Y156424D02*
X539469Y141636D01*
G01D02*
X540555Y141427D01*
G01X482717Y201517D02*
Y203406D01*
G01X481767D02*
Y201609D01*
G01X478625Y180451D02*
X479086Y182829D01*
G01X479497Y184940D02*
X479754Y186265D01*
G01X480165Y188376D02*
X480422Y189701D01*
G01X480833Y191812D02*
X482717Y201517D01*
G01X482823Y158850D02*
X481965Y163271D01*
G01X481554Y165382D02*
X481297Y166707D01*
G01X480886Y168818D02*
X480629Y170143D01*
G01X480218Y172254D02*
X479961Y173579D01*
G01X479550Y175690D02*
X479293Y177015D01*
G01X478882Y179126D02*
X478625Y180451D01*
G01X499668Y205407D02*
Y191807D01*
G01X500618Y205407D02*
Y192201D01*
G01X499668Y191807D02*
X514547Y176927D01*
G01X500618Y192201D02*
X515284Y177535D01*
G01X514547Y176927D02*
X523392Y163815D01*
G01X515284Y177535D02*
X524077Y164500D01*
G01X521000Y159502D02*
X520479Y159853D01*
G01X521164Y160538D02*
X521000Y160781D01*
G01D02*
X511035Y175555D01*
G01X520479Y159853D02*
X510347Y174873D01*
G01X511035Y175555D02*
X495955Y190635D01*
G01X510362Y174884D02*
X495005Y190241D01*
G01X495955Y190635D02*
Y198055D01*
G01Y200205D02*
Y201555D01*
G01Y203705D02*
Y205055D01*
G01X495005Y190241D02*
Y205055D01*
G01X491595Y203000D02*
Y188618D01*
G01X490645Y203000D02*
Y188538D01*
G01X491595Y188618D02*
X492209Y184953D01*
G01X490645Y188538D02*
X491331Y184444D01*
G01X492209Y184953D02*
X493253Y184098D01*
G01D02*
X493816Y184154D01*
G01X494917Y182734D02*
X495961Y181879D01*
G01D02*
X496524Y181935D01*
G01X497625Y180515D02*
X498669Y179660D01*
G01D02*
X499232Y179716D01*
G01X500332Y178296D02*
X501376Y177441D01*
G01D02*
X501939Y177497D01*
G01X503040Y176077D02*
X508396Y171687D01*
G01X491331Y184444D02*
X507686Y171040D01*
G01X508396Y171687D02*
X518229Y157109D01*
G01X507686Y171040D02*
X517544Y156424D01*
G01X486256Y202262D02*
Y200693D01*
G01X487206Y202262D02*
Y200610D01*
G01X486256Y200693D02*
X482673Y180238D01*
G01X487206Y200610D02*
X486974Y199281D01*
G01X486256Y200693D02*
X482673Y180238D01*
G01X486602Y197162D02*
X486370Y195833D01*
G01X486256Y200693D02*
X482673Y180238D01*
G01X485998Y193714D02*
X485764Y192377D01*
G01X486256Y200693D02*
X482673Y180238D01*
G01X485392Y190258D02*
X485160Y188929D01*
G01X486256Y200693D02*
X482673Y180238D01*
G01X484788Y186810D02*
X484556Y185481D01*
G01X486256Y200693D02*
X482673Y180238D01*
G01X484184Y183362D02*
X483640Y180247D01*
G01X482673Y180238D02*
X486620Y159935D01*
G01X483640Y180247D02*
X483897Y178922D01*
G01X482673Y180238D02*
X486620Y159935D01*
G01X484308Y176811D02*
X484565Y175486D01*
G01X482673Y180238D02*
X486620Y159935D01*
G01X484976Y173375D02*
X485233Y172050D01*
G01X482673Y180238D02*
X486620Y159935D01*
G01X485644Y169939D02*
X485901Y168614D01*
G01X482673Y180238D02*
X486620Y159935D01*
G01X486312Y166503D02*
X486569Y165178D01*
G01X482673Y180238D02*
X486620Y159935D01*
G01X486980Y163067D02*
X487516Y160306D01*
G01D02*
X488270Y159187D01*
G01X482823Y158850D02*
X481965Y163271D01*
G01X481554Y165382D02*
X481297Y166707D01*
G01X480886Y168818D02*
X480629Y170143D01*
G01X480218Y172254D02*
X479961Y173579D01*
G01X479550Y175690D02*
X479293Y177015D01*
G01X478882Y179126D02*
X478625Y180451D01*
G01D02*
X479086Y182829D01*
G01X479497Y184940D02*
X479754Y186265D01*
G01X480165Y188376D02*
X480422Y189701D01*
G01X480833Y191812D02*
X482717Y201517D01*
G01X481767Y203406D02*
Y201609D01*
G01X482717Y201517D02*
Y203406D01*
G01X500618Y205407D02*
Y192201D01*
G01X499668Y205407D02*
Y191807D01*
G01X500618Y192201D02*
X515284Y177535D01*
G01X499668Y191807D02*
X514547Y176927D01*
G01X515284Y177535D02*
X524077Y164500D01*
G01X514547Y176927D02*
X523392Y163815D01*
G01X521000Y159502D02*
X520479Y159853D01*
G01D02*
X510347Y174873D01*
G01X521164Y160538D02*
X521000Y160781D01*
G01X520479Y159853D02*
X510347Y174873D01*
G01X521000Y160781D02*
X511035Y175555D01*
G01X510362Y174884D02*
X495005Y190241D01*
G01X511035Y175555D02*
X495955Y190635D01*
G01X495005Y190241D02*
Y205055D01*
G01X495955Y190635D02*
Y198055D01*
G01X495005Y190241D02*
Y205055D01*
G01X495955Y200205D02*
Y201555D01*
G01X495005Y190241D02*
Y205055D01*
G01X495955Y203705D02*
Y205055D01*
G01X490645Y203000D02*
Y188538D01*
G01X491595Y203000D02*
Y188618D01*
G01X490645Y188538D02*
X491331Y184444D01*
G01X491595Y188618D02*
X492209Y184953D01*
G01X491331Y184444D02*
X507686Y171040D01*
G01X492209Y184953D02*
X493253Y184098D01*
G01X491331Y184444D02*
X507686Y171040D01*
G01X493253Y184098D02*
X493816Y184154D01*
G01X491331Y184444D02*
X507686Y171040D01*
G01X494917Y182734D02*
X495961Y181879D01*
G01X491331Y184444D02*
X507686Y171040D01*
G01X495961Y181879D02*
X496524Y181935D01*
G01X491331Y184444D02*
X507686Y171040D01*
G01X497625Y180515D02*
X498669Y179660D01*
G01X491331Y184444D02*
X507686Y171040D01*
G01X498669Y179660D02*
X499232Y179716D01*
G01X491331Y184444D02*
X507686Y171040D01*
G01X500332Y178296D02*
X501376Y177441D01*
G01X491331Y184444D02*
X507686Y171040D01*
G01X501376Y177441D02*
X501939Y177497D01*
G01X491331Y184444D02*
X507686Y171040D01*
G01X503040Y176077D02*
X508396Y171687D01*
G01X507686Y171040D02*
X517544Y156424D01*
G01X508396Y171687D02*
X518229Y157109D01*
G01X487206Y202262D02*
Y200610D01*
G01X486256Y202262D02*
Y200693D01*
G01X487206Y200610D02*
X486974Y199281D01*
G01X486602Y197162D02*
X486370Y195833D01*
G01X485998Y193714D02*
X485764Y192377D01*
G01X485392Y190258D02*
X485160Y188929D01*
G01X484788Y186810D02*
X484556Y185481D01*
G01X484184Y183362D02*
X483640Y180247D01*
G01X486256Y200693D02*
X482673Y180238D01*
G01X483640Y180247D02*
X483897Y178922D01*
G01X484308Y176811D02*
X484565Y175486D01*
G01X484976Y173375D02*
X485233Y172050D01*
G01X485644Y169939D02*
X485901Y168614D01*
G01X486312Y166503D02*
X486569Y165178D01*
G01X486980Y163067D02*
X487516Y160306D01*
G01X482673Y180238D02*
X486620Y159935D01*
G01X487516Y160306D02*
X488270Y159187D01*
G01X514150Y202350D02*
Y198009D01*
G01X513200Y202400D02*
Y197615D01*
G01X514150Y198009D02*
X525303Y186856D01*
G01X513200Y197615D02*
X524566Y186248D01*
G01X525303Y186856D02*
X533348Y174930D01*
G01X524566Y186248D02*
X532663Y174245D01*
G01X533348Y174930D02*
X549282Y164181D01*
G01X532663Y174245D02*
X548905Y163289D01*
G01X547850Y158458D02*
X529059Y171130D01*
G01X547850Y158458D02*
X529059Y171130D01*
G01X548211Y159361D02*
X529744Y171815D01*
G01X529059Y171130D02*
X521537Y182283D01*
G01X529744Y171815D02*
X522283Y182876D01*
G01X521537Y182283D02*
X521000Y182859D01*
G01D02*
X508700Y196060D01*
G01X522283Y182876D02*
X509650Y196434D01*
G01X508700Y196060D02*
Y204632D01*
G01X509650Y196434D02*
Y201132D01*
G01X508700Y196060D02*
Y204632D01*
G01X509650Y203282D02*
Y204632D01*
G01X546345Y155020D02*
X527040Y168041D01*
G01X545972Y154125D02*
X526355Y167356D01*
G01X527040Y168041D02*
X518916Y180084D01*
G01X526355Y167356D02*
X518179Y179476D01*
G01X518916Y180084D02*
X505149Y193849D01*
G01X518179Y179476D02*
X504199Y193455D01*
G01X505149Y193849D02*
Y206468D01*
G01X504199Y193455D02*
Y206468D01*
G01X538641Y198675D02*
X541445Y195871D01*
G01X537969Y198003D02*
X540708Y195263D01*
G01X532076Y197479D02*
X536344Y193210D01*
G01X532826Y198073D02*
X537081Y193818D01*
G01X536344Y193210D02*
X541760Y185181D01*
G01X537081Y193818D02*
X542445Y185866D01*
G01X522372Y204254D02*
Y200814D01*
G01X523322Y204254D02*
Y201209D01*
G01X522372Y200814D02*
X531920Y191266D01*
G01X523322Y201209D02*
X524276Y200255D01*
G01X522372Y200814D02*
X531920Y191266D01*
G01X525797Y198734D02*
X526751Y197780D01*
G01X522372Y200814D02*
X531920Y191266D01*
G01X528272Y196259D02*
X532657Y191874D01*
G01X531920Y191266D02*
X538624Y181326D01*
G01X532657Y191874D02*
X539309Y182011D01*
G01X538624Y181326D02*
X551467Y172663D01*
G01X539309Y182011D02*
X540428Y181257D01*
G01X538624Y181326D02*
X551467Y172663D01*
G01X538624Y181326D02*
X551467Y172663D01*
G01X538624Y181326D02*
X551467Y172663D01*
G01X538624Y181326D02*
X551467Y172663D01*
G01X538624Y181326D02*
X551467Y172663D01*
G01X538624Y181326D02*
X551467Y172663D01*
G01X551514Y168480D02*
X536130Y178858D01*
G01X551143Y167584D02*
X535445Y178173D01*
G01X536130Y178858D02*
X529161Y189189D01*
G01X535445Y178173D02*
X528424Y188581D01*
G01X529161Y189189D02*
X518700Y199650D01*
G01X528424Y188581D02*
X517750Y199256D01*
G01X518700Y199650D02*
Y201055D01*
G01X517750Y199256D02*
Y201055D01*
G01X513200Y202400D02*
Y197615D01*
G01X514150Y202350D02*
Y198009D01*
G01X513200Y197615D02*
X524566Y186248D01*
G01X514150Y198009D02*
X525303Y186856D01*
G01X524566Y186248D02*
X532663Y174245D01*
G01X525303Y186856D02*
X533348Y174930D01*
G01X532663Y174245D02*
X548905Y163289D01*
G01X533348Y174930D02*
X549282Y164181D01*
G01X548211Y159361D02*
X529744Y171815D01*
G01X547850Y158458D02*
X529059Y171130D01*
G01X529744Y171815D02*
X522283Y182876D01*
G01X529059Y171130D02*
X521537Y182283D01*
G01X522283Y182876D02*
X509650Y196434D01*
G01X521537Y182283D02*
X521000Y182859D01*
G01X522283Y182876D02*
X509650Y196434D01*
G01X521000Y182859D02*
X508700Y196060D01*
G01X509650Y196434D02*
Y201132D01*
G01Y203282D02*
Y204632D01*
G01X508700Y196060D02*
Y204632D01*
G01X545972Y154125D02*
X526355Y167356D01*
G01X546345Y155020D02*
X527040Y168041D01*
G01X526355Y167356D02*
X518179Y179476D01*
G01X527040Y168041D02*
X518916Y180084D01*
G01X518179Y179476D02*
X504199Y193455D01*
G01X518916Y180084D02*
X505149Y193849D01*
G01X504199Y193455D02*
Y206468D01*
G01X505149Y193849D02*
Y206468D01*
G01X537969Y198003D02*
X540708Y195263D01*
G01X538641Y198675D02*
X541445Y195871D01*
G01X532826Y198073D02*
X537081Y193818D01*
G01X532076Y197479D02*
X536344Y193210D01*
G01X537081Y193818D02*
X542445Y185866D01*
G01X536344Y193210D02*
X541760Y185181D01*
G01X523322Y204254D02*
Y201209D01*
G01X522372Y204254D02*
Y200814D01*
G01X523322Y201209D02*
X524276Y200255D01*
G01X525797Y198734D02*
X526751Y197780D01*
G01X528272Y196259D02*
X532657Y191874D01*
G01X522372Y200814D02*
X531920Y191266D01*
G01X532657Y191874D02*
X539309Y182011D01*
G01X531920Y191266D02*
X538624Y181326D01*
G01X539309Y182011D02*
X540428Y181257D01*
G01X538624Y181326D02*
X551467Y172663D01*
G01X551143Y167584D02*
X535445Y178173D01*
G01X551514Y168480D02*
X536130Y178858D01*
G01X535445Y178173D02*
X528424Y188581D01*
G01X536130Y178858D02*
X529161Y189189D01*
G01X528424Y188581D02*
X517750Y199256D01*
G01X529161Y189189D02*
X518700Y199650D01*
G01X517750Y199256D02*
Y201055D01*
G01X518700Y199650D02*
Y201055D01*
G01X521000Y159502D02*
X520479Y159853D01*
G01X521164Y160538D02*
X521000Y160781D01*
G01D02*
X511035Y175555D01*
G01X520479Y159853D02*
X510347Y174873D01*
G01X511035Y175555D02*
X495955Y190635D01*
G01X510362Y174884D02*
X495005Y190241D01*
G01X495955Y190635D02*
Y198055D01*
G01Y200205D02*
Y201555D01*
G01Y203705D02*
Y205055D01*
G01X495005Y190241D02*
Y205055D01*
G01X482823Y158850D02*
X481965Y163271D01*
G01X481554Y165382D02*
X481297Y166707D01*
G01X480886Y168818D02*
X480629Y170143D01*
G01X480218Y172254D02*
X479961Y173579D01*
G01X479550Y175690D02*
X479293Y177015D01*
G01X478882Y179126D02*
X478625Y180451D01*
G01D02*
X479086Y182829D01*
G01X479497Y184940D02*
X479754Y186265D01*
G01X480165Y188376D02*
X480422Y189701D01*
G01X480833Y191812D02*
X482717Y201517D01*
G01X481767Y203406D02*
Y201609D01*
G01X482717Y201517D02*
Y203406D01*
G01X547850Y158458D02*
X529059Y171130D01*
G01X547850Y158458D02*
X529059Y171130D01*
G01X548211Y159361D02*
X529744Y171815D01*
G01X529059Y171130D02*
X521537Y182283D01*
G01X529744Y171815D02*
X522283Y182876D01*
G01X521537Y182283D02*
X521000Y182859D01*
G01D02*
X508700Y196060D01*
G01X522283Y182876D02*
X509650Y196434D01*
G01X508700Y196060D02*
Y204632D01*
G01X509650Y196434D02*
Y201132D01*
G01X508700Y196060D02*
Y204632D01*
G01X509650Y203282D02*
Y204632D01*
G01X491595Y203000D02*
Y188618D01*
G01X490645Y203000D02*
Y188538D01*
G01X491595Y188618D02*
X492209Y184953D01*
G01X490645Y188538D02*
X491331Y184444D01*
G01X492209Y184953D02*
X493253Y184098D01*
G01D02*
X493816Y184154D01*
G01X494917Y182734D02*
X495961Y181879D01*
G01D02*
X496524Y181935D01*
G01X497625Y180515D02*
X498669Y179660D01*
G01D02*
X499232Y179716D01*
G01X500332Y178296D02*
X501376Y177441D01*
G01D02*
X501939Y177497D01*
G01X503040Y176077D02*
X508396Y171687D01*
G01X491331Y184444D02*
X507686Y171040D01*
G01X508396Y171687D02*
X518229Y157109D01*
G01X507686Y171040D02*
X517544Y156424D01*
G01X551514Y168480D02*
X536130Y178858D01*
G01X551143Y167584D02*
X535445Y178173D01*
G01X536130Y178858D02*
X529161Y189189D01*
G01X535445Y178173D02*
X528424Y188581D01*
G01X529161Y189189D02*
X518700Y199650D01*
G01X528424Y188581D02*
X517750Y199256D01*
G01X518700Y199650D02*
Y201055D01*
G01X517750Y199256D02*
Y201055D01*
G01X545972Y154125D02*
X526355Y167356D01*
G01X546345Y155020D02*
X527040Y168041D01*
G01X526355Y167356D02*
X518179Y179476D01*
G01X527040Y168041D02*
X518916Y180084D01*
G01X518179Y179476D02*
X504199Y193455D01*
G01X518916Y180084D02*
X505149Y193849D01*
G01X504199Y193455D02*
Y206468D01*
G01X505149Y193849D02*
Y206468D01*
G01X537969Y198003D02*
X540708Y195263D01*
G01X538641Y198675D02*
X541445Y195871D01*
G01X510550Y418187D02*
Y444991D01*
G01X511500Y418187D02*
Y445385D01*
G01X510550Y444991D02*
X506747Y448794D01*
G01X511500Y445385D02*
X507216Y449670D01*
G01X506747Y448794D02*
X484511Y453242D01*
G01X507216Y449670D02*
X484513Y454211D01*
G01X511500Y418187D02*
Y445385D01*
G01X510550Y418187D02*
Y444991D01*
G01X511500Y445385D02*
X507216Y449670D01*
G01X510550Y444991D02*
X506747Y448794D01*
G01X507216Y449670D02*
X484513Y454211D01*
G01X506747Y448794D02*
X484511Y453242D01*
G01X519202Y448993D02*
Y420739D01*
G01X518252D02*
Y448599D01*
G01X509844Y458351D02*
X519202Y448993D01*
G01X518252Y448599D02*
X509375Y457475D01*
G01X481699Y463979D02*
X509844Y458351D01*
G01X509375Y457475D02*
X508051Y457740D01*
G01X481699Y463979D02*
X509844Y458351D01*
G01X505845Y458181D02*
X504521Y458446D01*
G01X481699Y463979D02*
X509844Y458351D01*
G01X502315Y458887D02*
X500991Y459152D01*
G01X481699Y463979D02*
X509844Y458351D01*
G01X498785Y459593D02*
X481699Y463010D01*
G01X530678Y418444D02*
Y452628D01*
G01X531628Y418444D02*
Y453022D01*
G01X530678Y452628D02*
X511310Y471995D01*
G01X531628Y453022D02*
X511779Y472871D01*
G01X514400Y420550D02*
Y446900D01*
G01X515350Y420550D02*
Y447294D01*
G01X514400Y446900D02*
X508306Y452994D01*
G01X515350Y447294D02*
X508775Y453869D01*
G01X508306Y452993D02*
X506369Y453381D01*
G01X504162Y453822D02*
X502839Y454087D01*
G01X500632Y454528D02*
X499309Y454793D01*
G01X497102Y455234D02*
X484260Y457803D01*
G01X508775Y453869D02*
X484260Y458772D01*
G01X535573Y454470D02*
Y417251D01*
G01X534623D02*
Y454076D01*
G01X513419Y476625D02*
X535573Y454470D01*
G01X534623Y454076D02*
X512950Y475749D01*
G01X540310Y453790D02*
X513482Y480617D01*
G01X541260Y454184D02*
X513951Y481493D01*
G01X522150Y450149D02*
Y421716D01*
G01X523100D02*
Y450543D01*
G01X510524Y461775D02*
X522150Y450149D01*
G01X523100Y450543D02*
X510993Y462651D01*
G01X480437Y467793D02*
X510524Y461775D01*
G01X510993Y462651D02*
X480437Y468762D01*
G01X527023Y423060D02*
Y452171D01*
G01X526073Y423060D02*
Y451777D01*
G01X527023Y452171D02*
X510992Y468202D01*
G01X526073Y451777D02*
X510523Y467326D01*
G01X509375Y457475D02*
X508051Y457740D01*
G01X505845Y458181D02*
X504521Y458446D01*
G01X502315Y458887D02*
X500991Y459152D01*
G01X498785Y459593D02*
X481699Y463010D01*
G01Y463979D02*
X509844Y458351D01*
G01X518252Y448599D02*
X509375Y457475D01*
G01X509844Y458351D02*
X519202Y448993D01*
G01X518252Y420739D02*
Y448599D01*
G01X519202Y448993D02*
Y420739D01*
G01X531628Y418444D02*
Y453022D01*
G01X530678Y418444D02*
Y452628D01*
G01X531628Y453022D02*
X511779Y472871D01*
G01X530678Y452628D02*
X511310Y471995D01*
G01X515350Y420550D02*
Y447294D01*
G01X514400Y420550D02*
Y446900D01*
G01X515350Y447294D02*
X508775Y453869D01*
G01X514400Y446900D02*
X508306Y452994D01*
G01X508775Y453869D02*
X484260Y458772D01*
G01X508306Y452993D02*
X506369Y453381D01*
G01X508775Y453869D02*
X484260Y458772D01*
G01X504162Y453822D02*
X502839Y454087D01*
G01X508775Y453869D02*
X484260Y458772D01*
G01X500632Y454528D02*
X499309Y454793D01*
G01X508775Y453869D02*
X484260Y458772D01*
G01X497102Y455234D02*
X484260Y457803D01*
G01X534623Y454076D02*
X512950Y475749D01*
G01X513419Y476625D02*
X535573Y454470D01*
G01X534623Y417251D02*
Y454076D01*
G01X535573Y454470D02*
Y417251D01*
G01X541260Y454184D02*
X513951Y481493D01*
G01X540310Y453790D02*
X513482Y480617D01*
G01X510993Y462651D02*
X480437Y468762D01*
G01Y467793D02*
X510524Y461775D01*
G01X523100Y450543D02*
X510993Y462651D01*
G01X510524Y461775D02*
X522150Y450149D01*
G01X523100Y421716D02*
Y450543D01*
G01X522150Y450149D02*
Y421716D01*
G01X526073Y423060D02*
Y451777D01*
G01X527023Y423060D02*
Y452171D01*
G01X526073Y451777D02*
X510523Y467326D01*
G01X527023Y452171D02*
X510992Y468202D01*
G01X478702Y425389D02*
X485209Y418882D01*
G01X485881Y419554D02*
X479170Y426265D01*
G01X485881Y419554D02*
X479170Y426265D01*
G01X478702Y425389D02*
X485209Y418882D01*
G01X510042Y411096D02*
Y412591D01*
G01X509092Y411096D02*
Y412197D01*
G01X510042Y412591D02*
X484349Y438285D01*
G01X509092Y412197D02*
X483881Y437409D01*
G01X481093Y434084D02*
X503073Y412104D01*
G01X503745Y412776D02*
X481561Y434960D01*
G01X481093Y434084D02*
X503073Y412104D01*
G01X503745Y412776D02*
X481561Y434960D01*
G01X480433Y430555D02*
X492310Y418678D01*
G01X479965Y429679D02*
X491638Y418006D01*
G01X478702Y425389D02*
X485209Y418882D01*
G01X485881Y419554D02*
X479170Y426265D01*
G01X509092Y411096D02*
Y412197D01*
G01X510042Y411096D02*
Y412591D01*
G01X509092Y412197D02*
X483881Y437409D01*
G01X510042Y412591D02*
X484349Y438285D01*
G01X503745Y412776D02*
X481561Y434960D01*
G01X481093Y434084D02*
X503073Y412104D01*
G01X503745Y412776D02*
X481561Y434960D01*
G01X481093Y434084D02*
X503073Y412104D01*
G01X479965Y429679D02*
X491638Y418006D01*
G01X480433Y430555D02*
X492310Y418678D01*
G01X485881Y419554D02*
X479170Y426265D01*
G01X478702Y425389D02*
X485209Y418882D01*
G01X510042Y411096D02*
Y412591D01*
G01X509092Y411096D02*
Y412197D01*
G01X510042Y412591D02*
X484349Y438285D01*
G01X509092Y412197D02*
X483881Y437409D01*
G01X480433Y430555D02*
X492310Y418678D01*
G01X479965Y429679D02*
X491638Y418006D01*
G01X509092Y411096D02*
Y412197D01*
G01X510042Y411096D02*
Y412591D01*
G01X509092Y412197D02*
X483881Y437409D01*
G01X510042Y412591D02*
X484349Y438285D01*
G01X479965Y429679D02*
X491638Y418006D01*
G01X480433Y430555D02*
X492310Y418678D01*
G01X540310Y453790D02*
X513482Y480617D01*
G01X541260Y454184D02*
X513951Y481493D01*
G01X541260Y454184D02*
X513951Y481493D01*
G01X540310Y453790D02*
X513482Y480617D01*
G01X511310Y471995D02*
X483142Y477627D01*
G01X511779Y472871D02*
X483140Y478597D01*
G01X481995Y482912D02*
X499299Y479450D01*
G01X501505Y479009D02*
X502829Y478744D01*
G01X505035Y478302D02*
X506359Y478038D01*
G01X508565Y477596D02*
X509889Y477331D01*
G01X512095Y476890D02*
X513419Y476625D01*
G01X512950Y475749D02*
X481995Y481943D01*
G01X513482Y480617D02*
X512158Y480882D01*
G01X509952Y481323D02*
X508628Y481588D01*
G01X506422Y482029D02*
X483166Y486682D01*
G01X513951Y481493D02*
X483163Y487652D01*
G01X510992Y468202D02*
X482756Y473849D01*
G01X510523Y467326D02*
X496876Y470056D01*
G01X510992Y468202D02*
X482756Y473849D01*
G01X494670Y470497D02*
X493346Y470762D01*
G01X510992Y468202D02*
X482756Y473849D01*
G01X491140Y471203D02*
X489816Y471468D01*
G01X510992Y468202D02*
X482756Y473849D01*
G01X487610Y471909D02*
X486286Y472174D01*
G01X510992Y468202D02*
X482756Y473849D01*
G01X484080Y472615D02*
X482756Y472880D01*
G01X511779Y472871D02*
X483140Y478597D01*
G01X511310Y471995D02*
X483142Y477627D01*
G01X512950Y475749D02*
X481995Y481943D01*
G01Y482912D02*
X499299Y479450D01*
G01X512950Y475749D02*
X481995Y481943D01*
G01X501505Y479009D02*
X502829Y478744D01*
G01X512950Y475749D02*
X481995Y481943D01*
G01X505035Y478302D02*
X506359Y478038D01*
G01X512950Y475749D02*
X481995Y481943D01*
G01X508565Y477596D02*
X509889Y477331D01*
G01X512950Y475749D02*
X481995Y481943D01*
G01X512095Y476890D02*
X513419Y476625D01*
G01X513951Y481493D02*
X483163Y487652D01*
G01X513482Y480617D02*
X512158Y480882D01*
G01X513951Y481493D02*
X483163Y487652D01*
G01X509952Y481323D02*
X508628Y481588D01*
G01X513951Y481493D02*
X483163Y487652D01*
G01X506422Y482029D02*
X483166Y486682D01*
G01X510523Y467326D02*
X496876Y470056D01*
G01X494670Y470497D02*
X493346Y470762D01*
G01X491140Y471203D02*
X489816Y471468D01*
G01X487610Y471909D02*
X486286Y472174D01*
G01X484080Y472615D02*
X482756Y472880D01*
G01X510992Y468202D02*
X482756Y473849D01*
G01X513482Y480617D02*
X512158Y480882D01*
G01X509952Y481323D02*
X508628Y481588D01*
G01X506422Y482029D02*
X483166Y486682D01*
G01X513951Y481493D02*
X483163Y487652D01*
G01X513951Y481493D02*
X483163Y487652D01*
G01X513482Y480617D02*
X512158Y480882D01*
G01X513951Y481493D02*
X483163Y487652D01*
G01X509952Y481323D02*
X508628Y481588D01*
G01X513951Y481493D02*
X483163Y487652D01*
G01X506422Y482029D02*
X483166Y486682D01*
G01X564361Y117311D02*
X573868Y112659D01*
G01X564666Y118220D02*
X574177Y113566D01*
G01X573868Y112659D02*
X642639Y98637D01*
G01X574177Y113566D02*
X642815Y99571D01*
G01X591766Y117543D02*
X599717Y114874D01*
G01X591523Y116622D02*
X599605Y113909D01*
G01X599717Y114874D02*
X610171Y115837D01*
G01X599605Y113909D02*
X609968Y114864D01*
G01X564666Y118220D02*
X574177Y113566D01*
G01X564361Y117311D02*
X573868Y112659D01*
G01X574177Y113566D02*
X642815Y99571D01*
G01X573868Y112659D02*
X642639Y98637D01*
G01X591523Y116622D02*
X599605Y113909D01*
G01X591766Y117543D02*
X599717Y114874D01*
G01X599605Y113909D02*
X609968Y114864D01*
G01X599717Y114874D02*
X610171Y115837D01*
G01X543984Y131273D02*
X592866Y121770D01*
G01D02*
X604928Y122403D01*
G01X592799Y120815D02*
X604919Y121451D01*
G01X544460Y149605D02*
X594136Y140222D01*
G01X544829Y150503D02*
X594323Y141154D01*
G01X594136Y140222D02*
X603483Y138237D01*
G01X594323Y141154D02*
X603491Y139207D01*
G01X601006Y134805D02*
X541818Y146606D01*
G01X594741Y135085D02*
X601002Y133837D01*
G01X611085Y136722D02*
X601006Y134805D01*
G01X601002Y133837D02*
X611116Y135760D01*
G01X601006Y134805D02*
X541818Y146606D01*
G01X594741Y135085D02*
X541445Y145711D01*
G01X539840Y142533D02*
X540746Y142358D01*
G01X539840Y142533D02*
X540746Y142358D01*
G01X539840Y142533D02*
X540746Y142358D01*
G01D02*
X596724Y130077D01*
G01X540555Y141427D02*
X596710Y129107D01*
G01X596724Y130077D02*
X610015Y132599D01*
G01X596710Y129107D02*
X610019Y131632D01*
G01X595343Y124838D02*
X609026Y127473D01*
G01X595344Y125806D02*
X609019Y128440D01*
G01X543984Y131273D02*
X592866Y121770D01*
G01X592799Y120815D02*
X604919Y121451D01*
G01X592866Y121770D02*
X604928Y122403D01*
G01X591523Y116622D02*
X599605Y113909D01*
G01X591766Y117543D02*
X599717Y114874D01*
G01X599605Y113909D02*
X609968Y114864D01*
G01X599717Y114874D02*
X610171Y115837D01*
G01X544829Y150503D02*
X594323Y141154D01*
G01X544460Y149605D02*
X594136Y140222D01*
G01X594323Y141154D02*
X603491Y139207D01*
G01X594136Y140222D02*
X603483Y138237D01*
G01X601002Y133837D02*
X611116Y135760D01*
G01X611085Y136722D02*
X601006Y134805D01*
G01X594741Y135085D02*
X601002Y133837D01*
G01X594741Y135085D02*
X541445Y145711D01*
G01X601006Y134805D02*
X541818Y146606D01*
G01X540555Y141427D02*
X596710Y129107D01*
G01X539840Y142533D02*
X540746Y142358D01*
G01X540555Y141427D02*
X596710Y129107D01*
G01X540746Y142358D02*
X596724Y130077D01*
G01X596710Y129107D02*
X610019Y131632D01*
G01X596724Y130077D02*
X610015Y132599D01*
G01X595344Y125806D02*
X609019Y128440D01*
G01X595343Y124838D02*
X609026Y127473D01*
G01X549282Y164181D02*
X608143Y151865D01*
G01X548905Y163289D02*
X608136Y150895D01*
G01X605870Y146544D02*
X548473Y158353D01*
G01X605875Y147513D02*
X548647Y159288D01*
G01X605870Y146544D02*
X548473Y158353D01*
G01X604884Y143411D02*
X546345Y155020D01*
G01X604882Y142442D02*
X545972Y154125D01*
G01X548905Y163289D02*
X608136Y150895D01*
G01X549282Y164181D02*
X608143Y151865D01*
G01X605875Y147513D02*
X548647Y159288D01*
G01X605870Y146544D02*
X548473Y158353D01*
G01X605875Y147513D02*
X548647Y159288D01*
G01X604882Y142442D02*
X545972Y154125D01*
G01X604884Y143411D02*
X546345Y155020D01*
G01X601006Y134805D02*
X541818Y146606D01*
G01X594741Y135085D02*
X601002Y133837D01*
G01X611085Y136722D02*
X601006Y134805D01*
G01X601002Y133837D02*
X611116Y135760D01*
G01X601006Y134805D02*
X541818Y146606D01*
G01X594741Y135085D02*
X541445Y145711D01*
G01X543984Y131273D02*
X592866Y121770D01*
G01X592799Y120815D02*
X604919Y121451D01*
G01X592866Y121770D02*
X604928Y122403D01*
G01X605870Y146544D02*
X548473Y158353D01*
G01X605875Y147513D02*
X548647Y159288D01*
G01X605870Y146544D02*
X548473Y158353D01*
G01X539840Y142533D02*
X540746Y142358D01*
G01X539840Y142533D02*
X540746Y142358D01*
G01X539840Y142533D02*
X540746Y142358D01*
G01D02*
X596724Y130077D01*
G01X540555Y141427D02*
X596710Y129107D01*
G01X596724Y130077D02*
X610015Y132599D01*
G01X596710Y129107D02*
X610019Y131632D01*
G01X604882Y142442D02*
X545972Y154125D01*
G01X604884Y143411D02*
X546345Y155020D01*
G01X548473Y158353D02*
X547850Y158458D01*
G01X548473Y158353D02*
X547850Y158458D01*
G01X548647Y159288D02*
X548212Y159360D01*
G01X558856Y185180D02*
X612788Y171787D01*
G01X612810Y172761D02*
X559248Y186062D01*
G01X550219Y191001D02*
X558856Y185180D01*
G01X559248Y186062D02*
X556710Y187772D01*
G01X550219Y191001D02*
X558856Y185180D01*
G01X555481Y189083D02*
X554926Y188975D01*
G01X550219Y191001D02*
X558856Y185180D01*
G01X554926Y188975D02*
X553807Y189729D01*
G01X550219Y191001D02*
X558856Y185180D01*
G01X552578Y191039D02*
X552023Y190931D01*
G01X550219Y191001D02*
X558856Y185180D01*
G01X552023Y190931D02*
X550904Y191685D01*
G01X543378Y201190D02*
X550218Y191000D01*
G01X550904Y191685D02*
X550055Y192950D01*
G01X543378Y201190D02*
X550218Y191000D01*
G01X548856Y194736D02*
X548104Y195856D01*
G01X543378Y201190D02*
X550218Y191000D01*
G01X546905Y197642D02*
X546153Y198762D01*
G01X543378Y201190D02*
X550218Y191000D01*
G01X544950Y200552D02*
X544201Y201668D01*
G01X543151Y201581D02*
X543378Y201191D01*
G01X544201Y201668D02*
X543975Y202058D01*
G01X541445Y195871D02*
X542199Y194752D01*
G01X543402Y192969D02*
X545804Y189407D01*
G01X540708Y195263D02*
X545119Y188722D01*
G01X545804Y189407D02*
X546923Y188652D01*
G01D02*
X547478Y188760D01*
G01X548706Y187449D02*
X549825Y186695D01*
G01D02*
X550380Y186802D01*
G01X551608Y185491D02*
X552727Y184737D01*
G01D02*
X553282Y184844D01*
G01X554510Y183533D02*
X556294Y182330D01*
G01X545119Y188722D02*
X555901Y181449D01*
G01X556294Y182330D02*
X601747Y170876D01*
G01X555901Y181449D02*
X601514Y169953D01*
G01X556294Y182330D02*
X601747Y170876D01*
G01X601514Y169953D02*
X601876Y169862D01*
G01X541760Y185181D02*
X554127Y176839D01*
G01X542445Y185866D02*
X543441Y185195D01*
G01X541760Y185181D02*
X554127Y176839D01*
G01X543441Y185195D02*
X543996Y185302D01*
G01X541760Y185181D02*
X554127Y176839D01*
G01X545224Y183991D02*
X546343Y183237D01*
G01X541760Y185181D02*
X554127Y176839D01*
G01X546343Y183237D02*
X546898Y183344D01*
G01X541760Y185181D02*
X554127Y176839D01*
G01X548126Y182033D02*
X549245Y181279D01*
G01X541760Y185181D02*
X554127Y176839D01*
G01X549245Y181279D02*
X549800Y181387D01*
G01X541760Y185181D02*
X554127Y176839D01*
G01X551028Y180075D02*
X554500Y177734D01*
G01X554127Y176839D02*
X556441Y176378D01*
G01X554500Y177734D02*
X556645Y177307D01*
G01X556441Y176378D02*
X610263Y163402D01*
G01X556645Y177307D02*
X610285Y164375D01*
G01X540428Y181257D02*
X540983Y181364D01*
G01X542211Y180053D02*
X543330Y179299D01*
G01D02*
X543885Y179406D01*
G01X545113Y178095D02*
X546232Y177341D01*
G01D02*
X546787Y177449D01*
G01X548015Y176138D02*
X551853Y173549D01*
G01X551467Y172663D02*
X609123Y159304D01*
G01X551853Y173549D02*
X609140Y160276D01*
G01X602198Y157544D02*
X564759Y165749D01*
G01X601995Y156616D02*
X564556Y164821D01*
G01X564759Y165749D02*
X558480Y167126D01*
G01X564556Y164821D02*
X558287Y166195D01*
G01X558480Y167126D02*
X551514Y168480D01*
G01X558287Y166195D02*
X551143Y167584D01*
G01X548647Y159288D02*
X548212Y159360D01*
G01X548647Y159288D02*
X548212Y159360D01*
G01X548473Y158353D02*
X547850Y158458D01*
G01X548647Y159288D02*
X548212Y159360D01*
G01X549256Y204689D02*
X546804D01*
G01D02*
X546484Y205009D01*
G01X545812Y204337D02*
X546410Y203739D01*
G01X550129Y203817D02*
X549256Y204689D01*
G01D02*
X546804D01*
G01X546410Y203739D02*
X548862D01*
G01X550129Y203817D02*
X549256Y204689D01*
G01X548862Y203739D02*
X549392Y203209D01*
G01X552942Y199650D02*
X550129Y203817D01*
G01X549392Y203209D02*
X551934Y199444D01*
G01X552568Y197720D02*
X552942Y199650D01*
G01X551934Y199444D02*
X551560Y197514D01*
G01X554008Y195589D02*
X552568Y197720D01*
G01X551560Y197514D02*
X553441Y194731D01*
G01X554703Y195454D02*
X554008Y195589D01*
G01X553441Y194731D02*
X554908Y194446D01*
G01X558638Y198109D02*
X554703Y195454D01*
G01D02*
X554008Y195589D01*
G01X554908Y194446D02*
X558843Y197101D01*
G01X559494Y197944D02*
X559337Y197974D01*
G01D02*
X559334D01*
G01D02*
X558638Y198109D01*
G01D02*
X554703Y195454D01*
G01X558843Y197101D02*
X559152Y197041D01*
G01X560035Y197839D02*
X559494Y197943D01*
G01Y197944D02*
X559337Y197974D01*
G01D02*
X559334D01*
G01D02*
X558638Y198109D01*
G01X559160Y197039D02*
X559467Y196980D01*
G01X561562Y195573D02*
X560035Y197839D01*
G01X559467Y196980D02*
X560554Y195368D01*
G01X561277Y194105D02*
X561562Y195573D01*
G01X560554Y195368D02*
X560418Y194673D01*
G01X559981Y193231D02*
X561277Y194105D01*
G01X560418Y194673D02*
X559770Y194236D01*
G01X559981Y193231D02*
X561277Y194105D01*
G01X559770Y194235D02*
X559123Y193799D01*
G01X559679Y191681D02*
X559981Y193231D01*
G01X559123Y193799D02*
X558671Y191476D01*
G01X560371Y190655D02*
X559679Y191681D01*
G01X558671Y191476D02*
X559803Y189798D01*
G01X561840Y190367D02*
X560371Y190655D01*
G01X559803Y189798D02*
X562044Y189358D01*
G01X563833Y191710D02*
X561840Y190367D01*
G01D02*
X560371Y190655D01*
G01X562044Y189358D02*
X564036Y190701D01*
G01X566166Y191249D02*
X563833Y191710D01*
G01D02*
X561840Y190367D01*
G01X564036Y190701D02*
X565597Y190392D01*
G01X568048Y188462D02*
X566166Y191249D01*
G01X565597Y190392D02*
X567458Y187637D01*
G01X570772Y187721D02*
X568048Y188462D01*
G01X567458Y187637D02*
X570902Y186700D01*
G01X572705Y188828D02*
X570772Y187721D01*
G01X570902Y186700D02*
X572836Y187807D01*
G01X574856Y188243D02*
X572705Y188828D01*
G01X572836Y187807D02*
X574227Y187429D01*
G01X575839Y186528D02*
X574856Y188243D01*
G01X574227Y187429D02*
X575210Y185714D01*
G01X579742Y185466D02*
X575839Y186528D01*
G01X575210Y185714D02*
X579873Y184445D01*
G01X581488Y186466D02*
X579742Y185466D01*
G01X579873Y184445D02*
X581619Y185445D01*
G01X584790Y185568D02*
X581488Y186466D01*
G01X581619Y185445D02*
X584160Y184754D01*
G01X585503Y184321D02*
X584790Y185568D01*
G01X584160Y184754D02*
X584873Y183507D01*
G01X612959Y176853D02*
X585503Y184321D01*
G01X584873Y183507D02*
X612929Y175876D01*
G01X544201Y201668D02*
X543975Y202058D01*
G01X543151Y201581D02*
X543378Y201191D01*
G01X550904Y191685D02*
X550055Y192950D01*
G01X548856Y194736D02*
X548104Y195856D01*
G01X546905Y197642D02*
X546153Y198762D01*
G01X544950Y200552D02*
X544201Y201668D01*
G01X543378Y201190D02*
X550218Y191000D01*
G01X559248Y186062D02*
X556710Y187772D01*
G01X555481Y189083D02*
X554926Y188975D01*
G01D02*
X553807Y189729D01*
G01X552578Y191039D02*
X552023Y190931D01*
G01D02*
X550904Y191685D01*
G01X550219Y191001D02*
X558856Y185180D01*
G01X612810Y172761D02*
X559248Y186062D01*
G01X558856Y185180D02*
X612788Y171787D01*
G01X601514Y169953D02*
X601876Y169862D01*
G01X540708Y195263D02*
X545119Y188722D01*
G01X541445Y195871D02*
X542199Y194752D01*
G01X540708Y195263D02*
X545119Y188722D01*
G01X543402Y192969D02*
X545804Y189407D01*
G01X545119Y188722D02*
X555901Y181449D01*
G01X545804Y189407D02*
X546923Y188652D01*
G01X545119Y188722D02*
X555901Y181449D01*
G01X546923Y188652D02*
X547478Y188760D01*
G01X545119Y188722D02*
X555901Y181449D01*
G01X548706Y187449D02*
X549825Y186695D01*
G01X545119Y188722D02*
X555901Y181449D01*
G01X549825Y186695D02*
X550380Y186802D01*
G01X545119Y188722D02*
X555901Y181449D01*
G01X551608Y185491D02*
X552727Y184737D01*
G01X545119Y188722D02*
X555901Y181449D01*
G01X552727Y184737D02*
X553282Y184844D01*
G01X545119Y188722D02*
X555901Y181449D01*
G01X554510Y183533D02*
X556294Y182330D01*
G01X555901Y181449D02*
X601514Y169953D01*
G01D02*
X601876Y169862D01*
G01X556294Y182330D02*
X601747Y170876D01*
G01X542445Y185866D02*
X543441Y185195D01*
G01D02*
X543996Y185302D01*
G01X545224Y183991D02*
X546343Y183237D01*
G01D02*
X546898Y183344D01*
G01X548126Y182033D02*
X549245Y181279D01*
G01D02*
X549800Y181387D01*
G01X551028Y180075D02*
X554500Y177734D01*
G01X541760Y185181D02*
X554127Y176839D01*
G01X554500Y177734D02*
X556645Y177307D01*
G01X554127Y176839D02*
X556441Y176378D01*
G01X556645Y177307D02*
X610285Y164375D01*
G01X556441Y176378D02*
X610263Y163402D01*
G01X540428Y181257D02*
X540983Y181364D01*
G01X542211Y180053D02*
X543330Y179299D01*
G01D02*
X543885Y179406D01*
G01X545113Y178095D02*
X546232Y177341D01*
G01D02*
X546787Y177449D01*
G01X548015Y176138D02*
X551853Y173549D01*
G01D02*
X609140Y160276D01*
G01X551467Y172663D02*
X609123Y159304D01*
G01X601995Y156616D02*
X564556Y164821D01*
G01X602198Y157544D02*
X564759Y165749D01*
G01X564556Y164821D02*
X558287Y166195D01*
G01X564759Y165749D02*
X558480Y167126D01*
G01X558287Y166195D02*
X551143Y167584D01*
G01X558480Y167126D02*
X551514Y168480D01*
G01X588614Y187995D02*
X600403Y184505D01*
G01D02*
X600404D01*
G01D02*
X612196Y181013D01*
G01X612155Y180034D02*
X588199Y187127D01*
G01X582612Y192122D02*
X588612Y187996D01*
G01X588198Y187127D02*
X582398Y191115D01*
G01X581215Y191862D02*
X582612Y192122D01*
G01D02*
X588612Y187996D01*
G01X582398Y191115D02*
X581776Y190999D01*
G01X580405Y190683D02*
X581215Y191862D01*
G01X581776Y190999D02*
X580965Y189820D01*
G01X579515Y190517D02*
X580405Y190683D01*
G01X580965Y189820D02*
X579301Y189511D01*
G01X577732Y191743D02*
X579515Y190517D01*
G01D02*
X580405Y190683D01*
G01X579301Y189511D02*
X576868Y191183D01*
G01X577617Y192369D02*
X577732Y191743D01*
G01X576868Y191183D02*
X576611Y192585D01*
G01X578168Y193167D02*
X577617Y192369D01*
G01X576611Y192585D02*
X577162Y193383D01*
G01X577931Y194460D02*
X578168Y193167D01*
G01X577162Y193383D02*
X577067Y193900D01*
G01X575255Y196298D02*
X577931Y194460D01*
G01X577067Y193900D02*
X575041Y195292D01*
G01X573889Y196046D02*
X575255Y196298D01*
G01D02*
X577931Y194460D01*
G01X575041Y195292D02*
X574449Y195183D01*
G01X571884Y193127D02*
X573889Y196046D01*
G01X574449Y195183D02*
X572445Y192264D01*
G01X571258Y193011D02*
X571884Y193127D01*
G01X572445Y192264D02*
X571044Y192005D01*
G01X569319Y194344D02*
X571258Y193011D01*
G01D02*
X571884Y193127D01*
G01X571044Y192005D02*
X568456Y193783D01*
G01X569203Y194968D02*
X569319Y194344D01*
G01X568456Y193783D02*
X568196Y195182D01*
G01X571651Y198526D02*
X569203Y194968D01*
G01X568196Y195182D02*
X570644Y198740D01*
G01X571391Y199924D02*
X571651Y198526D01*
G01X570644Y198740D02*
X570528Y199363D01*
G01X568800Y201706D02*
X571391Y199924D01*
G01X570528Y199363D02*
X568586Y200699D01*
G01X567403Y201446D02*
X568800Y201706D01*
G01D02*
X571391Y199924D01*
G01X568586Y200699D02*
X567963Y200583D01*
G01X566118Y199579D02*
X567403Y201446D01*
G01X567963Y200583D02*
X566678Y198716D01*
G01X565493Y199463D02*
X566118Y199579D01*
G01X566678Y198716D02*
X565279Y198457D01*
G01X560722Y202741D02*
X565493Y199463D01*
G01D02*
X566118Y199579D01*
G01X565279Y198457D02*
X560508Y201734D01*
G01X558288Y202289D02*
X560722Y202741D01*
G01X560508Y201734D02*
X558074Y201283D01*
G01X555777Y204015D02*
X558288Y202289D01*
G01X558074Y201283D02*
X554914Y203454D01*
G01X555017Y208098D02*
X555777Y204015D01*
G01X554914Y203454D02*
X554081Y207927D01*
G01X555017Y208098D02*
X555777Y204015D01*
G01X554082Y207927D02*
X554009Y208319D01*
G01X554788Y209381D02*
X555029Y208115D01*
G01X554020Y208333D02*
X553918Y208866D01*
G01X553854Y210153D02*
X554788Y209381D01*
G01X553918Y208866D02*
X553512Y209203D01*
G01X553146Y210153D02*
X553854D01*
G01D02*
X554788Y209381D01*
G01X553512Y209203D02*
X553427D01*
G01X584873Y183507D02*
X612929Y175876D01*
G01X612959Y176853D02*
X585503Y184321D01*
G01X584160Y184754D02*
X584873Y183507D01*
G01X585503Y184321D02*
X584790Y185568D01*
G01X581619Y185445D02*
X584160Y184754D01*
G01X584790Y185568D02*
X581488Y186466D01*
G01X579873Y184445D02*
X581619Y185445D01*
G01X581488Y186466D02*
X579742Y185466D01*
G01X575210Y185714D02*
X579873Y184445D01*
G01X579742Y185466D02*
X575839Y186528D01*
G01X574227Y187429D02*
X575210Y185714D01*
G01X575839Y186528D02*
X574856Y188243D01*
G01X572836Y187807D02*
X574227Y187429D01*
G01X574856Y188243D02*
X572705Y188828D01*
G01X570902Y186700D02*
X572836Y187807D01*
G01X572705Y188828D02*
X570772Y187721D01*
G01X567458Y187637D02*
X570902Y186700D01*
G01X570772Y187721D02*
X568048Y188462D01*
G01X565597Y190392D02*
X567458Y187637D01*
G01X568048Y188462D02*
X566166Y191249D01*
G01X564036Y190701D02*
X565597Y190392D01*
G01X566166Y191249D02*
X563833Y191710D01*
G01X562044Y189358D02*
X564036Y190701D01*
G01D02*
X565597Y190392D01*
G01X563833Y191710D02*
X561840Y190367D01*
G01X559803Y189798D02*
X562044Y189358D01*
G01D02*
X564036Y190701D01*
G01X561840Y190367D02*
X560371Y190655D01*
G01X558671Y191476D02*
X559803Y189798D01*
G01X560371Y190655D02*
X559679Y191681D01*
G01X559123Y193799D02*
X558671Y191476D01*
G01X559679Y191681D02*
X559981Y193231D01*
G01X560418Y194673D02*
X559770Y194236D01*
G01Y194235D02*
X559123Y193799D01*
G01X559981Y193231D02*
X561277Y194105D01*
G01X560554Y195368D02*
X560418Y194673D01*
G01X561277Y194105D02*
X561562Y195573D01*
G01X559467Y196980D02*
X560554Y195368D01*
G01X561562Y195573D02*
X560035Y197839D01*
G01X559160Y197039D02*
X559467Y196980D01*
G01X560035Y197839D02*
X559494Y197943D01*
G01X558843Y197101D02*
X559152Y197041D01*
G01X559160Y197039D02*
X559467Y196980D01*
G01X559494Y197944D02*
X559337Y197974D01*
G01X558843Y197101D02*
X559152Y197041D01*
G01X559160Y197039D02*
X559467Y196980D01*
G01X559337Y197974D02*
X559334D01*
G01X558843Y197101D02*
X559152Y197041D01*
G01X559160Y197039D02*
X559467Y196980D01*
G01X559334Y197974D02*
X558638Y198109D01*
G01X554908Y194446D02*
X558843Y197101D01*
G01D02*
X559152Y197041D01*
G01X558638Y198109D02*
X554703Y195454D01*
G01X553441Y194731D02*
X554908Y194446D01*
G01D02*
X558843Y197101D01*
G01X554703Y195454D02*
X554008Y195589D01*
G01X551560Y197514D02*
X553441Y194731D01*
G01X554008Y195589D02*
X552568Y197720D01*
G01X551934Y199444D02*
X551560Y197514D01*
G01X552568Y197720D02*
X552942Y199650D01*
G01X549392Y203209D02*
X551934Y199444D01*
G01X552942Y199650D02*
X550129Y203817D01*
G01X546410Y203739D02*
X548862D01*
G01D02*
X549392Y203209D01*
G01X550129Y203817D02*
X549256Y204689D01*
G01X545812Y204337D02*
X546410Y203739D01*
G01D02*
X548862D01*
G01X549256Y204689D02*
X546804D01*
G01X545812Y204337D02*
X546410Y203739D01*
G01X546804Y204689D02*
X546484Y205009D01*
G01X558744Y214121D02*
X559979D01*
G01X558744Y213171D02*
X559584D01*
G01X559979Y214121D02*
X563195Y210905D01*
G01X559584Y213171D02*
X562587Y210168D01*
G01X563195Y210905D02*
X575370Y202696D01*
G01X562587Y210168D02*
X574682Y202014D01*
G01X575370Y202696D02*
X576815Y200516D01*
G01X574682Y202014D02*
X576127Y199834D01*
G01X576815Y200516D02*
X580369Y198120D01*
G01X576127Y199834D02*
X579994Y197226D01*
G01X580369Y198120D02*
X582930Y197599D01*
G01X579994Y197226D02*
X582555Y196705D01*
G01X582930Y197599D02*
X593153Y190707D01*
G01X582555Y196705D02*
X592760Y189826D01*
G01X593153Y190707D02*
X599390Y189134D01*
G01X592760Y189826D02*
X599176Y188208D01*
G01X599390Y189134D02*
X614804Y185907D01*
G01X599176Y188208D02*
X614800Y184937D01*
G01X553512Y209203D02*
X553427D01*
G01X553146Y210153D02*
X553854D01*
G01X553918Y208866D02*
X553512Y209203D01*
G01D02*
X553427D01*
G01X553854Y210153D02*
X554788Y209381D01*
G01X554020Y208333D02*
X553918Y208866D01*
G01X554788Y209381D02*
X555029Y208115D01*
G01X554914Y203454D02*
X554081Y207927D01*
G01X554082D02*
X554009Y208319D01*
G01X555017Y208098D02*
X555777Y204015D01*
G01X558074Y201283D02*
X554914Y203454D01*
G01X555777Y204015D02*
X558288Y202289D01*
G01X560508Y201734D02*
X558074Y201283D01*
G01X558288Y202289D02*
X560722Y202741D01*
G01X565279Y198457D02*
X560508Y201734D01*
G01X560722Y202741D02*
X565493Y199463D01*
G01X566678Y198716D02*
X565279Y198457D01*
G01D02*
X560508Y201734D01*
G01X565493Y199463D02*
X566118Y199579D01*
G01X567963Y200583D02*
X566678Y198716D01*
G01X566118Y199579D02*
X567403Y201446D01*
G01X568586Y200699D02*
X567963Y200583D01*
G01X567403Y201446D02*
X568800Y201706D01*
G01X570528Y199363D02*
X568586Y200699D01*
G01D02*
X567963Y200583D01*
G01X568800Y201706D02*
X571391Y199924D01*
G01X570644Y198740D02*
X570528Y199363D01*
G01X571391Y199924D02*
X571651Y198526D01*
G01X568196Y195182D02*
X570644Y198740D01*
G01X571651Y198526D02*
X569203Y194968D01*
G01X568456Y193783D02*
X568196Y195182D01*
G01X569203Y194968D02*
X569319Y194344D01*
G01X571044Y192005D02*
X568456Y193783D01*
G01X569319Y194344D02*
X571258Y193011D01*
G01X572445Y192264D02*
X571044Y192005D01*
G01D02*
X568456Y193783D01*
G01X571258Y193011D02*
X571884Y193127D01*
G01X574449Y195183D02*
X572445Y192264D01*
G01X571884Y193127D02*
X573889Y196046D01*
G01X575041Y195292D02*
X574449Y195183D01*
G01X573889Y196046D02*
X575255Y196298D01*
G01X577067Y193900D02*
X575041Y195292D01*
G01D02*
X574449Y195183D01*
G01X575255Y196298D02*
X577931Y194460D01*
G01X577162Y193383D02*
X577067Y193900D01*
G01X577931Y194460D02*
X578168Y193167D01*
G01X576611Y192585D02*
X577162Y193383D01*
G01X578168Y193167D02*
X577617Y192369D01*
G01X576868Y191183D02*
X576611Y192585D01*
G01X577617Y192369D02*
X577732Y191743D01*
G01X579301Y189511D02*
X576868Y191183D01*
G01X577732Y191743D02*
X579515Y190517D01*
G01X580965Y189820D02*
X579301Y189511D01*
G01D02*
X576868Y191183D01*
G01X579515Y190517D02*
X580405Y190683D01*
G01X581776Y190999D02*
X580965Y189820D01*
G01X580405Y190683D02*
X581215Y191862D01*
G01X582398Y191115D02*
X581776Y190999D01*
G01X581215Y191862D02*
X582612Y192122D01*
G01X588198Y187127D02*
X582398Y191115D01*
G01D02*
X581776Y190999D01*
G01X582612Y192122D02*
X588612Y187996D01*
G01X612155Y180034D02*
X588199Y187127D01*
G01X588614Y187995D02*
X600403Y184505D01*
G01X612155Y180034D02*
X588199Y187127D01*
G01X600403Y184505D02*
X600404D01*
G01X612155Y180034D02*
X588199Y187127D01*
G01X600404Y184505D02*
X612196Y181013D01*
G01X598641Y197328D02*
X614556Y194146D01*
G01X614555Y193177D02*
X598252Y196436D01*
G01X590661Y203089D02*
X598641Y197328D01*
G01X598252Y196436D02*
X589785Y202549D01*
G01X590560Y203716D02*
X590661Y203089D01*
G01X589785Y202549D02*
X589559Y203954D01*
G01X593241Y207428D02*
X590560Y203716D01*
G01X589559Y203954D02*
X592240Y207665D01*
G01X593014Y208831D02*
X593241Y207428D01*
G01X592240Y207665D02*
X592141Y208275D01*
G01X590464Y210673D02*
X593014Y208831D01*
G01X592139Y208291D02*
X590226Y209672D01*
G01X589061Y210448D02*
X590464Y210673D01*
G01D02*
X593014Y208831D01*
G01X590226Y209672D02*
X589601Y209572D01*
G01X587196Y207865D02*
X589061Y210448D01*
G01X589601Y209572D02*
X587737Y206990D01*
G01X586374Y207731D02*
X587196Y207865D01*
G01X587737Y206990D02*
X586137Y206729D01*
G01X584803Y208865D02*
X586374Y207731D01*
G01D02*
X587196Y207865D01*
G01X586137Y206729D02*
X583927Y208324D01*
G01X584690Y209563D02*
X584803Y208865D01*
G01X583927Y208324D02*
X583689Y209800D01*
G01X587624Y213627D02*
X584690Y209563D01*
G01X583689Y209800D02*
X586622Y213864D01*
G01X587349Y215325D02*
X587624Y213627D01*
G01X586623Y213864D02*
X586474Y214785D01*
G01X584970Y217043D02*
X587349Y215325D01*
G01X586474Y214785D02*
X584733Y216042D01*
G01X583568Y216817D02*
X584970Y217043D01*
G01D02*
X587349Y215325D01*
G01X584733Y216042D02*
X584108Y215941D01*
G01X580277Y212261D02*
X583568Y216817D01*
G01X584108Y215941D02*
X580817Y211386D01*
G01X579452Y212128D02*
X580277Y212261D01*
G01X580817Y211386D02*
X579215Y211127D01*
G01X576201Y214476D02*
X579452Y212128D01*
G01D02*
X580277Y212261D01*
G01X579215Y211127D02*
X575325Y213936D01*
G01X576100Y215101D02*
X576201Y214476D01*
G01X575325Y213936D02*
X575098Y215339D01*
G01X576637Y215845D02*
X576100Y215101D01*
G01X575098Y215339D02*
X575635Y216081D01*
G01X576409Y217246D02*
X576637Y215845D01*
G01X575635Y216081D02*
X575534Y216706D01*
G01X573859Y219088D02*
X576409Y217246D01*
G01X575534Y216706D02*
X573622Y218087D01*
G01X573859Y219088D02*
X576409Y217246D01*
G01X571472Y217499D02*
X572455Y218861D01*
G01X572996Y217985D02*
X572012Y216623D01*
G01X570845Y217398D02*
X571472Y217499D01*
G01X572012Y216623D02*
X570607Y216397D01*
G01X570152Y217898D02*
X570845Y217398D01*
G01D02*
X571472Y217499D01*
G01X570607Y216397D02*
X569564Y217150D01*
G01X570095Y217947D02*
X570152Y217898D01*
G01X569565Y217150D02*
X569450Y217248D01*
G01X569627Y218415D02*
X570095Y217947D01*
G01X569450Y217248D02*
X568955Y217743D01*
G01X615446Y190008D02*
X597191Y193659D01*
G01X615445Y189039D02*
X596816Y192764D01*
G01X597191Y193659D02*
X586088Y201187D01*
G01X596816Y192764D02*
X585398Y200506D01*
G01X586088Y201187D02*
X584705Y203287D01*
G01X585398Y200506D02*
X584015Y202606D01*
G01X584705Y203287D02*
X575521Y209514D01*
G01X584015Y202606D02*
X575314Y208506D01*
G01X584705Y203287D02*
X575521Y209514D01*
G01D02*
X575053Y209424D01*
G01X575314Y208506D02*
X575237Y208491D01*
G01X575521Y209514D02*
X575053Y209424D01*
G01X575233Y208490D02*
X575080Y208461D01*
G01X575521Y209514D02*
X575053Y209424D01*
G01D02*
X569915Y212907D01*
G01X574846Y208416D02*
X569307Y212171D01*
G01X569915Y212907D02*
X569022Y213800D01*
G01X569307Y212171D02*
X568319Y213159D01*
G01X558744Y213171D02*
X559584D01*
G01X558744Y214121D02*
X559979D01*
G01X559584Y213171D02*
X562587Y210168D01*
G01X559979Y214121D02*
X563195Y210905D01*
G01X562587Y210168D02*
X574682Y202014D01*
G01X563195Y210905D02*
X575370Y202696D01*
G01X574682Y202014D02*
X576127Y199834D01*
G01X575370Y202696D02*
X576815Y200516D01*
G01X576127Y199834D02*
X579994Y197226D01*
G01X576815Y200516D02*
X580369Y198120D01*
G01X579994Y197226D02*
X582555Y196705D01*
G01X580369Y198120D02*
X582930Y197599D01*
G01X582555Y196705D02*
X592760Y189826D01*
G01X582930Y197599D02*
X593153Y190707D01*
G01X592760Y189826D02*
X599176Y188208D01*
G01X593153Y190707D02*
X599390Y189134D01*
G01X599176Y188208D02*
X614800Y184937D01*
G01X599390Y189134D02*
X614804Y185907D01*
G01X569450Y217248D02*
X568955Y217743D01*
G01X569627Y218415D02*
X570095Y217947D01*
G01X569565Y217150D02*
X569450Y217248D01*
G01X570095Y217947D02*
X570152Y217898D01*
G01X570607Y216397D02*
X569564Y217150D01*
G01X570152Y217898D02*
X570845Y217398D01*
G01X572012Y216623D02*
X570607Y216397D01*
G01D02*
X569564Y217150D01*
G01X570845Y217398D02*
X571472Y217499D01*
G01X572996Y217985D02*
X572012Y216623D01*
G01X571472Y217499D02*
X572455Y218861D01*
G01X575534Y216706D02*
X573622Y218087D01*
G01X573859Y219088D02*
X576409Y217246D01*
G01X575635Y216081D02*
X575534Y216706D01*
G01X576409Y217246D02*
X576637Y215845D01*
G01X575098Y215339D02*
X575635Y216081D01*
G01X576637Y215845D02*
X576100Y215101D01*
G01X575325Y213936D02*
X575098Y215339D01*
G01X576100Y215101D02*
X576201Y214476D01*
G01X579215Y211127D02*
X575325Y213936D01*
G01X576201Y214476D02*
X579452Y212128D01*
G01X580817Y211386D02*
X579215Y211127D01*
G01D02*
X575325Y213936D01*
G01X579452Y212128D02*
X580277Y212261D01*
G01X584108Y215941D02*
X580817Y211386D01*
G01X580277Y212261D02*
X583568Y216817D01*
G01X584733Y216042D02*
X584108Y215941D01*
G01X583568Y216817D02*
X584970Y217043D01*
G01X586474Y214785D02*
X584733Y216042D01*
G01D02*
X584108Y215941D01*
G01X584970Y217043D02*
X587349Y215325D01*
G01X586623Y213864D02*
X586474Y214785D01*
G01X587349Y215325D02*
X587624Y213627D01*
G01X583689Y209800D02*
X586622Y213864D01*
G01X587624Y213627D02*
X584690Y209563D01*
G01X583927Y208324D02*
X583689Y209800D01*
G01X584690Y209563D02*
X584803Y208865D01*
G01X586137Y206729D02*
X583927Y208324D01*
G01X584803Y208865D02*
X586374Y207731D01*
G01X587737Y206990D02*
X586137Y206729D01*
G01D02*
X583927Y208324D01*
G01X586374Y207731D02*
X587196Y207865D01*
G01X589601Y209572D02*
X587737Y206990D01*
G01X587196Y207865D02*
X589061Y210448D01*
G01X590226Y209672D02*
X589601Y209572D01*
G01X589061Y210448D02*
X590464Y210673D01*
G01X592139Y208291D02*
X590226Y209672D01*
G01D02*
X589601Y209572D01*
G01X590464Y210673D02*
X593014Y208831D01*
G01X592240Y207665D02*
X592141Y208275D01*
G01X593014Y208831D02*
X593241Y207428D01*
G01X589559Y203954D02*
X592240Y207665D01*
G01X593241Y207428D02*
X590560Y203716D01*
G01X589785Y202549D02*
X589559Y203954D01*
G01X590560Y203716D02*
X590661Y203089D01*
G01X598252Y196436D02*
X589785Y202549D01*
G01X590661Y203089D02*
X598641Y197328D01*
G01X614555Y193177D02*
X598252Y196436D01*
G01X598641Y197328D02*
X614556Y194146D01*
G01X615445Y189039D02*
X596816Y192764D01*
G01X615446Y190008D02*
X597191Y193659D01*
G01X596816Y192764D02*
X585398Y200506D01*
G01X597191Y193659D02*
X586088Y201187D01*
G01X585398Y200506D02*
X584015Y202606D01*
G01X586088Y201187D02*
X584705Y203287D01*
G01X584015Y202606D02*
X575314Y208506D01*
G01D02*
X575237Y208491D01*
G01X584705Y203287D02*
X575521Y209514D01*
G01X575314Y208506D02*
X575237Y208491D01*
G01X575233Y208490D02*
X575080Y208461D01*
G01X574846Y208416D02*
X569307Y212171D01*
G01X575521Y209514D02*
X575053Y209424D01*
G01X574846Y208416D02*
X569307Y212171D01*
G01X575053Y209424D02*
X569915Y212907D01*
G01X569307Y212171D02*
X568319Y213159D01*
G01X569915Y212907D02*
X569022Y213800D01*
G01X548473Y158353D02*
X547850Y158458D01*
G01X548473Y158353D02*
X547850Y158458D01*
G01X548647Y159288D02*
X548212Y159360D01*
G01X602198Y157544D02*
X564759Y165749D01*
G01X601995Y156616D02*
X564556Y164821D01*
G01X564759Y165749D02*
X558480Y167126D01*
G01X564556Y164821D02*
X558287Y166195D01*
G01X558480Y167126D02*
X551514Y168480D01*
G01X558287Y166195D02*
X551143Y167584D01*
G01X598641Y197328D02*
X614556Y194146D01*
G01X614555Y193177D02*
X598252Y196436D01*
G01X590661Y203089D02*
X598641Y197328D01*
G01X598252Y196436D02*
X589785Y202549D01*
G01X590560Y203716D02*
X590661Y203089D01*
G01X589785Y202549D02*
X589559Y203954D01*
G01X593241Y207428D02*
X590560Y203716D01*
G01X589559Y203954D02*
X592240Y207665D01*
G01X593014Y208831D02*
X593241Y207428D01*
G01X592240Y207665D02*
X592141Y208275D01*
G01X590464Y210673D02*
X593014Y208831D01*
G01X592139Y208291D02*
X590226Y209672D01*
G01X589061Y210448D02*
X590464Y210673D01*
G01D02*
X593014Y208831D01*
G01X590226Y209672D02*
X589601Y209572D01*
G01X587196Y207865D02*
X589061Y210448D01*
G01X589601Y209572D02*
X587737Y206990D01*
G01X586374Y207731D02*
X587196Y207865D01*
G01X587737Y206990D02*
X586137Y206729D01*
G01X584803Y208865D02*
X586374Y207731D01*
G01D02*
X587196Y207865D01*
G01X586137Y206729D02*
X583927Y208324D01*
G01X584690Y209563D02*
X584803Y208865D01*
G01X583927Y208324D02*
X583689Y209800D01*
G01X587624Y213627D02*
X584690Y209563D01*
G01X583689Y209800D02*
X586622Y213864D01*
G01X587349Y215325D02*
X587624Y213627D01*
G01X586623Y213864D02*
X586474Y214785D01*
G01X584970Y217043D02*
X587349Y215325D01*
G01X586474Y214785D02*
X584733Y216042D01*
G01X583568Y216817D02*
X584970Y217043D01*
G01D02*
X587349Y215325D01*
G01X584733Y216042D02*
X584108Y215941D01*
G01X580277Y212261D02*
X583568Y216817D01*
G01X584108Y215941D02*
X580817Y211386D01*
G01X579452Y212128D02*
X580277Y212261D01*
G01X580817Y211386D02*
X579215Y211127D01*
G01X576201Y214476D02*
X579452Y212128D01*
G01D02*
X580277Y212261D01*
G01X579215Y211127D02*
X575325Y213936D01*
G01X576100Y215101D02*
X576201Y214476D01*
G01X575325Y213936D02*
X575098Y215339D01*
G01X576637Y215845D02*
X576100Y215101D01*
G01X575098Y215339D02*
X575635Y216081D01*
G01X576409Y217246D02*
X576637Y215845D01*
G01X575635Y216081D02*
X575534Y216706D01*
G01X573859Y219088D02*
X576409Y217246D01*
G01X575534Y216706D02*
X573622Y218087D01*
G01X573859Y219088D02*
X576409Y217246D01*
G01X571472Y217499D02*
X572455Y218861D01*
G01X572996Y217985D02*
X572012Y216623D01*
G01X570845Y217398D02*
X571472Y217499D01*
G01X572012Y216623D02*
X570607Y216397D01*
G01X570152Y217898D02*
X570845Y217398D01*
G01D02*
X571472Y217499D01*
G01X570607Y216397D02*
X569564Y217150D01*
G01X570095Y217947D02*
X570152Y217898D01*
G01X569565Y217150D02*
X569450Y217248D01*
G01X569627Y218415D02*
X570095Y217947D01*
G01X569450Y217248D02*
X568955Y217743D01*
G01X588614Y187995D02*
X600403Y184505D01*
G01D02*
X600404D01*
G01D02*
X612196Y181013D01*
G01X612155Y180034D02*
X588199Y187127D01*
G01X582612Y192122D02*
X588612Y187996D01*
G01X588198Y187127D02*
X582398Y191115D01*
G01X581215Y191862D02*
X582612Y192122D01*
G01D02*
X588612Y187996D01*
G01X582398Y191115D02*
X581776Y190999D01*
G01X580405Y190683D02*
X581215Y191862D01*
G01X581776Y190999D02*
X580965Y189820D01*
G01X579515Y190517D02*
X580405Y190683D01*
G01X580965Y189820D02*
X579301Y189511D01*
G01X577732Y191743D02*
X579515Y190517D01*
G01D02*
X580405Y190683D01*
G01X579301Y189511D02*
X576868Y191183D01*
G01X577617Y192369D02*
X577732Y191743D01*
G01X576868Y191183D02*
X576611Y192585D01*
G01X578168Y193167D02*
X577617Y192369D01*
G01X576611Y192585D02*
X577162Y193383D01*
G01X577931Y194460D02*
X578168Y193167D01*
G01X577162Y193383D02*
X577067Y193900D01*
G01X575255Y196298D02*
X577931Y194460D01*
G01X577067Y193900D02*
X575041Y195292D01*
G01X573889Y196046D02*
X575255Y196298D01*
G01D02*
X577931Y194460D01*
G01X575041Y195292D02*
X574449Y195183D01*
G01X571884Y193127D02*
X573889Y196046D01*
G01X574449Y195183D02*
X572445Y192264D01*
G01X571258Y193011D02*
X571884Y193127D01*
G01X572445Y192264D02*
X571044Y192005D01*
G01X569319Y194344D02*
X571258Y193011D01*
G01D02*
X571884Y193127D01*
G01X571044Y192005D02*
X568456Y193783D01*
G01X569203Y194968D02*
X569319Y194344D01*
G01X568456Y193783D02*
X568196Y195182D01*
G01X571651Y198526D02*
X569203Y194968D01*
G01X568196Y195182D02*
X570644Y198740D01*
G01X571391Y199924D02*
X571651Y198526D01*
G01X570644Y198740D02*
X570528Y199363D01*
G01X568800Y201706D02*
X571391Y199924D01*
G01X570528Y199363D02*
X568586Y200699D01*
G01X567403Y201446D02*
X568800Y201706D01*
G01D02*
X571391Y199924D01*
G01X568586Y200699D02*
X567963Y200583D01*
G01X566118Y199579D02*
X567403Y201446D01*
G01X567963Y200583D02*
X566678Y198716D01*
G01X565493Y199463D02*
X566118Y199579D01*
G01X566678Y198716D02*
X565279Y198457D01*
G01X560722Y202741D02*
X565493Y199463D01*
G01D02*
X566118Y199579D01*
G01X565279Y198457D02*
X560508Y201734D01*
G01X558288Y202289D02*
X560722Y202741D01*
G01X560508Y201734D02*
X558074Y201283D01*
G01X555777Y204015D02*
X558288Y202289D01*
G01X558074Y201283D02*
X554914Y203454D01*
G01X555017Y208098D02*
X555777Y204015D01*
G01X554914Y203454D02*
X554081Y207927D01*
G01X555017Y208098D02*
X555777Y204015D01*
G01X554082Y207927D02*
X554009Y208319D01*
G01X554788Y209381D02*
X555029Y208115D01*
G01X554020Y208333D02*
X553918Y208866D01*
G01X553854Y210153D02*
X554788Y209381D01*
G01X553918Y208866D02*
X553512Y209203D01*
G01X553146Y210153D02*
X553854D01*
G01D02*
X554788Y209381D01*
G01X553512Y209203D02*
X553427D01*
G01X584873Y183507D02*
X612929Y175876D01*
G01X612959Y176853D02*
X585503Y184321D01*
G01X584160Y184754D02*
X584873Y183507D01*
G01X585503Y184321D02*
X584790Y185568D01*
G01X581619Y185445D02*
X584160Y184754D01*
G01X584790Y185568D02*
X581488Y186466D01*
G01X579873Y184445D02*
X581619Y185445D01*
G01X581488Y186466D02*
X579742Y185466D01*
G01X575210Y185714D02*
X579873Y184445D01*
G01X579742Y185466D02*
X575839Y186528D01*
G01X574227Y187429D02*
X575210Y185714D01*
G01X575839Y186528D02*
X574856Y188243D01*
G01X572836Y187807D02*
X574227Y187429D01*
G01X574856Y188243D02*
X572705Y188828D01*
G01X570902Y186700D02*
X572836Y187807D01*
G01X572705Y188828D02*
X570772Y187721D01*
G01X567458Y187637D02*
X570902Y186700D01*
G01X570772Y187721D02*
X568048Y188462D01*
G01X565597Y190392D02*
X567458Y187637D01*
G01X568048Y188462D02*
X566166Y191249D01*
G01X564036Y190701D02*
X565597Y190392D01*
G01X566166Y191249D02*
X563833Y191710D01*
G01X562044Y189358D02*
X564036Y190701D01*
G01D02*
X565597Y190392D01*
G01X563833Y191710D02*
X561840Y190367D01*
G01X559803Y189798D02*
X562044Y189358D01*
G01D02*
X564036Y190701D01*
G01X561840Y190367D02*
X560371Y190655D01*
G01X558671Y191476D02*
X559803Y189798D01*
G01X560371Y190655D02*
X559679Y191681D01*
G01X559123Y193799D02*
X558671Y191476D01*
G01X559679Y191681D02*
X559981Y193231D01*
G01X560418Y194673D02*
X559770Y194236D01*
G01Y194235D02*
X559123Y193799D01*
G01X559981Y193231D02*
X561277Y194105D01*
G01X560554Y195368D02*
X560418Y194673D01*
G01X561277Y194105D02*
X561562Y195573D01*
G01X559467Y196980D02*
X560554Y195368D01*
G01X561562Y195573D02*
X560035Y197839D01*
G01X559160Y197039D02*
X559467Y196980D01*
G01X560035Y197839D02*
X559494Y197943D01*
G01X558843Y197101D02*
X559152Y197041D01*
G01X559160Y197039D02*
X559467Y196980D01*
G01X559494Y197944D02*
X559337Y197974D01*
G01X558843Y197101D02*
X559152Y197041D01*
G01X559160Y197039D02*
X559467Y196980D01*
G01X559337Y197974D02*
X559334D01*
G01X558843Y197101D02*
X559152Y197041D01*
G01X559160Y197039D02*
X559467Y196980D01*
G01X559334Y197974D02*
X558638Y198109D01*
G01X554908Y194446D02*
X558843Y197101D01*
G01D02*
X559152Y197041D01*
G01X558638Y198109D02*
X554703Y195454D01*
G01X553441Y194731D02*
X554908Y194446D01*
G01D02*
X558843Y197101D01*
G01X554703Y195454D02*
X554008Y195589D01*
G01X551560Y197514D02*
X553441Y194731D01*
G01X554008Y195589D02*
X552568Y197720D01*
G01X551934Y199444D02*
X551560Y197514D01*
G01X552568Y197720D02*
X552942Y199650D01*
G01X549392Y203209D02*
X551934Y199444D01*
G01X552942Y199650D02*
X550129Y203817D01*
G01X546410Y203739D02*
X548862D01*
G01D02*
X549392Y203209D01*
G01X550129Y203817D02*
X549256Y204689D01*
G01X545812Y204337D02*
X546410Y203739D01*
G01D02*
X548862D01*
G01X549256Y204689D02*
X546804D01*
G01X545812Y204337D02*
X546410Y203739D01*
G01X546804Y204689D02*
X546484Y205009D01*
G01X601514Y169953D02*
X601876Y169862D01*
G01X540708Y195263D02*
X545119Y188722D01*
G01X541445Y195871D02*
X542199Y194752D01*
G01X540708Y195263D02*
X545119Y188722D01*
G01X543402Y192969D02*
X545804Y189407D01*
G01X545119Y188722D02*
X555901Y181449D01*
G01X545804Y189407D02*
X546923Y188652D01*
G01X545119Y188722D02*
X555901Y181449D01*
G01X546923Y188652D02*
X547478Y188760D01*
G01X545119Y188722D02*
X555901Y181449D01*
G01X548706Y187449D02*
X549825Y186695D01*
G01X545119Y188722D02*
X555901Y181449D01*
G01X549825Y186695D02*
X550380Y186802D01*
G01X545119Y188722D02*
X555901Y181449D01*
G01X551608Y185491D02*
X552727Y184737D01*
G01X545119Y188722D02*
X555901Y181449D01*
G01X552727Y184737D02*
X553282Y184844D01*
G01X545119Y188722D02*
X555901Y181449D01*
G01X554510Y183533D02*
X556294Y182330D01*
G01X555901Y181449D02*
X601514Y169953D01*
G01D02*
X601876Y169862D01*
G01X556294Y182330D02*
X601747Y170876D01*
G01X558856Y185180D02*
X612788Y171787D01*
G01X612810Y172761D02*
X559248Y186062D01*
G01X550219Y191001D02*
X558856Y185180D01*
G01X559248Y186062D02*
X556710Y187772D01*
G01X550219Y191001D02*
X558856Y185180D01*
G01X555481Y189083D02*
X554926Y188975D01*
G01X550219Y191001D02*
X558856Y185180D01*
G01X554926Y188975D02*
X553807Y189729D01*
G01X550219Y191001D02*
X558856Y185180D01*
G01X552578Y191039D02*
X552023Y190931D01*
G01X550219Y191001D02*
X558856Y185180D01*
G01X552023Y190931D02*
X550904Y191685D01*
G01X543378Y201190D02*
X550218Y191000D01*
G01X550904Y191685D02*
X550055Y192950D01*
G01X543378Y201190D02*
X550218Y191000D01*
G01X548856Y194736D02*
X548104Y195856D01*
G01X543378Y201190D02*
X550218Y191000D01*
G01X546905Y197642D02*
X546153Y198762D01*
G01X543378Y201190D02*
X550218Y191000D01*
G01X544950Y200552D02*
X544201Y201668D01*
G01X543151Y201581D02*
X543378Y201191D01*
G01X544201Y201668D02*
X543975Y202058D01*
G01X615445Y189039D02*
X596816Y192764D01*
G01X615446Y190008D02*
X597191Y193659D01*
G01X596816Y192764D02*
X585398Y200506D01*
G01X597191Y193659D02*
X586088Y201187D01*
G01X585398Y200506D02*
X584015Y202606D01*
G01X586088Y201187D02*
X584705Y203287D01*
G01X584015Y202606D02*
X575314Y208506D01*
G01D02*
X575237Y208491D01*
G01X584705Y203287D02*
X575521Y209514D01*
G01X575314Y208506D02*
X575237Y208491D01*
G01X575233Y208490D02*
X575080Y208461D01*
G01X574846Y208416D02*
X569307Y212171D01*
G01X575521Y209514D02*
X575053Y209424D01*
G01X574846Y208416D02*
X569307Y212171D01*
G01X575053Y209424D02*
X569915Y212907D01*
G01X569307Y212171D02*
X568319Y213159D01*
G01X569915Y212907D02*
X569022Y213800D01*
G01X572455Y218861D02*
X573859Y219088D01*
G01X573622Y218087D02*
X572996Y217985D01*
G01X573622Y218087D02*
X572996Y217985D01*
G01X572455Y218861D02*
X573859Y219088D01*
G01X573622Y218087D02*
X572996Y217985D01*
G01X586300Y224616D02*
X617681Y255997D01*
G01X586929Y223900D02*
X618557Y255528D01*
G01X576115Y265575D02*
X581537D01*
G01X576115D02*
X574606D01*
G01Y264625D02*
X581931D01*
G01X581537Y265575D02*
X589669Y273708D01*
G01X581931Y264625D02*
X590545Y273239D01*
G01X589669Y273708D02*
X608283Y366787D01*
G01X590545Y273239D02*
X609165Y366352D01*
G01X588156Y276636D02*
X601980Y345794D01*
G01X601049Y345981D02*
X587280Y277105D01*
G01X580344Y268825D02*
X588156Y276636D01*
G01X587280Y277105D02*
X579950Y269775D01*
G01X575056Y268825D02*
X580344D01*
G01X579950Y269775D02*
X575056D01*
G01X600568Y359708D02*
X584420Y278964D01*
G01X601499Y359521D02*
X585296Y278495D01*
G01X584420Y278964D02*
X579732Y274275D01*
G01X585296Y278495D02*
X580126Y273325D01*
G01X579732Y274275D02*
X575776D01*
G01X580126Y273325D02*
X575776D01*
G01X582634Y281990D02*
X578468Y277825D01*
G01X581758Y282459D02*
X578074Y278775D01*
G01X578468Y277825D02*
X574884D01*
G01X578074Y278775D02*
X574776D01*
G01X599199Y240594D02*
X615748Y257143D01*
G01X599199Y240594D02*
X585392Y226787D01*
G01X584720Y227459D02*
X614872Y257612D01*
G01X583606Y230957D02*
X612110Y259462D01*
G01X584278Y230285D02*
X612986Y258993D01*
G01X578610Y231880D02*
X581605D01*
G01X578731Y232830D02*
X581211D01*
G01X581605Y231880D02*
X610194Y260469D01*
G01X581211Y232830D02*
X609318Y260938D01*
G01X568377Y236350D02*
X576544D01*
G01X568400Y237300D02*
X576150D01*
G01X576544Y236350D02*
X577219Y237025D01*
G01X576150Y237300D02*
X576825Y237975D01*
G01X577219Y237025D02*
X581099D01*
G01X576825Y237975D02*
X580705D01*
G01X581099Y237025D02*
X607713Y263638D01*
G01X580705Y237975D02*
X606837Y264107D01*
G01X574900Y241006D02*
X580520D01*
G01X574900Y241956D02*
X580126D01*
G01X580520Y241006D02*
X604536Y265022D01*
G01X580126Y241956D02*
X603660Y265491D01*
G01X561294Y246750D02*
X580280D01*
G01X561294Y245800D02*
X579886D01*
G01X561294Y246750D02*
X580280D01*
G01X579887Y245799D02*
X580673D01*
G01X580280Y246750D02*
X600867Y267338D01*
G01X580673Y245799D02*
X601743Y266869D01*
G01X600867Y267338D02*
X618448Y355260D01*
G01X580995Y251743D02*
X568990D01*
G01Y250793D02*
X581389D01*
G01X598097Y268845D02*
X580995Y251743D01*
G01X581389Y250793D02*
X598973Y268376D01*
G01X615946Y358188D02*
X598097Y268845D01*
G01X598973Y268376D02*
X616671Y356967D01*
G01X615946Y358188D02*
X598097Y268845D01*
G01X567240Y254900D02*
X581165D01*
G01X567251Y255850D02*
X580771D01*
G01X581165Y254900D02*
X596195Y269930D01*
G01X580771Y255850D02*
X595319Y270399D01*
G01X596195Y269930D02*
X614356Y360713D01*
G01X595319Y270399D02*
X613474Y361148D01*
G01X593312Y271407D02*
X611720Y363486D01*
G01X610838Y363921D02*
X592436Y271876D01*
G01X581944Y260039D02*
X593312Y271407D01*
G01X592436Y271876D02*
X581550Y260989D01*
G01X576339Y260039D02*
X581944D01*
G01X581550Y260989D02*
X576411D01*
G01X586929Y223900D02*
X618557Y255528D01*
G01X586300Y224616D02*
X617681Y255997D01*
G01X574606Y264625D02*
X581931D01*
G01X576115Y265575D02*
X581537D01*
G01X581931Y264625D02*
X590545Y273239D01*
G01X581537Y265575D02*
X589669Y273708D01*
G01X590545Y273239D02*
X609165Y366352D01*
G01X589669Y273708D02*
X608283Y366787D01*
G01X574606Y264625D02*
X581931D01*
G01X576115Y265575D02*
X574606D01*
G01Y264625D02*
X581931D01*
G01X576115Y265575D02*
X581537D01*
G01X581931Y264625D02*
X590545Y273239D01*
G01X581537Y265575D02*
X589669Y273708D01*
G01X590545Y273239D02*
X609165Y366352D01*
G01X589669Y273708D02*
X608283Y366787D01*
G01X574606Y264625D02*
X581931D01*
G01X576115Y265575D02*
X574606D01*
G01X579950Y269775D02*
X575056D01*
G01Y268825D02*
X580344D01*
G01X587280Y277105D02*
X579950Y269775D01*
G01X580344Y268825D02*
X588156Y276636D01*
G01X601049Y345981D02*
X587280Y277105D01*
G01X588156Y276636D02*
X601980Y345794D01*
G01X601499Y359521D02*
X585296Y278495D01*
G01X600568Y359708D02*
X584420Y278964D01*
G01X585296Y278495D02*
X580126Y273325D01*
G01X584420Y278964D02*
X579732Y274275D01*
G01X580126Y273325D02*
X575776D01*
G01X579732Y274275D02*
X575776D01*
G01X581758Y282459D02*
X578074Y278775D01*
G01X582634Y281990D02*
X578468Y277825D01*
G01X578074Y278775D02*
X574776D01*
G01X578468Y277825D02*
X574884D01*
G01X584720Y227459D02*
X614872Y257612D01*
G01X599199Y240594D02*
X615748Y257143D01*
G01X584720Y227459D02*
X614872Y257612D01*
G01X599199Y240594D02*
X585392Y226787D01*
G01X584720Y227459D02*
X614872Y257612D01*
G01X599199Y240594D02*
X615748Y257143D01*
G01X584720Y227459D02*
X614872Y257612D01*
G01X599199Y240594D02*
X585392Y226787D01*
G01X584278Y230285D02*
X612986Y258993D01*
G01X583606Y230957D02*
X612110Y259462D01*
G01X578731Y232830D02*
X581211D01*
G01X578610Y231880D02*
X581605D01*
G01X581211Y232830D02*
X609318Y260938D01*
G01X581605Y231880D02*
X610194Y260469D01*
G01X568400Y237300D02*
X576150D01*
G01X568377Y236350D02*
X576544D01*
G01X576150Y237300D02*
X576825Y237975D01*
G01X576544Y236350D02*
X577219Y237025D01*
G01X576825Y237975D02*
X580705D01*
G01X577219Y237025D02*
X581099D01*
G01X580705Y237975D02*
X606837Y264107D01*
G01X581099Y237025D02*
X607713Y263638D01*
G01X574900Y241956D02*
X580126D01*
G01X574900Y241006D02*
X580520D01*
G01X580126Y241956D02*
X603660Y265491D01*
G01X580520Y241006D02*
X604536Y265022D01*
G01X561294Y245800D02*
X579886D01*
G01X579887Y245799D02*
X580673D01*
G01X561294Y246750D02*
X580280D01*
G01X580673Y245799D02*
X601743Y266869D01*
G01X580280Y246750D02*
X600867Y267338D01*
G01D02*
X618448Y355260D01*
G01X598973Y268376D02*
X616671Y356967D01*
G01X615946Y358188D02*
X598097Y268845D01*
G01X581389Y250793D02*
X598973Y268376D01*
G01X598097Y268845D02*
X580995Y251743D01*
G01X568990Y250793D02*
X581389D01*
G01X580995Y251743D02*
X568990D01*
G01X567251Y255850D02*
X580771D01*
G01X567240Y254900D02*
X581165D01*
G01X580771Y255850D02*
X595319Y270399D01*
G01X581165Y254900D02*
X596195Y269930D01*
G01X595319Y270399D02*
X613474Y361148D01*
G01X596195Y269930D02*
X614356Y360713D01*
G01X581550Y260989D02*
X576411D01*
G01X576339Y260039D02*
X581944D01*
G01X592436Y271876D02*
X581550Y260989D01*
G01X581944Y260039D02*
X593312Y271407D01*
G01X610838Y363921D02*
X592436Y271876D01*
G01X593312Y271407D02*
X611720Y363486D01*
G01X588156Y276636D02*
X601980Y345794D01*
G01X601049Y345981D02*
X587280Y277105D01*
G01X580344Y268825D02*
X588156Y276636D01*
G01X587280Y277105D02*
X579950Y269775D01*
G01X575056Y268825D02*
X580344D01*
G01X579950Y269775D02*
X575056D01*
G01X582634Y281990D02*
X578468Y277825D01*
G01X581758Y282459D02*
X578074Y278775D01*
G01X578468Y277825D02*
X574884D01*
G01X578074Y278775D02*
X574776D01*
G01X601499Y359521D02*
X585296Y278495D01*
G01X600568Y359708D02*
X584420Y278964D01*
G01X585296Y278495D02*
X580126Y273325D01*
G01X584420Y278964D02*
X579732Y274275D01*
G01X580126Y273325D02*
X575776D01*
G01X579732Y274275D02*
X575776D01*
G01X572455Y218861D02*
X573859Y219088D01*
G01X573622Y218087D02*
X572996Y217985D01*
G01X598973Y268376D02*
X616671Y356967D01*
G01X615946Y358188D02*
X598097Y268845D01*
G01X581389Y250793D02*
X598973Y268376D01*
G01X598097Y268845D02*
X580995Y251743D01*
G01X568990Y250793D02*
X581389D01*
G01X580995Y251743D02*
X568990D01*
G01X593312Y271407D02*
X611720Y363486D01*
G01X610838Y363921D02*
X592436Y271876D01*
G01X581944Y260039D02*
X593312Y271407D01*
G01X592436Y271876D02*
X581550Y260989D01*
G01X576339Y260039D02*
X581944D01*
G01X581550Y260989D02*
X576411D01*
G01X583606Y230957D02*
X612110Y259462D01*
G01X584278Y230285D02*
X612986Y258993D01*
G01X578610Y231880D02*
X581605D01*
G01X578731Y232830D02*
X581211D01*
G01X581605Y231880D02*
X610194Y260469D01*
G01X581211Y232830D02*
X609318Y260938D01*
G01X580995Y251743D02*
X568990D01*
G01Y250793D02*
X581389D01*
G01X598097Y268845D02*
X580995Y251743D01*
G01X581389Y250793D02*
X598973Y268376D01*
G01X615946Y358188D02*
X598097Y268845D01*
G01X598973Y268376D02*
X616671Y356967D01*
G01X615946Y358188D02*
X598097Y268845D01*
G01X578731Y232830D02*
X581211D01*
G01X578610Y231880D02*
X581605D01*
G01X581211Y232830D02*
X609318Y260938D01*
G01X581605Y231880D02*
X610194Y260469D01*
G01X561294Y245800D02*
X579886D01*
G01X579887Y245799D02*
X580673D01*
G01X561294Y246750D02*
X580280D01*
G01X580673Y245799D02*
X601743Y266869D01*
G01X580280Y246750D02*
X600867Y267338D01*
G01D02*
X618448Y355260D01*
G01X567251Y255850D02*
X580771D01*
G01X567240Y254900D02*
X581165D01*
G01X580771Y255850D02*
X595319Y270399D01*
G01X581165Y254900D02*
X596195Y269930D01*
G01X595319Y270399D02*
X613474Y361148D01*
G01X596195Y269930D02*
X614356Y360713D01*
G01X574900Y241006D02*
X580520D01*
G01X574900Y241956D02*
X580126D01*
G01X580520Y241006D02*
X604536Y265022D01*
G01X580126Y241956D02*
X603660Y265491D01*
G01X584278Y230285D02*
X612986Y258993D01*
G01X583606Y230957D02*
X612110Y259462D01*
G01X568400Y237300D02*
X576150D01*
G01X568377Y236350D02*
X576544D01*
G01X576150Y237300D02*
X576825Y237975D01*
G01X576544Y236350D02*
X577219Y237025D01*
G01X576825Y237975D02*
X580705D01*
G01X577219Y237025D02*
X581099D01*
G01X580705Y237975D02*
X606837Y264107D01*
G01X581099Y237025D02*
X607713Y263638D01*
G01X574900Y241956D02*
X580126D01*
G01X574900Y241006D02*
X580520D01*
G01X580126Y241956D02*
X603660Y265491D01*
G01X580520Y241006D02*
X604536Y265022D01*
G01X597693Y357274D02*
X582634Y281990D01*
G01X596724Y357274D02*
X581758Y282459D01*
G01X576375Y283275D02*
X574800D01*
G01Y282325D02*
X576769D01*
G01X579477Y286377D02*
X576375Y283275D01*
G01D02*
X574800D01*
G01X576769Y282325D02*
X580353Y285908D01*
G01X589349Y335730D02*
X579477Y286377D01*
G01X580353Y285908D02*
X590280Y335543D01*
G01X589349Y335730D02*
X593122Y354595D01*
G01X590280Y335543D02*
X594091Y354595D01*
G01X577870Y290170D02*
X590195Y351819D01*
G01X589226D02*
X576994Y290639D01*
G01X576165Y288465D02*
X576916Y289216D01*
G01X576915D02*
X577870Y290170D01*
G01X576994Y290639D02*
X575492Y289137D01*
G01X585526Y348631D02*
X575567Y298822D01*
G01X586495Y348631D02*
X576481Y298543D01*
G01X575567Y298822D02*
X572160Y290652D01*
G01X576481Y298543D02*
X573037Y290286D01*
G01X572160Y290652D02*
X571170Y289662D01*
G01X573037Y290184D02*
X571841Y288989D01*
G01X596724Y357274D02*
X581758Y282459D01*
G01X597693Y357274D02*
X582634Y281990D01*
G01X590280Y335543D02*
X594091Y354595D01*
G01X589349Y335730D02*
X593122Y354595D01*
G01X580353Y285908D02*
X590280Y335543D01*
G01X589349Y335730D02*
X579477Y286377D01*
G01X576769Y282325D02*
X580353Y285908D01*
G01X579477Y286377D02*
X576375Y283275D01*
G01X574800Y282325D02*
X576769D01*
G01D02*
X580353Y285908D01*
G01X576375Y283275D02*
X574800D01*
G01X576994Y290639D02*
X575492Y289137D01*
G01X576165Y288465D02*
X576916Y289216D01*
G01X576994Y290639D02*
X575492Y289137D01*
G01X576915Y289216D02*
X577870Y290170D01*
G01X589226Y351819D02*
X576994Y290639D01*
G01X577870Y290170D02*
X590195Y351819D01*
G01X586495Y348631D02*
X576481Y298543D01*
G01X585526Y348631D02*
X575567Y298822D01*
G01X576481Y298543D02*
X573037Y290286D01*
G01X575567Y298822D02*
X572160Y290652D01*
G01X573037Y290184D02*
X571841Y288989D01*
G01X572160Y290652D02*
X571170Y289662D01*
G01X573586Y304233D02*
X581708Y344856D01*
G01X580659Y334764D02*
X574496Y303937D01*
G01X568949Y294199D02*
X569220Y294786D01*
G01D02*
X573586Y304233D01*
G01X574496Y303937D02*
X570083Y294388D01*
G01X568949Y294199D02*
X569220Y294786D01*
G01D02*
X573586Y304233D01*
G01X570083Y294388D02*
X569812Y293801D01*
G01X573586Y304233D02*
X581708Y344856D01*
G01X580659Y334764D02*
X582677Y344856D01*
G01X573586Y304233D02*
X581708Y344856D01*
G01X580659Y334764D02*
X574496Y303937D01*
G01X568949Y294199D02*
X569220Y294786D01*
G01D02*
X573586Y304233D01*
G01X574496Y303937D02*
X570083Y294388D01*
G01X568949Y294199D02*
X569220Y294786D01*
G01D02*
X573586Y304233D01*
G01X570083Y294388D02*
X569812Y293801D01*
G01X573586Y304233D02*
X581708Y344856D01*
G01X580659Y334764D02*
X582677Y344856D01*
G01X561325Y287725D02*
X562749D01*
G01D02*
X563997Y288973D01*
G01X561325Y288675D02*
X562355D01*
G01X562749Y287725D02*
X563997Y288973D01*
G01X562355Y288675D02*
X563254Y289575D01*
G01X563997Y288973D02*
X565083Y290643D01*
G01X563254Y289575D02*
X564232Y291077D01*
G01X565083Y290643D02*
X571917Y308439D01*
G01X564232Y291077D02*
X571001Y308704D01*
G01X571917Y308439D02*
X576880Y333250D01*
G01X571001Y308704D02*
X575930Y333345D01*
G01X576880Y333250D02*
Y349477D01*
G01X575930Y333345D02*
Y349382D01*
G01X554608Y292800D02*
X555834Y291574D01*
G01X555831Y292921D02*
X556228Y292524D01*
G01X555834Y291574D02*
X557874D01*
G01X556228Y292524D02*
X557480D01*
G01X557874Y291574D02*
X560246Y293947D01*
G01X557480Y292524D02*
X559451Y294497D01*
G01X560246Y293947D02*
X567930Y310905D01*
G01X559451Y294497D02*
X567019Y311198D01*
G01X567930Y310905D02*
X571140Y326964D01*
G01X567019Y311198D02*
X570188Y327051D01*
G01X571140Y326964D02*
X570946Y339640D01*
G01X570188Y327051D02*
X569996Y339582D01*
G01X570946Y339640D02*
X567063Y375974D01*
G01X569996Y339582D02*
X566122Y375830D01*
G01X590280Y335543D02*
X594091Y354595D01*
G01X589349Y335730D02*
X593122Y354595D01*
G01X580353Y285908D02*
X590280Y335543D01*
G01X589349Y335730D02*
X579477Y286377D01*
G01X576769Y282325D02*
X580353Y285908D01*
G01X579477Y286377D02*
X576375Y283275D01*
G01X574800Y282325D02*
X576769D01*
G01D02*
X580353Y285908D01*
G01X576375Y283275D02*
X574800D01*
G01X574496Y303937D02*
X570083Y294388D01*
G01D02*
X569812Y293801D01*
G01X568949Y294199D02*
X569220Y294786D01*
G01X574496Y303937D02*
X570083Y294388D01*
G01D02*
X569812Y293801D01*
G01X569220Y294786D02*
X573586Y304233D01*
G01X580659Y334764D02*
X574496Y303937D01*
G01X580659Y334764D02*
X582677Y344856D01*
G01X573586Y304233D02*
X581708Y344856D01*
G01X561325Y288675D02*
X562355D01*
G01X561325Y287725D02*
X562749D01*
G01X561325Y288675D02*
X562355D01*
G01D02*
X563254Y289575D01*
G01X562749Y287725D02*
X563997Y288973D01*
G01X563254Y289575D02*
X564232Y291077D01*
G01X563997Y288973D02*
X565083Y290643D01*
G01X564232Y291077D02*
X571001Y308704D01*
G01X565083Y290643D02*
X571917Y308439D01*
G01X571001Y308704D02*
X575930Y333345D01*
G01X571917Y308439D02*
X576880Y333250D01*
G01X575930Y333345D02*
Y349382D01*
G01X576880Y333250D02*
Y349477D01*
G01X555831Y292921D02*
X556228Y292524D01*
G01X554608Y292800D02*
X555834Y291574D01*
G01X556228Y292524D02*
X557480D01*
G01X555834Y291574D02*
X557874D01*
G01X557480Y292524D02*
X559451Y294497D01*
G01X557874Y291574D02*
X560246Y293947D01*
G01X559451Y294497D02*
X567019Y311198D01*
G01X560246Y293947D02*
X567930Y310905D01*
G01X567019Y311198D02*
X570188Y327051D01*
G01X567930Y310905D02*
X571140Y326964D01*
G01X570188Y327051D02*
X569996Y339582D01*
G01X571140Y326964D02*
X570946Y339640D01*
G01X569996Y339582D02*
X566122Y375830D01*
G01X570946Y339640D02*
X567063Y375974D01*
G01X597693Y357274D02*
X582634Y281990D01*
G01X596724Y357274D02*
X581758Y282459D01*
G01X577870Y290170D02*
X590195Y351819D01*
G01X589226D02*
X576994Y290639D01*
G01X576165Y288465D02*
X576916Y289216D01*
G01X576915D02*
X577870Y290170D01*
G01X576994Y290639D02*
X575492Y289137D01*
G01X585526Y348631D02*
X575567Y298822D01*
G01X586495Y348631D02*
X576481Y298543D01*
G01X575567Y298822D02*
X572160Y290652D01*
G01X576481Y298543D02*
X573037Y290286D01*
G01X572160Y290652D02*
X571170Y289662D01*
G01X573037Y290184D02*
X571841Y288989D01*
G01X605796Y369730D02*
X601049Y345981D01*
G01X603117Y372455D02*
X600568Y359708D01*
G01X603999Y372020D02*
X601499Y359521D01*
G01X598264Y401692D02*
X595454Y398284D01*
G01X595455D02*
X592644Y394875D01*
G01X604276Y410479D02*
X591759Y395295D01*
G01X592644Y394875D02*
X591409Y388696D01*
G01X591759Y395295D02*
X590440Y388696D01*
G01X591409D02*
X595499Y368244D01*
G01X590440Y388696D02*
X594567Y368058D01*
G01X595499Y368244D02*
X595731Y367080D01*
G01X594567Y368058D02*
X594800Y366894D01*
G01X595731Y367080D02*
X597693Y357274D01*
G01X594800Y366894D02*
X596724Y357274D01*
G01X593122Y354595D02*
X586373Y388334D01*
G01X594091Y354595D02*
X592393Y363090D01*
G01X593122Y354595D02*
X586373Y388334D01*
G01X592020Y364954D02*
X591844Y365836D01*
G01X593122Y354595D02*
X586373Y388334D01*
G01X590922Y370446D02*
X590746Y371328D01*
G01X593122Y354595D02*
X586373Y388334D01*
G01X590372Y373192D02*
X590196Y374074D01*
G01X593122Y354595D02*
X586373Y388334D01*
G01X589822Y375938D02*
X589646Y376820D01*
G01X593122Y354595D02*
X586373Y388334D01*
G01X589272Y378684D02*
X589080Y379647D01*
G01X593122Y354595D02*
X586373Y388334D01*
G01X588707Y381511D02*
X587342Y388334D01*
G01X586373D02*
X588070Y396814D01*
G01X587342Y388334D02*
X588149Y392364D01*
G01X586373Y388334D02*
X588070Y396814D01*
G01X588149Y392365D02*
X588955Y396394D01*
G01X588070Y396814D02*
X613049Y427117D01*
G01X588955Y396394D02*
X613672Y426379D01*
G01X586619Y369705D02*
X586443Y370587D01*
G01X586070Y372451D02*
X585894Y373333D01*
G01X585520Y375197D02*
X585344Y376079D01*
G01X584971Y377944D02*
X584794Y378829D01*
G01Y378830D02*
X582994Y387830D01*
G01X586109Y367405D02*
X582025Y387830D01*
G01X582994D02*
X584883Y397273D01*
G01X582025Y387830D02*
X583980Y397605D01*
G01X584883Y397273D02*
X585656Y398668D01*
G01X583980Y397605D02*
X584867Y399205D01*
G01X585656Y398668D02*
X610598Y428924D01*
G01X584867Y399205D02*
X609957Y429640D01*
G01X590195Y351819D02*
X587041Y367591D01*
G01X586109Y367405D02*
X589226Y351819D01*
G01X577668Y387912D02*
X585526Y348631D01*
G01X584181Y360208D02*
X583785Y362188D01*
G01X577668Y387912D02*
X585526Y348631D01*
G01X583412Y364052D02*
X583201Y365107D01*
G01X577668Y387912D02*
X585526Y348631D01*
G01X582828Y366971D02*
X582652Y367853D01*
G01X577668Y387912D02*
X585526Y348631D01*
G01X582279Y369717D02*
X582103Y370599D01*
G01X577668Y387912D02*
X585526Y348631D01*
G01X581729Y372463D02*
X581553Y373345D01*
G01X577668Y387912D02*
X585526Y348631D01*
G01X581179Y375209D02*
X581003Y376091D01*
G01X577668Y387912D02*
X585526Y348631D01*
G01X580629Y377955D02*
X580337Y379418D01*
G01X577668Y387912D02*
X585526Y348631D01*
G01X579963Y381282D02*
X578637Y387912D01*
G01X579596Y397553D02*
X577668Y387912D01*
G01X578637D02*
X580499Y397222D01*
G01X581999Y401887D02*
X579596Y397553D01*
G01X580499Y397222D02*
X582788Y401350D01*
G01X607031Y432253D02*
X581999Y401887D01*
G01X582788Y401350D02*
X607677Y431543D01*
G01X577668Y387912D02*
X585526Y348631D01*
G01X584192Y360152D02*
X586495Y348631D01*
G01X605796Y369730D02*
X601049Y345981D01*
G01X603999Y372020D02*
X601499Y359521D01*
G01X603117Y372455D02*
X600568Y359708D01*
G01X604276Y410479D02*
X591759Y395295D01*
G01X604276Y410479D02*
X591759Y395295D01*
G01X604276Y410479D02*
X591759Y395295D01*
G01X604276Y410479D02*
X591759Y395295D01*
G01X598264Y401692D02*
X595454Y398284D01*
G01X604276Y410479D02*
X591759Y395295D01*
G01X595455Y398284D02*
X592644Y394875D01*
G01X591759Y395295D02*
X590440Y388696D01*
G01X592644Y394875D02*
X591409Y388696D01*
G01X590440D02*
X594567Y368058D01*
G01X591409Y388696D02*
X595499Y368244D01*
G01X594567Y368058D02*
X594800Y366894D01*
G01X595499Y368244D02*
X595731Y367080D01*
G01X594800Y366894D02*
X596724Y357274D01*
G01X595731Y367080D02*
X597693Y357274D01*
G01X594091Y354595D02*
X592393Y363090D01*
G01X592020Y364954D02*
X591844Y365836D01*
G01X590922Y370446D02*
X590746Y371328D01*
G01X590372Y373192D02*
X590196Y374074D01*
G01X589822Y375938D02*
X589646Y376820D01*
G01X589272Y378684D02*
X589080Y379647D01*
G01X588707Y381511D02*
X587342Y388334D01*
G01X593122Y354595D02*
X586373Y388334D01*
G01X587342D02*
X588149Y392364D01*
G01Y392365D02*
X588955Y396394D01*
G01X586373Y388334D02*
X588070Y396814D01*
G01X588955Y396394D02*
X613672Y426379D01*
G01X588070Y396814D02*
X613049Y427117D01*
G01X586109Y367405D02*
X589226Y351819D01*
G01X590195D02*
X587041Y367591D01*
G01X586109Y367405D02*
X582025Y387830D01*
G01X586619Y369705D02*
X586443Y370587D01*
G01X586109Y367405D02*
X582025Y387830D01*
G01X586070Y372451D02*
X585894Y373333D01*
G01X586109Y367405D02*
X582025Y387830D01*
G01X585520Y375197D02*
X585344Y376079D01*
G01X586109Y367405D02*
X582025Y387830D01*
G01X584971Y377944D02*
X584794Y378829D01*
G01X586109Y367405D02*
X582025Y387830D01*
G01X584794Y378830D02*
X582994Y387830D01*
G01X582025D02*
X583980Y397605D01*
G01X582994Y387830D02*
X584883Y397273D01*
G01X583980Y397605D02*
X584867Y399205D01*
G01X584883Y397273D02*
X585656Y398668D01*
G01X584867Y399205D02*
X609957Y429640D01*
G01X585656Y398668D02*
X610598Y428924D01*
G01X582788Y401350D02*
X607677Y431543D01*
G01X607031Y432253D02*
X581999Y401887D01*
G01X580499Y397222D02*
X582788Y401350D01*
G01X581999Y401887D02*
X579596Y397553D01*
G01X578637Y387912D02*
X580499Y397222D01*
G01X579596Y397553D02*
X577668Y387912D01*
G01X584181Y360208D02*
X583785Y362188D01*
G01X583412Y364052D02*
X583201Y365107D01*
G01X582828Y366971D02*
X582652Y367853D01*
G01X582279Y369717D02*
X582103Y370599D01*
G01X581729Y372463D02*
X581553Y373345D01*
G01X581179Y375209D02*
X581003Y376091D01*
G01X580629Y377955D02*
X580337Y379418D01*
G01X579963Y381282D02*
X578637Y387912D01*
G01X584192Y360152D02*
X586495Y348631D01*
G01X577668Y387912D02*
X585526Y348631D01*
G01X581708Y344856D02*
X573223Y387286D01*
G01X582677Y344856D02*
X579376Y361375D01*
G01X581708Y344856D02*
X573223Y387286D01*
G01X578402Y366241D02*
X578207Y367221D01*
G01X581708Y344856D02*
X573223Y387286D01*
G01X577818Y369164D02*
X577622Y370144D01*
G01X581708Y344856D02*
X573223Y387286D01*
G01X577233Y372087D02*
X577037Y373067D01*
G01X581708Y344856D02*
X573223Y387286D01*
G01X576648Y375010D02*
X576452Y375990D01*
G01X581708Y344856D02*
X573223Y387286D01*
G01X576063Y377933D02*
X575867Y378913D01*
G01X581708Y344856D02*
X573223Y387286D01*
G01X575478Y380856D02*
X574192Y387286D01*
G01X573223D02*
X575295Y397650D01*
G01X574192Y387286D02*
X576198Y397319D01*
G01X575295Y397650D02*
X578937Y404222D01*
G01X576198Y397319D02*
X579726Y403685D01*
G01X581708Y344856D02*
X573223Y387286D01*
G01X582677Y344856D02*
X579376Y361375D01*
G01X581708Y344856D02*
X573223Y387286D01*
G01X578402Y366241D02*
X578207Y367221D01*
G01X581708Y344856D02*
X573223Y387286D01*
G01X577818Y369164D02*
X577622Y370144D01*
G01X581708Y344856D02*
X573223Y387286D01*
G01X577233Y372087D02*
X577037Y373067D01*
G01X581708Y344856D02*
X573223Y387286D01*
G01X576648Y375010D02*
X576452Y375990D01*
G01X581708Y344856D02*
X573223Y387286D01*
G01X576063Y377933D02*
X575867Y378913D01*
G01X581708Y344856D02*
X573223Y387286D01*
G01X575478Y380856D02*
X574192Y387286D01*
G01X573223D02*
X575295Y397650D01*
G01X574192Y387286D02*
X576198Y397319D01*
G01X575295Y397650D02*
X578937Y404222D01*
G01X576198Y397319D02*
X579726Y403685D01*
G01X576880Y349477D02*
X569587Y385947D01*
G01X575930Y349382D02*
X568618Y385947D01*
G01X569587D02*
X571875Y397385D01*
G01X568618Y385947D02*
X570972Y397716D01*
G01X571875Y397385D02*
X576711Y406107D01*
G01X570972Y397716D02*
X575922Y406644D01*
G01X567063Y375974D02*
X565518Y383688D01*
G01X566122Y375830D02*
X564549Y383688D01*
G01X565518D02*
X568704Y399623D01*
G01X564549Y383688D02*
X567801Y399954D01*
G01X568704Y399623D02*
X573470Y408223D01*
G01X567801Y399954D02*
X572681Y408760D01*
G01X594091Y354595D02*
X592393Y363090D01*
G01X592020Y364954D02*
X591844Y365836D01*
G01X590922Y370446D02*
X590746Y371328D01*
G01X590372Y373192D02*
X590196Y374074D01*
G01X589822Y375938D02*
X589646Y376820D01*
G01X589272Y378684D02*
X589080Y379647D01*
G01X588707Y381511D02*
X587342Y388334D01*
G01X593122Y354595D02*
X586373Y388334D01*
G01X587342D02*
X588149Y392364D01*
G01Y392365D02*
X588955Y396394D01*
G01X586373Y388334D02*
X588070Y396814D01*
G01X588955Y396394D02*
X613672Y426379D01*
G01X588070Y396814D02*
X613049Y427117D01*
G01X582677Y344856D02*
X579376Y361375D01*
G01X578402Y366241D02*
X578207Y367221D01*
G01X577818Y369164D02*
X577622Y370144D01*
G01X577233Y372087D02*
X577037Y373067D01*
G01X576648Y375010D02*
X576452Y375990D01*
G01X576063Y377933D02*
X575867Y378913D01*
G01X575478Y380856D02*
X574192Y387286D01*
G01X581708Y344856D02*
X573223Y387286D01*
G01X574192D02*
X576198Y397319D01*
G01X573223Y387286D02*
X575295Y397650D01*
G01X576198Y397319D02*
X579726Y403685D01*
G01X575295Y397650D02*
X578937Y404222D01*
G01X575930Y349382D02*
X568618Y385947D01*
G01X576880Y349477D02*
X569587Y385947D01*
G01X568618D02*
X570972Y397716D01*
G01X569587Y385947D02*
X571875Y397385D01*
G01X570972Y397716D02*
X575922Y406644D01*
G01X571875Y397385D02*
X576711Y406107D01*
G01X566122Y375830D02*
X564549Y383688D01*
G01X567063Y375974D02*
X565518Y383688D01*
G01X564549D02*
X567801Y399954D01*
G01X565518Y383688D02*
X568704Y399623D01*
G01X567801Y399954D02*
X572681Y408760D01*
G01X568704Y399623D02*
X573470Y408223D01*
G01X605796Y369730D02*
X601049Y345981D01*
G01X598264Y401692D02*
X595454Y398284D01*
G01X595455D02*
X592644Y394875D01*
G01X604276Y410479D02*
X591759Y395295D01*
G01X592644Y394875D02*
X591409Y388696D01*
G01X591759Y395295D02*
X590440Y388696D01*
G01X591409D02*
X595499Y368244D01*
G01X590440Y388696D02*
X594567Y368058D01*
G01X595499Y368244D02*
X595731Y367080D01*
G01X594567Y368058D02*
X594800Y366894D01*
G01X595731Y367080D02*
X597693Y357274D01*
G01X594800Y366894D02*
X596724Y357274D01*
G01X586619Y369705D02*
X586443Y370587D01*
G01X586070Y372451D02*
X585894Y373333D01*
G01X585520Y375197D02*
X585344Y376079D01*
G01X584971Y377944D02*
X584794Y378829D01*
G01Y378830D02*
X582994Y387830D01*
G01X586109Y367405D02*
X582025Y387830D01*
G01X582994D02*
X584883Y397273D01*
G01X582025Y387830D02*
X583980Y397605D01*
G01X584883Y397273D02*
X585656Y398668D01*
G01X583980Y397605D02*
X584867Y399205D01*
G01X585656Y398668D02*
X610598Y428924D01*
G01X584867Y399205D02*
X609957Y429640D01*
G01X590195Y351819D02*
X587041Y367591D01*
G01X586109Y367405D02*
X589226Y351819D01*
G01X577668Y387912D02*
X585526Y348631D01*
G01X584181Y360208D02*
X583785Y362188D01*
G01X577668Y387912D02*
X585526Y348631D01*
G01X583412Y364052D02*
X583201Y365107D01*
G01X577668Y387912D02*
X585526Y348631D01*
G01X582828Y366971D02*
X582652Y367853D01*
G01X577668Y387912D02*
X585526Y348631D01*
G01X582279Y369717D02*
X582103Y370599D01*
G01X577668Y387912D02*
X585526Y348631D01*
G01X581729Y372463D02*
X581553Y373345D01*
G01X577668Y387912D02*
X585526Y348631D01*
G01X581179Y375209D02*
X581003Y376091D01*
G01X577668Y387912D02*
X585526Y348631D01*
G01X580629Y377955D02*
X580337Y379418D01*
G01X577668Y387912D02*
X585526Y348631D01*
G01X579963Y381282D02*
X578637Y387912D01*
G01X579596Y397553D02*
X577668Y387912D01*
G01X578637D02*
X580499Y397222D01*
G01X581999Y401887D02*
X579596Y397553D01*
G01X580499Y397222D02*
X582788Y401350D01*
G01X607031Y432253D02*
X581999Y401887D01*
G01X582788Y401350D02*
X607677Y431543D01*
G01X577668Y387912D02*
X585526Y348631D01*
G01X584192Y360152D02*
X586495Y348631D01*
G01X603999Y372020D02*
X601499Y359521D01*
G01X603117Y372455D02*
X600568Y359708D01*
G01X540310Y443259D02*
Y409972D01*
G01X541260Y429470D02*
Y409972D01*
G01X540310Y443259D02*
Y453790D01*
G01X541260Y429470D02*
Y454184D01*
G01Y429470D02*
Y409972D01*
G01X540310Y443259D02*
Y409972D01*
G01X541260Y429470D02*
Y454184D01*
G01X540310Y443259D02*
Y453790D01*
G01Y443259D02*
Y409972D01*
G01X541260Y429470D02*
Y409972D01*
G01X540310Y443259D02*
Y453790D01*
G01X541260Y429470D02*
Y454184D01*
G01Y429470D02*
Y409972D01*
G01X540310Y443259D02*
Y409972D01*
G01X541260Y429470D02*
Y454184D01*
G01X540310Y443259D02*
Y453790D01*
G01X602019Y406246D02*
X601447Y405552D01*
G01X600237Y404085D02*
X599474Y403159D01*
G01X602019Y406246D02*
X601447Y405552D01*
G01X600237Y404085D02*
X599474Y403159D01*
G01X578937Y404222D02*
X604150Y434807D01*
G01X579726Y403685D02*
X604828Y434135D01*
G01X578937Y404222D02*
X604150Y434807D01*
G01X579726Y403685D02*
X604828Y434135D01*
G01X576711Y406107D02*
X601873Y436629D01*
G01X575922Y406644D02*
X601195Y437301D01*
G01D02*
X605785Y441152D01*
G01X573470Y408223D02*
X598996Y439189D01*
G01X572681Y408760D02*
X598318Y439861D01*
G01X598996Y439189D02*
X603991Y443381D01*
G01X598318Y439861D02*
X603409Y444134D01*
G01X579726Y403685D02*
X604828Y434135D01*
G01X578937Y404222D02*
X604150Y434807D01*
G01X575922Y406644D02*
X601195Y437301D01*
G01X576711Y406107D02*
X601873Y436629D01*
G01X601195Y437301D02*
X605785Y441152D01*
G01X572681Y408760D02*
X598318Y439861D01*
G01X573470Y408223D02*
X598996Y439189D01*
G01X598318Y439861D02*
X603409Y444134D01*
G01X598996Y439189D02*
X603991Y443381D01*
G01X602019Y406246D02*
X601447Y405552D01*
G01X600237Y404085D02*
X599474Y403159D01*
G01X642639Y98637D02*
X655347Y96424D01*
G01X642815Y99571D02*
X655337Y97391D01*
G01X655347Y96424D02*
X671825Y99629D01*
G01X655337Y97391D02*
X671823Y100597D01*
G01X610171Y115837D02*
X620916Y109921D01*
G01X609968Y114864D02*
X610026Y114832D01*
G01X610171Y115837D02*
X620916Y109921D01*
G01X610026Y114832D02*
X610025D01*
G01X610171Y115837D02*
X620916Y109921D01*
G01X610025Y114832D02*
X615240Y111960D01*
G01X610171Y115837D02*
X620916Y109921D01*
G01X615240Y111960D02*
X615241D01*
G01X610171Y115837D02*
X620916Y109921D01*
G01X615241Y111960D02*
X620583Y109019D01*
G01X620916Y109921D02*
X657041Y102465D01*
G01X620583Y109019D02*
X657038Y101495D01*
G01X657041Y102465D02*
X673084Y105672D01*
G01X657038Y101495D02*
X673051Y104696D01*
G01X642815Y99571D02*
X655337Y97391D01*
G01X642639Y98637D02*
X655347Y96424D01*
G01X655337Y97391D02*
X671823Y100597D01*
G01X655347Y96424D02*
X671825Y99629D01*
G01X609968Y114864D02*
X610026Y114832D01*
G01D02*
X610025D01*
G01D02*
X615240Y111960D01*
G01D02*
X615241D01*
G01D02*
X620583Y109019D01*
G01X610171Y115837D02*
X620916Y109921D01*
G01X620583Y109019D02*
X657038Y101495D01*
G01X620916Y109921D02*
X657041Y102465D01*
G01X657038Y101495D02*
X673051Y104696D01*
G01X657041Y102465D02*
X673084Y105672D01*
G01X604928Y122403D02*
X614078Y121741D01*
G01X604919Y121451D02*
X613950Y120797D01*
G01X614078Y121741D02*
X617090Y121140D01*
G01X613950Y120797D02*
X616751Y120238D01*
G01X617090Y121140D02*
X633378Y111774D01*
G01X616751Y120238D02*
X633043Y110870D01*
G01X633378Y111774D02*
X659145Y106888D01*
G01X633043Y110870D02*
X659150Y105920D01*
G01X659145Y106888D02*
X672065Y109473D01*
G01X659150Y105920D02*
X672174Y108525D01*
G01X659145Y106888D02*
X672065Y109473D01*
G01X603483Y138237D02*
X610674Y139643D01*
G01X603491Y139207D02*
X610637Y140604D01*
G01X610674Y139643D02*
X619714Y138596D01*
G01X610637Y140604D02*
X619970Y139523D01*
G01X619714Y138596D02*
X627707Y134994D01*
G01X619970Y139523D02*
X627944Y135930D01*
G01X627707Y134994D02*
X630064Y134825D01*
G01X627944Y135930D02*
X630191Y135769D01*
G01X630064Y134825D02*
X644136Y132013D01*
G01X630191Y135769D02*
X644136Y132982D01*
G01Y132013D02*
X653936Y133973D01*
G01X644136Y132982D02*
X653936Y134942D01*
G01X644136Y132013D02*
X653936Y133973D01*
G01D02*
X654330Y133894D01*
G01D02*
X665540Y131959D01*
G01X653936Y134942D02*
X654504Y134829D01*
G01X653936Y133973D02*
X654330Y133894D01*
G01D02*
X665540Y131959D01*
G01X654504Y134829D02*
X665689Y132898D01*
G01X619152Y135716D02*
X611085Y136722D01*
G01X611116Y135760D02*
X618886Y134791D01*
G01X628320Y131441D02*
X619152Y135716D01*
G01X618886Y134791D02*
X628083Y130503D01*
G01X633553Y131130D02*
X628320Y131441D01*
G01X628083Y130503D02*
X633414Y130186D01*
G01X643111Y128867D02*
X633553Y131130D01*
G01X633414Y130186D02*
X643094Y127894D01*
G01X652202Y130685D02*
X643111Y128867D01*
G01X643094Y127894D02*
X652239Y129723D01*
G01X659461Y129800D02*
X652202Y130685D01*
G01X652239Y129723D02*
X659306Y128861D01*
G01X723082Y116564D02*
X659461Y129800D01*
G01X659306Y128861D02*
X723090Y115591D01*
G01X616207Y131474D02*
X628968Y123700D01*
G01D02*
X629240Y123646D01*
G01X622421Y126575D02*
X628617Y122801D01*
G01X628968Y123700D02*
X629240Y123646D01*
G01X628617Y122801D02*
X630918Y122341D01*
G01X631104Y123273D02*
X654840Y118524D01*
G01X630918Y122340D02*
X654840Y117555D01*
G01Y118524D02*
X674362Y122429D01*
G01X654840Y117555D02*
X674385Y121464D01*
G01X610015Y132599D02*
X616207Y131474D01*
G01X610019Y131632D02*
X615863Y130570D01*
G01X616207Y131474D02*
X628968Y123700D01*
G01X615863Y130570D02*
X622421Y126576D01*
G01X609026Y127473D02*
X614673Y126467D01*
G01X609019Y128440D02*
X615013Y127372D01*
G01X614673Y126467D02*
X633966Y114837D01*
G01X615013Y127372D02*
X634315Y115737D01*
G01X633966Y114837D02*
X634129Y114804D01*
G01Y114805D02*
X658679Y109894D01*
G01X634315Y115737D02*
X658679Y110863D01*
G01Y109894D02*
X671778Y112514D01*
G01X658679Y110863D02*
X671684Y113465D01*
G01X604919Y121451D02*
X613950Y120797D01*
G01X604928Y122403D02*
X614078Y121741D01*
G01X613950Y120797D02*
X616751Y120238D01*
G01X614078Y121741D02*
X617090Y121140D01*
G01X616751Y120238D02*
X633043Y110870D01*
G01X617090Y121140D02*
X633378Y111774D01*
G01X633043Y110870D02*
X659150Y105920D01*
G01X633378Y111774D02*
X659145Y106888D01*
G01X659150Y105920D02*
X672174Y108525D01*
G01X659145Y106888D02*
X672065Y109473D01*
G01X609968Y114864D02*
X610026Y114832D01*
G01D02*
X610025D01*
G01D02*
X615240Y111960D01*
G01D02*
X615241D01*
G01D02*
X620583Y109019D01*
G01X610171Y115837D02*
X620916Y109921D01*
G01X620583Y109019D02*
X657038Y101495D01*
G01X620916Y109921D02*
X657041Y102465D01*
G01X657038Y101495D02*
X673051Y104696D01*
G01X657041Y102465D02*
X673084Y105672D01*
G01X603491Y139207D02*
X610637Y140604D01*
G01X603483Y138237D02*
X610674Y139643D01*
G01X610637Y140604D02*
X619970Y139523D01*
G01X610674Y139643D02*
X619714Y138596D01*
G01X619970Y139523D02*
X627944Y135930D01*
G01X619714Y138596D02*
X627707Y134994D01*
G01X627944Y135930D02*
X630191Y135769D01*
G01X627707Y134994D02*
X630064Y134825D01*
G01X630191Y135769D02*
X644136Y132982D01*
G01X630064Y134825D02*
X644136Y132013D01*
G01Y132982D02*
X653936Y134942D01*
G01D02*
X654504Y134829D01*
G01X644136Y132013D02*
X653936Y133973D01*
G01Y134942D02*
X654504Y134829D01*
G01D02*
X665689Y132898D01*
G01X653936Y133973D02*
X654330Y133894D01*
G01X653936Y134942D02*
X654504Y134829D01*
G01D02*
X665689Y132898D01*
G01X654330Y133894D02*
X665540Y131959D01*
G01X659306Y128861D02*
X723090Y115591D01*
G01X723082Y116564D02*
X659461Y129800D01*
G01X652239Y129723D02*
X659306Y128861D01*
G01X659461Y129800D02*
X652202Y130685D01*
G01X643094Y127894D02*
X652239Y129723D01*
G01X652202Y130685D02*
X643111Y128867D01*
G01X633414Y130186D02*
X643094Y127894D01*
G01X643111Y128867D02*
X633553Y131130D01*
G01X628083Y130503D02*
X633414Y130186D01*
G01X633553Y131130D02*
X628320Y131441D01*
G01X618886Y134791D02*
X628083Y130503D01*
G01X628320Y131441D02*
X619152Y135716D01*
G01X611116Y135760D02*
X618886Y134791D01*
G01X619152Y135716D02*
X611085Y136722D01*
G01X610019Y131632D02*
X615863Y130570D01*
G01X610015Y132599D02*
X616207Y131474D01*
G01X622421Y126575D02*
X628617Y122801D01*
G01X615863Y130570D02*
X622421Y126576D01*
G01X616207Y131474D02*
X628968Y123700D01*
G01X622421Y126575D02*
X628617Y122801D01*
G01D02*
X630918Y122341D01*
G01X628968Y123700D02*
X629240Y123646D01*
G01X630918Y122340D02*
X654840Y117555D01*
G01X631104Y123273D02*
X654840Y118524D01*
G01Y117555D02*
X674385Y121464D01*
G01X654840Y118524D02*
X674362Y122429D01*
G01X609019Y128440D02*
X615013Y127372D01*
G01X609026Y127473D02*
X614673Y126467D01*
G01X615013Y127372D02*
X634315Y115737D01*
G01X614673Y126467D02*
X633966Y114837D01*
G01X634315Y115737D02*
X658679Y110863D01*
G01X633966Y114837D02*
X634129Y114804D01*
G01X634315Y115737D02*
X658679Y110863D01*
G01X634129Y114805D02*
X658679Y109894D01*
G01Y110863D02*
X671684Y113465D01*
G01X658679Y109894D02*
X671778Y112514D01*
G01X608143Y151865D02*
X625267Y155194D01*
G01X608136Y150895D02*
X625175Y154208D01*
G01X625267Y155194D02*
X636659Y150667D01*
G01X625175Y154208D02*
X636570Y149680D01*
G01X636659Y150667D02*
X647097Y152755D01*
G01X636570Y149680D02*
X647081Y151782D01*
G01X647097Y152755D02*
X657166Y150395D01*
G01X647081Y151782D02*
X657149Y149423D01*
G01X657166Y150395D02*
X665444Y152029D01*
G01X657149Y149423D02*
X674110Y152771D01*
G01X636301Y145670D02*
X623753Y150020D01*
G01X632584Y147965D02*
X636368Y146653D01*
G01X646849Y147779D02*
X636301Y145670D01*
G01X636368Y146653D02*
X646861Y148751D01*
G01X659803Y144852D02*
X646849Y147779D01*
G01X646861Y148751D02*
X659815Y145824D01*
G01X662352Y145271D02*
X660640Y145019D01*
G01D02*
X659803Y144852D01*
G01D02*
X646849Y147779D01*
G01X659815Y145824D02*
X660478Y145956D01*
G01X662352Y145271D02*
X660640Y145019D01*
G01D02*
X659803Y144852D01*
G01X660478Y145956D02*
X662390Y146238D01*
G01X665572Y144531D02*
X662352Y145271D01*
G01X662390Y146238D02*
X664175Y145828D01*
G01X665572Y144531D02*
X662352Y145271D01*
G01X636301Y145670D02*
X623753Y150020D01*
G01X632584Y147965D02*
X623823Y151002D01*
G01X623753Y150020D02*
X605870Y146544D01*
G01X623823Y151002D02*
X605875Y147513D01*
G01X661573Y137658D02*
X684027Y135364D01*
G01X683931Y134418D02*
X661477Y136712D01*
G01X654578Y139065D02*
X658357Y138307D01*
G01D02*
X661573Y137658D01*
G01X661477Y136712D02*
X654578Y138096D01*
G01X649591Y138067D02*
X654578Y139065D01*
G01X649591Y138067D02*
X644218Y136992D01*
G01X654578Y138096D02*
X644220Y136023D01*
G01X644218Y136992D02*
X629412Y139903D01*
G01D02*
X628974Y139979D01*
G01X644220Y136023D02*
X628711Y139060D01*
G01X629412Y139903D02*
X628974Y139979D01*
G01D02*
X617031Y144818D01*
G01X628711Y139060D02*
X616802Y143885D01*
G01X617031Y144818D02*
X613770Y145134D01*
G01X616802Y143885D02*
X613815Y144175D01*
G01X613770Y145134D02*
X609328Y144273D01*
G01D02*
X609327D01*
G01D02*
X604884Y143411D01*
G01X613815Y144175D02*
X604882Y142442D01*
G01X673995Y157807D02*
X657253Y154347D01*
G01X673967Y156831D02*
X657233Y153372D01*
G01X657253Y154347D02*
X647267Y156840D01*
G01X657233Y153372D02*
X647244Y155866D01*
G01X647267Y156840D02*
X637311Y154848D01*
G01X647244Y155866D02*
X637231Y153863D01*
G01X637311Y154848D02*
X625195Y159406D01*
G01X637231Y153863D02*
X625112Y158422D01*
G01X625195Y159406D02*
X608509Y156162D01*
G01X625112Y158422D02*
X608497Y155191D01*
G01X608509Y156162D02*
X602198Y157544D01*
G01X608497Y155191D02*
X601995Y156616D01*
G01X608136Y150895D02*
X625175Y154208D01*
G01X608143Y151865D02*
X625267Y155194D01*
G01X625175Y154208D02*
X636570Y149680D01*
G01X625267Y155194D02*
X636659Y150667D01*
G01X636570Y149680D02*
X647081Y151782D01*
G01X636659Y150667D02*
X647097Y152755D01*
G01X647081Y151782D02*
X657149Y149423D01*
G01X647097Y152755D02*
X657166Y150395D01*
G01X657149Y149423D02*
X674110Y152771D01*
G01X657166Y150395D02*
X665444Y152029D01*
G01X657149Y149423D02*
X674110Y152771D01*
G01X662390Y146238D02*
X664175Y145828D01*
G01X665572Y144531D02*
X662352Y145271D01*
G01X659815Y145824D02*
X660478Y145956D01*
G01D02*
X662390Y146238D01*
G01X662352Y145271D02*
X660640Y145019D01*
G01X659815Y145824D02*
X660478Y145956D01*
G01D02*
X662390Y146238D01*
G01X660640Y145019D02*
X659803Y144852D01*
G01X646861Y148751D02*
X659815Y145824D01*
G01D02*
X660478Y145956D01*
G01X659803Y144852D02*
X646849Y147779D01*
G01X636368Y146653D02*
X646861Y148751D01*
G01X646849Y147779D02*
X636301Y145670D01*
G01X632584Y147965D02*
X636368Y146653D01*
G01X632584Y147965D02*
X623823Y151002D01*
G01X636301Y145670D02*
X623753Y150020D01*
G01X623823Y151002D02*
X605875Y147513D01*
G01X623753Y150020D02*
X605870Y146544D01*
G01X654578Y138096D02*
X644220Y136023D01*
G01X649591Y138067D02*
X654578Y139065D01*
G01X661477Y136712D02*
X654578Y138096D01*
G01Y139065D02*
X658357Y138307D01*
G01X661477Y136712D02*
X654578Y138096D01*
G01X658357Y138307D02*
X661573Y137658D01*
G01X683931Y134418D02*
X661477Y136712D01*
G01X661573Y137658D02*
X684027Y135364D01*
G01X683931Y134418D02*
X661477Y136712D01*
G01X654578Y138096D02*
X644220Y136023D01*
G01X649591Y138067D02*
X644218Y136992D01*
G01X644220Y136023D02*
X628711Y139060D01*
G01X644218Y136992D02*
X629412Y139903D01*
G01X644220Y136023D02*
X628711Y139060D01*
G01D02*
X616802Y143885D01*
G01X629412Y139903D02*
X628974Y139979D01*
G01X628711Y139060D02*
X616802Y143885D01*
G01X628974Y139979D02*
X617031Y144818D01*
G01X616802Y143885D02*
X613815Y144175D01*
G01X617031Y144818D02*
X613770Y145134D01*
G01X613815Y144175D02*
X604882Y142442D01*
G01X613770Y145134D02*
X609328Y144273D01*
G01X613815Y144175D02*
X604882Y142442D01*
G01X609328Y144273D02*
X609327D01*
G01X613815Y144175D02*
X604882Y142442D01*
G01X609327Y144273D02*
X604884Y143411D01*
G01X673967Y156831D02*
X657233Y153372D01*
G01X673995Y157807D02*
X657253Y154347D01*
G01X657233Y153372D02*
X647244Y155866D01*
G01X657253Y154347D02*
X647267Y156840D01*
G01X647244Y155866D02*
X637231Y153863D01*
G01X647267Y156840D02*
X637311Y154848D01*
G01X637231Y153863D02*
X625112Y158422D01*
G01X637311Y154848D02*
X625195Y159406D01*
G01X625112Y158422D02*
X608497Y155191D01*
G01X625195Y159406D02*
X608509Y156162D01*
G01X608497Y155191D02*
X601995Y156616D01*
G01X608509Y156162D02*
X602198Y157544D01*
G01X619152Y135716D02*
X611085Y136722D01*
G01X611116Y135760D02*
X618886Y134791D01*
G01X628320Y131441D02*
X619152Y135716D01*
G01X618886Y134791D02*
X628083Y130503D01*
G01X633553Y131130D02*
X628320Y131441D01*
G01X628083Y130503D02*
X633414Y130186D01*
G01X643111Y128867D02*
X633553Y131130D01*
G01X633414Y130186D02*
X643094Y127894D01*
G01X652202Y130685D02*
X643111Y128867D01*
G01X643094Y127894D02*
X652239Y129723D01*
G01X659461Y129800D02*
X652202Y130685D01*
G01X652239Y129723D02*
X659306Y128861D01*
G01X723082Y116564D02*
X659461Y129800D01*
G01X659306Y128861D02*
X723090Y115591D01*
G01X604919Y121451D02*
X613950Y120797D01*
G01X604928Y122403D02*
X614078Y121741D01*
G01X613950Y120797D02*
X616751Y120238D01*
G01X614078Y121741D02*
X617090Y121140D01*
G01X616751Y120238D02*
X633043Y110870D01*
G01X617090Y121140D02*
X633378Y111774D01*
G01X633043Y110870D02*
X659150Y105920D01*
G01X633378Y111774D02*
X659145Y106888D01*
G01X659150Y105920D02*
X672174Y108525D01*
G01X659145Y106888D02*
X672065Y109473D01*
G01X636301Y145670D02*
X623753Y150020D01*
G01X632584Y147965D02*
X636368Y146653D01*
G01X646849Y147779D02*
X636301Y145670D01*
G01X636368Y146653D02*
X646861Y148751D01*
G01X659803Y144852D02*
X646849Y147779D01*
G01X646861Y148751D02*
X659815Y145824D01*
G01X662352Y145271D02*
X660640Y145019D01*
G01D02*
X659803Y144852D01*
G01D02*
X646849Y147779D01*
G01X659815Y145824D02*
X660478Y145956D01*
G01X662352Y145271D02*
X660640Y145019D01*
G01D02*
X659803Y144852D01*
G01X660478Y145956D02*
X662390Y146238D01*
G01X665572Y144531D02*
X662352Y145271D01*
G01X662390Y146238D02*
X664175Y145828D01*
G01X665572Y144531D02*
X662352Y145271D01*
G01X636301Y145670D02*
X623753Y150020D01*
G01X632584Y147965D02*
X623823Y151002D01*
G01X623753Y150020D02*
X605870Y146544D01*
G01X623823Y151002D02*
X605875Y147513D01*
G01X616207Y131474D02*
X628968Y123700D01*
G01D02*
X629240Y123646D01*
G01X622421Y126575D02*
X628617Y122801D01*
G01X628968Y123700D02*
X629240Y123646D01*
G01X628617Y122801D02*
X630918Y122341D01*
G01X631104Y123273D02*
X654840Y118524D01*
G01X630918Y122340D02*
X654840Y117555D01*
G01Y118524D02*
X674362Y122429D01*
G01X654840Y117555D02*
X674385Y121464D01*
G01X610015Y132599D02*
X616207Y131474D01*
G01X610019Y131632D02*
X615863Y130570D01*
G01X616207Y131474D02*
X628968Y123700D01*
G01X615863Y130570D02*
X622421Y126576D01*
G01X673995Y157807D02*
X657253Y154347D01*
G01X673967Y156831D02*
X657233Y153372D01*
G01X657253Y154347D02*
X647267Y156840D01*
G01X657233Y153372D02*
X647244Y155866D01*
G01X647267Y156840D02*
X637311Y154848D01*
G01X647244Y155866D02*
X637231Y153863D01*
G01X637311Y154848D02*
X625195Y159406D01*
G01X637231Y153863D02*
X625112Y158422D01*
G01X625195Y159406D02*
X608509Y156162D01*
G01X625112Y158422D02*
X608497Y155191D01*
G01X608509Y156162D02*
X602198Y157544D01*
G01X608497Y155191D02*
X601995Y156616D01*
G01X654578Y138096D02*
X644220Y136023D01*
G01X649591Y138067D02*
X654578Y139065D01*
G01X661477Y136712D02*
X654578Y138096D01*
G01Y139065D02*
X658357Y138307D01*
G01X661477Y136712D02*
X654578Y138096D01*
G01X658357Y138307D02*
X661573Y137658D01*
G01X683931Y134418D02*
X661477Y136712D01*
G01X661573Y137658D02*
X684027Y135364D01*
G01X683931Y134418D02*
X661477Y136712D01*
G01X654578Y138096D02*
X644220Y136023D01*
G01X649591Y138067D02*
X644218Y136992D01*
G01X644220Y136023D02*
X628711Y139060D01*
G01X644218Y136992D02*
X629412Y139903D01*
G01X644220Y136023D02*
X628711Y139060D01*
G01D02*
X616802Y143885D01*
G01X629412Y139903D02*
X628974Y139979D01*
G01X628711Y139060D02*
X616802Y143885D01*
G01X628974Y139979D02*
X617031Y144818D01*
G01X616802Y143885D02*
X613815Y144175D01*
G01X617031Y144818D02*
X613770Y145134D01*
G01X613815Y144175D02*
X604882Y142442D01*
G01X613770Y145134D02*
X609328Y144273D01*
G01X613815Y144175D02*
X604882Y142442D01*
G01X609328Y144273D02*
X609327D01*
G01X613815Y144175D02*
X604882Y142442D01*
G01X609327Y144273D02*
X604884Y143411D01*
G01X655852Y180468D02*
X675010Y173767D01*
G01X655852Y180468D02*
X675010Y173767D01*
G01X671037Y176163D02*
X655920Y181451D01*
G01X612788Y171787D02*
X655852Y180468D01*
G01X655920Y181451D02*
X612810Y172761D01*
G01X601747Y170876D02*
X611272Y168476D01*
G01X601747Y170876D02*
X611272Y168476D01*
G01X601876Y169862D02*
X611245Y167502D01*
G01X611272Y168476D02*
X627498Y171630D01*
G01X611245Y167502D02*
X627395Y170642D01*
G01X627498Y171630D02*
X637308Y167495D01*
G01X627395Y170642D02*
X637208Y166506D01*
G01X637308Y167495D02*
X648545Y169741D01*
G01X637208Y166506D02*
X645472Y168157D01*
G01X637308Y167495D02*
X648545Y169741D01*
G01X645472Y168157D02*
X648549Y168773D01*
G01X637308Y167495D02*
X648545Y169741D01*
G01D02*
X649622Y169536D01*
G01D02*
X652482Y168834D01*
G01X648549Y168773D02*
X649420Y168607D01*
G01X649622Y169536D02*
X652482Y168834D01*
G01X649420Y168607D02*
X652227Y167918D01*
G01X652482Y168834D02*
X658078Y167088D01*
G01X652227Y167918D02*
X658055Y166099D01*
G01X658078Y167088D02*
X673349Y171088D01*
G01X658055Y166099D02*
X673378Y170113D01*
G01X610263Y163402D02*
X626546Y166567D01*
G01D02*
X626764Y166609D01*
G01X610285Y164375D02*
X626865Y167597D01*
G01X626546Y166567D02*
X626764Y166609D01*
G01D02*
X636652Y162483D01*
G01X626865Y167597D02*
X636750Y163472D01*
G01X636652Y162483D02*
X647703Y164692D01*
G01D02*
X647913Y164686D01*
G01X636750Y163472D02*
X647622Y165645D01*
G01X636652Y162483D02*
X647703Y164692D01*
G01D02*
X647913Y164686D01*
G01X647622Y165645D02*
X648051Y165633D01*
G01X647703Y164692D02*
X647913Y164686D01*
G01D02*
X658900Y161788D01*
G01X648051Y165633D02*
X658918Y162766D01*
G01X658900Y161788D02*
X676108Y165647D01*
G01X658918Y162766D02*
X676176Y166636D01*
G01X609123Y159304D02*
X625491Y162485D01*
G01X609140Y160276D02*
X625569Y163468D01*
G01X625491Y162485D02*
X636322Y158522D01*
G01X625569Y163468D02*
X626792Y163021D01*
G01X625491Y162485D02*
X636322Y158522D01*
G01X626792Y163022D02*
X636398Y159507D01*
G01X636322Y158522D02*
X641967Y159650D01*
G01Y159651D02*
X647144Y160686D01*
G01X636398Y159507D02*
X647165Y161660D01*
G01X647144Y160686D02*
X658821Y157830D01*
G01X647165Y161660D02*
X658844Y158803D01*
G01X658821Y157830D02*
X675047Y160983D01*
G01X658844Y158803D02*
X675116Y161965D01*
G01X652282Y184964D02*
X655704Y185670D01*
G01X652282Y184964D02*
X612959Y176853D01*
G01X612929Y175876D02*
X655647Y184688D01*
G01X655704Y185670D02*
X679754Y177733D01*
G01X655647Y184688D02*
X679511Y176812D01*
G01X655920Y181451D02*
X612810Y172761D01*
G01X612788Y171787D02*
X655852Y180468D01*
G01X671037Y176163D02*
X655920Y181451D01*
G01X655852Y180468D02*
X675010Y173767D01*
G01X601876Y169862D02*
X611245Y167502D01*
G01X601747Y170876D02*
X611272Y168476D01*
G01X611245Y167502D02*
X627395Y170642D01*
G01X611272Y168476D02*
X627498Y171630D01*
G01X627395Y170642D02*
X637208Y166506D01*
G01X627498Y171630D02*
X637308Y167495D01*
G01X637208Y166506D02*
X645472Y168157D01*
G01D02*
X648549Y168773D01*
G01D02*
X649420Y168607D01*
G01X637308Y167495D02*
X648545Y169741D01*
G01X648549Y168773D02*
X649420Y168607D01*
G01X648545Y169741D02*
X649622Y169536D01*
G01X648549Y168773D02*
X649420Y168607D01*
G01D02*
X652227Y167918D01*
G01X649622Y169536D02*
X652482Y168834D01*
G01X652227Y167918D02*
X658055Y166099D01*
G01X652482Y168834D02*
X658078Y167088D01*
G01X658055Y166099D02*
X673378Y170113D01*
G01X658078Y167088D02*
X673349Y171088D01*
G01X610285Y164375D02*
X626865Y167597D01*
G01X610263Y163402D02*
X626546Y166567D01*
G01X610285Y164375D02*
X626865Y167597D01*
G01D02*
X636750Y163472D01*
G01X626546Y166567D02*
X626764Y166609D01*
G01X626865Y167597D02*
X636750Y163472D01*
G01X626764Y166609D02*
X636652Y162483D01*
G01X636750Y163472D02*
X647622Y165645D01*
G01D02*
X648051Y165633D01*
G01X636652Y162483D02*
X647703Y164692D01*
G01X636750Y163472D02*
X647622Y165645D01*
G01D02*
X648051Y165633D01*
G01D02*
X658918Y162766D01*
G01X647703Y164692D02*
X647913Y164686D01*
G01X648051Y165633D02*
X658918Y162766D01*
G01X647913Y164686D02*
X658900Y161788D01*
G01X658918Y162766D02*
X676176Y166636D01*
G01X658900Y161788D02*
X676108Y165647D01*
G01X609140Y160276D02*
X625569Y163468D01*
G01X609123Y159304D02*
X625491Y162485D01*
G01X625569Y163468D02*
X626792Y163021D01*
G01Y163022D02*
X636398Y159507D01*
G01X625491Y162485D02*
X636322Y158522D01*
G01X636398Y159507D02*
X647165Y161660D01*
G01X636322Y158522D02*
X641967Y159650D01*
G01X636398Y159507D02*
X647165Y161660D01*
G01X641967Y159651D02*
X647144Y160686D01*
G01X647165Y161660D02*
X658844Y158803D01*
G01X647144Y160686D02*
X658821Y157830D01*
G01X658844Y158803D02*
X675116Y161965D01*
G01X658821Y157830D02*
X675047Y160983D01*
G01X612196Y181013D02*
X655314Y189948D01*
G01X634044Y184570D02*
X655255Y188965D01*
G01X655314Y189948D02*
X679726Y181762D01*
G01X655255Y188965D02*
X679481Y180842D01*
G01X612196Y181013D02*
X655314Y189948D01*
G01X634044Y184570D02*
X612155Y180034D01*
G01X612929Y175876D02*
X655647Y184688D01*
G01X652282Y184964D02*
X655704Y185670D01*
G01X655647Y184688D02*
X679511Y176812D01*
G01X655704Y185670D02*
X679754Y177733D01*
G01X612929Y175876D02*
X655647Y184688D01*
G01X652282Y184964D02*
X612959Y176853D01*
G01X614804Y185907D02*
X657224Y194387D01*
G01X614800Y184937D02*
X657145Y193402D01*
G01X657224Y194387D02*
X681191Y185426D01*
G01X657145Y193402D02*
X680930Y184509D01*
G01X634044Y184570D02*
X655255Y188965D01*
G01X634044Y184570D02*
X612155Y180034D01*
G01X612196Y181013D02*
X655314Y189948D01*
G01X655255Y188965D02*
X679481Y180842D01*
G01X655314Y189948D02*
X679726Y181762D01*
G01X659447Y203035D02*
X683694Y192797D01*
G01X683414Y191883D02*
X659346Y202046D01*
G01X633350Y197867D02*
X659447Y203035D01*
G01X659346Y202046D02*
X634264Y197080D01*
G01X614556Y194146D02*
X633350Y197867D01*
G01X634264Y197080D02*
X614555Y193177D01*
G01X671371Y193311D02*
X657977Y198441D01*
G01X682049Y188202D02*
X657893Y197455D01*
G01X657977Y198441D02*
X615446Y190008D01*
G01X657893Y197455D02*
X615445Y189039D01*
G01X614800Y184937D02*
X657145Y193402D01*
G01X614804Y185907D02*
X657224Y194387D01*
G01X657145Y193402D02*
X680930Y184509D01*
G01X657224Y194387D02*
X681191Y185426D01*
G01X634264Y197080D02*
X614555Y193177D01*
G01X614556Y194146D02*
X633350Y197867D01*
G01X659346Y202046D02*
X634264Y197080D01*
G01X633350Y197867D02*
X659447Y203035D01*
G01X683414Y191883D02*
X659346Y202046D01*
G01X659447Y203035D02*
X683694Y192797D01*
G01X682049Y188202D02*
X657893Y197455D01*
G01X682049Y188202D02*
X657893Y197455D01*
G01X682049Y188202D02*
X657893Y197455D01*
G01X671371Y193311D02*
X657977Y198441D01*
G01X657893Y197455D02*
X615445Y189039D01*
G01X657977Y198441D02*
X615446Y190008D01*
G01X659447Y203035D02*
X683694Y192797D01*
G01X683414Y191883D02*
X659346Y202046D01*
G01X633350Y197867D02*
X659447Y203035D01*
G01X659346Y202046D02*
X634264Y197080D01*
G01X614556Y194146D02*
X633350Y197867D01*
G01X634264Y197080D02*
X614555Y193177D01*
G01X612196Y181013D02*
X655314Y189948D01*
G01X634044Y184570D02*
X655255Y188965D01*
G01X655314Y189948D02*
X679726Y181762D01*
G01X655255Y188965D02*
X679481Y180842D01*
G01X612196Y181013D02*
X655314Y189948D01*
G01X634044Y184570D02*
X612155Y180034D01*
G01X612929Y175876D02*
X655647Y184688D01*
G01X652282Y184964D02*
X655704Y185670D01*
G01X655647Y184688D02*
X679511Y176812D01*
G01X655704Y185670D02*
X679754Y177733D01*
G01X612929Y175876D02*
X655647Y184688D01*
G01X652282Y184964D02*
X612959Y176853D01*
G01X601876Y169862D02*
X611245Y167502D01*
G01X601747Y170876D02*
X611272Y168476D01*
G01X611245Y167502D02*
X627395Y170642D01*
G01X611272Y168476D02*
X627498Y171630D01*
G01X627395Y170642D02*
X637208Y166506D01*
G01X627498Y171630D02*
X637308Y167495D01*
G01X637208Y166506D02*
X645472Y168157D01*
G01D02*
X648549Y168773D01*
G01D02*
X649420Y168607D01*
G01X637308Y167495D02*
X648545Y169741D01*
G01X648549Y168773D02*
X649420Y168607D01*
G01X648545Y169741D02*
X649622Y169536D01*
G01X648549Y168773D02*
X649420Y168607D01*
G01D02*
X652227Y167918D01*
G01X649622Y169536D02*
X652482Y168834D01*
G01X652227Y167918D02*
X658055Y166099D01*
G01X652482Y168834D02*
X658078Y167088D01*
G01X658055Y166099D02*
X673378Y170113D01*
G01X658078Y167088D02*
X673349Y171088D01*
G01X655852Y180468D02*
X675010Y173767D01*
G01X655852Y180468D02*
X675010Y173767D01*
G01X671037Y176163D02*
X655920Y181451D01*
G01X612788Y171787D02*
X655852Y180468D01*
G01X655920Y181451D02*
X612810Y172761D01*
G01X682049Y188202D02*
X657893Y197455D01*
G01X682049Y188202D02*
X657893Y197455D01*
G01X682049Y188202D02*
X657893Y197455D01*
G01X671371Y193311D02*
X657977Y198441D01*
G01X657893Y197455D02*
X615445Y189039D01*
G01X657977Y198441D02*
X615446Y190008D01*
G01X617681Y255997D02*
X634699Y341100D01*
G01X618557Y255528D02*
X635581Y340665D01*
G01X615748Y257143D02*
X632922Y343029D01*
G01X614872Y257612D02*
X632040Y343464D01*
G01X612110Y259462D02*
X629284Y345300D01*
G01X612986Y258993D02*
X630166Y344865D01*
G01X610194Y260469D02*
X627455Y346754D01*
G01X609318Y260938D02*
X626418Y346414D01*
G01X610194Y260469D02*
X627455Y346754D01*
G01X607713Y263638D02*
X624918Y349641D01*
G01X606837Y264107D02*
X624036Y350076D01*
G01X604536Y265022D02*
X621937Y352019D01*
G01X603660Y265491D02*
X621055Y352454D01*
G01X601743Y266869D02*
X619330Y354825D01*
G01X618557Y255528D02*
X635581Y340665D01*
G01X617681Y255997D02*
X634699Y341100D01*
G01X614872Y257612D02*
X632040Y343464D01*
G01X615748Y257143D02*
X632922Y343029D01*
G01X614872Y257612D02*
X632040Y343464D01*
G01X615748Y257143D02*
X632922Y343029D01*
G01X612986Y258993D02*
X630166Y344865D01*
G01X612110Y259462D02*
X629284Y345300D01*
G01X609318Y260938D02*
X626418Y346414D01*
G01X610194Y260469D02*
X627455Y346754D01*
G01X606837Y264107D02*
X624036Y350076D01*
G01X607713Y263638D02*
X624918Y349641D01*
G01X603660Y265491D02*
X621055Y352454D01*
G01X604536Y265022D02*
X621937Y352019D01*
G01X601743Y266869D02*
X619330Y354825D01*
G01X612110Y259462D02*
X629284Y345300D01*
G01X612986Y258993D02*
X630166Y344865D01*
G01X610194Y260469D02*
X627455Y346754D01*
G01X609318Y260938D02*
X626418Y346414D01*
G01X610194Y260469D02*
X627455Y346754D01*
G01X609318Y260938D02*
X626418Y346414D01*
G01X610194Y260469D02*
X627455Y346754D01*
G01X601743Y266869D02*
X619330Y354825D01*
G01X604536Y265022D02*
X621937Y352019D01*
G01X603660Y265491D02*
X621055Y352454D01*
G01X612986Y258993D02*
X630166Y344865D01*
G01X612110Y259462D02*
X629284Y345300D01*
G01X606837Y264107D02*
X624036Y350076D01*
G01X607713Y263638D02*
X624918Y349641D01*
G01X603660Y265491D02*
X621055Y352454D01*
G01X604536Y265022D02*
X621937Y352019D01*
G01X634699Y341100D02*
X667897Y379037D01*
G01X635581Y340665D02*
X668655Y378460D01*
G01X635581Y340665D02*
X668655Y378460D01*
G01X634699Y341100D02*
X667897Y379037D01*
G01X638369Y335032D02*
X639422D01*
G01X638232Y334082D02*
X639308D01*
G01X638232D02*
X639308D01*
G01X638369Y335032D02*
X639422D01*
G01X608283Y366787D02*
X623197Y383830D01*
G01X609165Y366352D02*
X624078Y383393D01*
G01X623197Y383830D02*
X626877Y401773D01*
G01X624078Y383393D02*
X625260Y389158D01*
G01X623197Y383830D02*
X626877Y401773D01*
G01X625643Y391021D02*
X625823Y391902D01*
G01X623197Y383830D02*
X626877Y401773D01*
G01X626206Y393764D02*
X626386Y394645D01*
G01X623197Y383830D02*
X626877Y401773D01*
G01X626769Y396507D02*
X626949Y397388D01*
G01X623197Y383830D02*
X626877Y401773D01*
G01X627331Y399251D02*
X627762Y401355D01*
G01X626877Y401773D02*
X633625Y410106D01*
G01X627762Y401355D02*
X634285Y409411D01*
G01X619150Y383550D02*
X619660Y386038D01*
G01X620042Y387900D02*
X620222Y388781D01*
G01X620605Y390643D02*
X620785Y391524D01*
G01X621168Y393386D02*
X621348Y394267D01*
G01X621730Y396130D02*
X621913Y397027D01*
G01X622296Y398889D02*
X623320Y403891D01*
G01X622456Y404407D02*
X618269Y383987D01*
G01X606678Y369295D02*
X619150Y383550D01*
G01X618269Y383987D02*
X605796Y369730D01*
G01X601980Y345794D02*
X606678Y369295D01*
G01X618034Y406473D02*
X616900Y400947D01*
G01X618034Y406473D02*
X616900Y400947D01*
G01X618128Y402200D02*
X617948Y401319D01*
G01X616900Y400947D02*
X613485Y384304D01*
G01X617566Y399457D02*
X617363Y398467D01*
G01X616900Y400947D02*
X613485Y384304D01*
G01X616980Y396605D02*
X616800Y395724D01*
G01X616900Y400947D02*
X613485Y384304D01*
G01X616417Y393862D02*
X616237Y392981D01*
G01X616900Y400947D02*
X613485Y384304D01*
G01X615854Y391119D02*
X615634Y390043D01*
G01X616900Y400947D02*
X613485Y384304D01*
G01X615251Y388181D02*
X614366Y383867D01*
G01X613485Y384304D02*
X603117Y372455D01*
G01X614366Y383867D02*
X603999Y372020D01*
G01X632922Y343029D02*
X663103Y377520D01*
G01X632040Y343464D02*
X662345Y378097D01*
G01X663103Y377520D02*
X672567Y391879D01*
G01X662345Y378097D02*
X671832Y392492D01*
G01X629284Y345300D02*
X656890Y376851D01*
G01X630166Y344865D02*
X657648Y376274D01*
G01X656890Y376851D02*
X668866Y395012D01*
G01X657648Y376274D02*
X669601Y394399D01*
G01X626418Y346414D02*
X626573Y347189D01*
G01X627455Y346754D02*
X652474Y375345D01*
G01X626573Y347189D02*
X651716Y375922D01*
G01X652474Y375345D02*
X666638Y396837D01*
G01X651716Y375922D02*
X665903Y397450D01*
G01X624918Y349641D02*
X649173Y377358D01*
G01X624036Y350076D02*
X648415Y377935D01*
G01X649173Y377358D02*
X663533Y399137D01*
G01X648415Y377935D02*
X662798Y399750D01*
G01D02*
X671492Y408077D01*
G01X621937Y352019D02*
X646135Y379671D01*
G01X621055Y352454D02*
X645377Y380248D01*
G01X646135Y379671D02*
X660588Y401593D01*
G01X645377Y380248D02*
X659853Y402206D01*
G01X660588Y401593D02*
X670632Y411214D01*
G01X659853Y402206D02*
X672278Y414107D01*
G01X618448Y355260D02*
X641679Y381808D01*
G01X619330Y354825D02*
X642545Y381354D01*
G01X641679Y381808D02*
X644319Y392306D01*
G01X642545Y381354D02*
X644460Y388968D01*
G01X641679Y381808D02*
X644319Y392306D01*
G01X644944Y390889D02*
X645187Y391858D01*
G01X644319Y392306D02*
X651382Y400590D01*
G01X645187Y391858D02*
X652086Y399951D01*
G01X651382Y400590D02*
X660809Y410360D01*
G01X652086Y399951D02*
X661441Y409645D01*
G01X616671Y356967D02*
X616828Y357753D01*
G01X637453Y382766D02*
X615946Y358188D01*
G01X616828Y357753D02*
X638319Y382312D01*
G01X638108Y385368D02*
X637453Y382766D01*
G01X638319Y382312D02*
X639029Y385136D01*
G01X638108Y385368D02*
X640946Y396648D01*
G01X639029Y385136D02*
X640730Y391893D01*
G01X638108Y385368D02*
X640946Y396648D01*
G01X641214Y393814D02*
X641806Y396169D01*
G01X640946Y396648D02*
X653583Y409691D01*
G01X641806Y396169D02*
X643961Y398393D01*
G01X640946Y396648D02*
X653583Y409691D01*
G01X645339Y399816D02*
X646034Y400534D01*
G01X640946Y396648D02*
X653583Y409691D01*
G01X647413Y401957D02*
X648108Y402675D01*
G01X640946Y396648D02*
X653583Y409691D01*
G01X640946Y396648D02*
X653583Y409691D01*
G01X614356Y360713D02*
X633868Y383009D01*
G01X613474Y361148D02*
X632989Y383449D01*
G01X633868Y383009D02*
X636740Y396520D01*
G01X637136Y398379D02*
X637590Y400519D01*
G01X632989Y383449D02*
X636673Y400776D01*
G01X637590Y400519D02*
X638064Y401872D01*
G01X636673Y400776D02*
X637221Y402342D01*
G01X638064Y401872D02*
X639662Y403842D01*
G01X637221Y402342D02*
X639002Y404538D01*
G01X633473Y402298D02*
X634875Y404030D01*
G01X633473Y402298D02*
X634875Y404030D01*
G01X634137Y404629D02*
X632591Y402719D01*
G01X629557Y383867D02*
X630612Y388833D01*
G01X631007Y390692D02*
X631194Y391572D01*
G01X631590Y393432D02*
X631776Y394312D01*
G01X632172Y396171D02*
X632358Y397051D01*
G01X632754Y398910D02*
X633473Y402298D01*
G01X632591Y402719D02*
X628678Y384307D01*
G01X611720Y363486D02*
X629557Y383867D01*
G01X628678Y384307D02*
X610838Y363921D01*
G01X609165Y366352D02*
X624078Y383393D01*
G01X608283Y366787D02*
X623197Y383830D01*
G01X624078Y383393D02*
X625260Y389158D01*
G01X625643Y391021D02*
X625823Y391902D01*
G01X626206Y393764D02*
X626386Y394645D01*
G01X626769Y396507D02*
X626949Y397388D01*
G01X627331Y399251D02*
X627762Y401355D01*
G01X623197Y383830D02*
X626877Y401773D01*
G01X627762Y401355D02*
X634285Y409411D01*
G01X626877Y401773D02*
X633625Y410106D01*
G01X609165Y366352D02*
X624078Y383393D01*
G01X608283Y366787D02*
X623197Y383830D01*
G01X624078Y383393D02*
X625260Y389158D01*
G01X625643Y391021D02*
X625823Y391902D01*
G01X626206Y393764D02*
X626386Y394645D01*
G01X626769Y396507D02*
X626949Y397388D01*
G01X627331Y399251D02*
X627762Y401355D01*
G01X623197Y383830D02*
X626877Y401773D01*
G01X627762Y401355D02*
X634285Y409411D01*
G01X626877Y401773D02*
X633625Y410106D01*
G01X601980Y345794D02*
X606678Y369295D01*
G01X618269Y383987D02*
X605796Y369730D01*
G01X606678Y369295D02*
X619150Y383550D01*
G01X622456Y404407D02*
X618269Y383987D01*
G01X619150Y383550D02*
X619660Y386038D01*
G01X622456Y404407D02*
X618269Y383987D01*
G01X620042Y387900D02*
X620222Y388781D01*
G01X622456Y404407D02*
X618269Y383987D01*
G01X620605Y390643D02*
X620785Y391524D01*
G01X622456Y404407D02*
X618269Y383987D01*
G01X621168Y393386D02*
X621348Y394267D01*
G01X622456Y404407D02*
X618269Y383987D01*
G01X621730Y396130D02*
X621913Y397027D01*
G01X622456Y404407D02*
X618269Y383987D01*
G01X622296Y398889D02*
X623320Y403891D01*
G01X618128Y402200D02*
X617948Y401319D01*
G01X618034Y406473D02*
X616900Y400947D01*
G01X617566Y399457D02*
X617363Y398467D01*
G01X616980Y396605D02*
X616800Y395724D01*
G01X616417Y393862D02*
X616237Y392981D01*
G01X615854Y391119D02*
X615634Y390043D01*
G01X615251Y388181D02*
X614366Y383867D01*
G01X616900Y400947D02*
X613485Y384304D01*
G01X614366Y383867D02*
X603999Y372020D01*
G01X613485Y384304D02*
X603117Y372455D01*
G01X632040Y343464D02*
X662345Y378097D01*
G01X632922Y343029D02*
X663103Y377520D01*
G01X662345Y378097D02*
X671832Y392492D01*
G01X663103Y377520D02*
X672567Y391879D01*
G01X632040Y343464D02*
X662345Y378097D01*
G01X632922Y343029D02*
X663103Y377520D01*
G01X662345Y378097D02*
X671832Y392492D01*
G01X663103Y377520D02*
X672567Y391879D01*
G01X630166Y344865D02*
X657648Y376274D01*
G01X629284Y345300D02*
X656890Y376851D01*
G01X657648Y376274D02*
X669601Y394399D01*
G01X656890Y376851D02*
X668866Y395012D01*
G01X626418Y346414D02*
X626573Y347189D01*
G01D02*
X651716Y375922D01*
G01X627455Y346754D02*
X652474Y375345D01*
G01X651716Y375922D02*
X665903Y397450D01*
G01X652474Y375345D02*
X666638Y396837D01*
G01X624036Y350076D02*
X648415Y377935D01*
G01X624918Y349641D02*
X649173Y377358D01*
G01X648415Y377935D02*
X662798Y399750D01*
G01X649173Y377358D02*
X663533Y399137D01*
G01X662798Y399750D02*
X671492Y408077D01*
G01X621055Y352454D02*
X645377Y380248D01*
G01X621937Y352019D02*
X646135Y379671D01*
G01X645377Y380248D02*
X659853Y402206D01*
G01X646135Y379671D02*
X660588Y401593D01*
G01X659853Y402206D02*
X672278Y414107D01*
G01X660588Y401593D02*
X670632Y411214D01*
G01X659853Y402206D02*
X672278Y414107D01*
G01X659853Y402206D02*
X672278Y414107D01*
G01X619330Y354825D02*
X642545Y381354D01*
G01X618448Y355260D02*
X641679Y381808D01*
G01X642545Y381354D02*
X644460Y388968D01*
G01X644944Y390889D02*
X645187Y391858D01*
G01X641679Y381808D02*
X644319Y392306D01*
G01X645187Y391858D02*
X652086Y399951D01*
G01X644319Y392306D02*
X651382Y400590D01*
G01X652086Y399951D02*
X661441Y409645D01*
G01X651382Y400590D02*
X660809Y410360D01*
G01X639029Y385136D02*
X640730Y391893D01*
G01X641214Y393814D02*
X641806Y396169D01*
G01X638108Y385368D02*
X640946Y396648D01*
G01X641806Y396169D02*
X643961Y398393D01*
G01X645339Y399816D02*
X646034Y400534D01*
G01X647413Y401957D02*
X648108Y402675D01*
G01X640946Y396648D02*
X653583Y409691D01*
G01X638319Y382312D02*
X639029Y385136D01*
G01X638108Y385368D02*
X637453Y382766D01*
G01X616828Y357753D02*
X638319Y382312D01*
G01X637453Y382766D02*
X615946Y358188D01*
G01X616671Y356967D02*
X616828Y357753D01*
G01X613474Y361148D02*
X632989Y383449D01*
G01X614356Y360713D02*
X633868Y383009D01*
G01X632989Y383449D02*
X636673Y400776D01*
G01X633868Y383009D02*
X636740Y396520D01*
G01X632989Y383449D02*
X636673Y400776D01*
G01X637136Y398379D02*
X637590Y400519D01*
G01X636673Y400776D02*
X637221Y402342D01*
G01X637590Y400519D02*
X638064Y401872D01*
G01X637221Y402342D02*
X639002Y404538D01*
G01X638064Y401872D02*
X639662Y403842D01*
G01X628678Y384307D02*
X610838Y363921D01*
G01X611720Y363486D02*
X629557Y383867D01*
G01X632591Y402719D02*
X628678Y384307D01*
G01X629557Y383867D02*
X630612Y388833D01*
G01X632591Y402719D02*
X628678Y384307D01*
G01X631007Y390692D02*
X631194Y391572D01*
G01X632591Y402719D02*
X628678Y384307D01*
G01X631590Y393432D02*
X631776Y394312D01*
G01X632591Y402719D02*
X628678Y384307D01*
G01X632172Y396171D02*
X632358Y397051D01*
G01X632591Y402719D02*
X628678Y384307D01*
G01X632754Y398910D02*
X633473Y402298D01*
G01X634137Y404629D02*
X632591Y402719D01*
G01X633473Y402298D02*
X634875Y404030D01*
G01X619150Y383550D02*
X619660Y386038D01*
G01X620042Y387900D02*
X620222Y388781D01*
G01X620605Y390643D02*
X620785Y391524D01*
G01X621168Y393386D02*
X621348Y394267D01*
G01X621730Y396130D02*
X621913Y397027D01*
G01X622296Y398889D02*
X623320Y403891D01*
G01X622456Y404407D02*
X618269Y383987D01*
G01X606678Y369295D02*
X619150Y383550D01*
G01X618269Y383987D02*
X605796Y369730D01*
G01X601980Y345794D02*
X606678Y369295D01*
G01X618128Y402200D02*
X617948Y401319D01*
G01X618034Y406473D02*
X616900Y400947D01*
G01X617566Y399457D02*
X617363Y398467D01*
G01X616980Y396605D02*
X616800Y395724D01*
G01X616417Y393862D02*
X616237Y392981D01*
G01X615854Y391119D02*
X615634Y390043D01*
G01X615251Y388181D02*
X614366Y383867D01*
G01X616900Y400947D02*
X613485Y384304D01*
G01X614366Y383867D02*
X603999Y372020D01*
G01X613485Y384304D02*
X603117Y372455D01*
G01X662048Y346403D02*
Y350169D01*
G01X661098Y346209D02*
Y350613D01*
G01Y346209D02*
Y350613D01*
G01X662048Y346403D02*
Y350169D01*
G01X652048Y346403D02*
Y350313D01*
G01X651098Y346481D02*
Y350441D01*
G01Y346481D02*
Y350441D01*
G01X652048Y346403D02*
Y350313D01*
G01X639029Y385136D02*
X640730Y391893D01*
G01X641214Y393814D02*
X641806Y396169D01*
G01X638108Y385368D02*
X640946Y396648D01*
G01X641806Y396169D02*
X643961Y398393D01*
G01X645339Y399816D02*
X646034Y400534D01*
G01X647413Y401957D02*
X648108Y402675D01*
G01X640946Y396648D02*
X653583Y409691D01*
G01X638319Y382312D02*
X639029Y385136D01*
G01X638108Y385368D02*
X637453Y382766D01*
G01X616828Y357753D02*
X638319Y382312D01*
G01X637453Y382766D02*
X615946Y358188D01*
G01X616671Y356967D02*
X616828Y357753D01*
G01X633473Y402298D02*
X634875Y404030D01*
G01X633473Y402298D02*
X634875Y404030D01*
G01X634137Y404629D02*
X632591Y402719D01*
G01X629557Y383867D02*
X630612Y388833D01*
G01X631007Y390692D02*
X631194Y391572D01*
G01X631590Y393432D02*
X631776Y394312D01*
G01X632172Y396171D02*
X632358Y397051D01*
G01X632754Y398910D02*
X633473Y402298D01*
G01X632591Y402719D02*
X628678Y384307D01*
G01X611720Y363486D02*
X629557Y383867D01*
G01X628678Y384307D02*
X610838Y363921D01*
G01X629284Y345300D02*
X656890Y376851D01*
G01X630166Y344865D02*
X657648Y376274D01*
G01X656890Y376851D02*
X668866Y395012D01*
G01X657648Y376274D02*
X669601Y394399D01*
G01X626418Y346414D02*
X626573Y347189D01*
G01X627455Y346754D02*
X652474Y375345D01*
G01X626573Y347189D02*
X651716Y375922D01*
G01X652474Y375345D02*
X666638Y396837D01*
G01X651716Y375922D02*
X665903Y397450D01*
G01X616671Y356967D02*
X616828Y357753D01*
G01X637453Y382766D02*
X615946Y358188D01*
G01X616828Y357753D02*
X638319Y382312D01*
G01X638108Y385368D02*
X637453Y382766D01*
G01X638319Y382312D02*
X639029Y385136D01*
G01X638108Y385368D02*
X640946Y396648D01*
G01X639029Y385136D02*
X640730Y391893D01*
G01X638108Y385368D02*
X640946Y396648D01*
G01X641214Y393814D02*
X641806Y396169D01*
G01X640946Y396648D02*
X653583Y409691D01*
G01X641806Y396169D02*
X643961Y398393D01*
G01X640946Y396648D02*
X653583Y409691D01*
G01X645339Y399816D02*
X646034Y400534D01*
G01X640946Y396648D02*
X653583Y409691D01*
G01X647413Y401957D02*
X648108Y402675D01*
G01X640946Y396648D02*
X653583Y409691D01*
G01X640946Y396648D02*
X653583Y409691D01*
G01X626418Y346414D02*
X626573Y347189D01*
G01D02*
X651716Y375922D01*
G01X627455Y346754D02*
X652474Y375345D01*
G01X651716Y375922D02*
X665903Y397450D01*
G01X652474Y375345D02*
X666638Y396837D01*
G01X619330Y354825D02*
X642545Y381354D01*
G01X618448Y355260D02*
X641679Y381808D01*
G01X642545Y381354D02*
X644460Y388968D01*
G01X644944Y390889D02*
X645187Y391858D01*
G01X641679Y381808D02*
X644319Y392306D01*
G01X645187Y391858D02*
X652086Y399951D01*
G01X644319Y392306D02*
X651382Y400590D01*
G01X652086Y399951D02*
X661441Y409645D01*
G01X651382Y400590D02*
X660809Y410360D01*
G01X613474Y361148D02*
X632989Y383449D01*
G01X614356Y360713D02*
X633868Y383009D01*
G01X632989Y383449D02*
X636673Y400776D01*
G01X633868Y383009D02*
X636740Y396520D01*
G01X632989Y383449D02*
X636673Y400776D01*
G01X637136Y398379D02*
X637590Y400519D01*
G01X636673Y400776D02*
X637221Y402342D01*
G01X637590Y400519D02*
X638064Y401872D01*
G01X637221Y402342D02*
X639002Y404538D01*
G01X638064Y401872D02*
X639662Y403842D01*
G01X621937Y352019D02*
X646135Y379671D01*
G01X621055Y352454D02*
X645377Y380248D01*
G01X646135Y379671D02*
X660588Y401593D01*
G01X645377Y380248D02*
X659853Y402206D01*
G01X660588Y401593D02*
X670632Y411214D01*
G01X659853Y402206D02*
X672278Y414107D01*
G01X630166Y344865D02*
X657648Y376274D01*
G01X629284Y345300D02*
X656890Y376851D01*
G01X657648Y376274D02*
X669601Y394399D01*
G01X656890Y376851D02*
X668866Y395012D01*
G01X624036Y350076D02*
X648415Y377935D01*
G01X624918Y349641D02*
X649173Y377358D01*
G01X648415Y377935D02*
X662798Y399750D01*
G01X649173Y377358D02*
X663533Y399137D01*
G01X662798Y399750D02*
X671492Y408077D01*
G01X621055Y352454D02*
X645377Y380248D01*
G01X621937Y352019D02*
X646135Y379671D01*
G01X645377Y380248D02*
X659853Y402206D01*
G01X646135Y379671D02*
X660588Y401593D01*
G01X659853Y402206D02*
X672278Y414107D01*
G01X660588Y401593D02*
X670632Y411214D01*
G01X659853Y402206D02*
X672278Y414107D01*
G01X659853Y402206D02*
X672278Y414107D01*
G01X633625Y410106D02*
X663504Y431818D01*
G01X634285Y409411D02*
X664157Y431118D01*
G01X661929Y434390D02*
X668470Y442188D01*
G01X667849Y442928D02*
X661275Y435090D01*
G01X632007Y412652D02*
X661929Y434390D01*
G01X661275Y435090D02*
X631347Y413347D01*
G01X628265Y408031D02*
X629230Y409221D01*
G01X629231Y409223D02*
X632007Y412652D01*
G01X631347Y413347D02*
X627585Y408701D01*
G01X623320Y403891D02*
X628265Y408031D01*
G01X627585Y408701D02*
X622456Y404407D01*
G01X664771Y445184D02*
X658783Y438046D01*
G01X664771Y445184D02*
X658783Y438046D01*
G01X665500Y444572D02*
X659436Y437346D01*
G01X658783Y438046D02*
X632907Y419243D01*
G01D02*
X628805Y416262D01*
G01X659436Y437346D02*
X630180Y416087D01*
G01X632907Y419243D02*
X628805Y416262D01*
G01X630180Y416087D02*
X629465Y415567D01*
G01X628805Y416262D02*
X626546Y413472D01*
G01X629465Y415567D02*
X628189Y413992D01*
G01X628805Y416262D02*
X626546Y413472D01*
G01D02*
X625489Y412167D01*
G01X628189Y413992D02*
X626546Y411963D01*
G01Y413472D02*
X625489Y412167D01*
G01X626546Y411963D02*
X626418Y411805D01*
G01X626546Y413472D02*
X625489Y412167D01*
G01X626418Y411805D02*
X626156Y411481D01*
G01X625489Y412167D02*
X618034Y406473D01*
G01X626156Y411481D02*
X618894Y405933D01*
G01D02*
X618511Y404062D01*
G01X678599Y457934D02*
X662877Y448855D01*
G01X663498Y448115D02*
X657142Y440540D01*
G01X662877Y448855D02*
X656489Y441240D01*
G01X657142Y440540D02*
X642163Y429652D01*
G01X656489Y441240D02*
X641810Y430571D01*
G01X642163Y429652D02*
X623894Y427734D01*
G01X641810Y430571D02*
X623600Y428659D01*
G01X623894Y427734D02*
X616177Y423420D01*
G01X623600Y428659D02*
X615557Y424163D01*
G01X616177Y423420D02*
X605011Y409874D01*
G01X615557Y424163D02*
X604278Y410479D01*
G01X603801Y408407D02*
X603229Y407713D01*
G01X613049Y427117D02*
X623470Y433100D01*
G01X613672Y426379D02*
X623769Y432176D01*
G01X623470Y433100D02*
X640792Y434921D01*
G01X623769Y432176D02*
X641145Y434002D01*
G01X640792Y434921D02*
X654697Y445029D01*
G01X641145Y434002D02*
X655350Y444329D01*
G01X654697Y445029D02*
X660393Y451822D01*
G01X655350Y444329D02*
X661014Y451082D01*
G01X660393Y451822D02*
X677381Y461629D01*
G01X661014Y451082D02*
X677761Y460751D01*
G01X610598Y428924D02*
X619238Y434571D01*
G01X609957Y429640D02*
X618807Y435425D01*
G01X619238Y434571D02*
X625410Y436865D01*
G01X627192Y437529D02*
X628789Y438122D01*
G01X630571Y438785D02*
X633313Y439804D01*
G01X618807Y435425D02*
X633082Y440732D01*
G01X633313Y439804D02*
X635567Y440105D01*
G01X637451Y440357D02*
X638888Y440548D01*
G01X640772Y440801D02*
X644654Y441319D01*
G01X633082Y440732D02*
X643156Y442077D01*
G01X640772Y440801D02*
X644654Y441319D01*
G01D02*
X650056Y445607D01*
G01X643156Y442077D02*
X644268Y442226D01*
G01X644654Y441319D02*
X650056Y445607D01*
G01X644268Y442226D02*
X649389Y446292D01*
G01X650056Y445607D02*
X652653Y448702D01*
G01X653876Y450158D02*
X655002Y451500D01*
G01D02*
X655831Y452487D01*
G01X649389Y446292D02*
X655210Y453227D01*
G01X655831Y452487D02*
X676291Y464299D01*
G01X655210Y453227D02*
X675911Y465177D01*
G01X616397Y438598D02*
X607031Y432253D01*
G01X607677Y431543D02*
X616839Y437749D01*
G01X616671Y438703D02*
X616397Y438598D01*
G01X616839Y437749D02*
X616900Y437772D01*
G01X631526Y444366D02*
X616900Y438790D01*
G01D02*
X616671Y438703D01*
G01D02*
X616397Y438598D01*
G01X616900Y437772D02*
X631762Y443438D01*
G01X642470Y445831D02*
X631526Y444366D01*
G01X631762Y443438D02*
X642813Y444918D01*
G01X643156Y446287D02*
X642470Y445831D01*
G01D02*
X631526Y444366D01*
G01X642813Y444918D02*
X643156Y445146D01*
G01X643602Y446583D02*
X643156Y446287D01*
G01D02*
X642470Y445831D01*
G01X643156Y445146D02*
X644191Y445833D01*
G01X645355Y448201D02*
X644477Y447391D01*
G01D02*
X644476D01*
G01D02*
X643602Y446583D01*
G01X644191Y445833D02*
X646044Y447544D01*
G01X651430Y455442D02*
X645355Y448201D01*
G01X646044Y447544D02*
X652051Y454702D01*
G01X674435Y468724D02*
X651430Y455442D01*
G01X652051Y454702D02*
X674815Y467846D01*
G01X660809Y410360D02*
X670194Y417420D01*
G01X661441Y409645D02*
X670645Y416569D01*
G01X649487Y404098D02*
X650182Y404816D01*
G01X651561Y406239D02*
X654214Y408976D01*
G01X653583Y409691D02*
X668384Y420827D01*
G01X654214Y408976D02*
X668835Y419976D01*
G01X639662Y403842D02*
X640390Y404371D01*
G01D02*
X641088Y404260D01*
G01X641928Y405488D02*
X642656Y406017D01*
G01D02*
X643156Y405937D01*
G01X644194Y407134D02*
X644922Y407663D01*
G01D02*
X645620Y407552D01*
G01X646460Y408781D02*
X647188Y409310D01*
G01D02*
X647886Y409199D01*
G01X648726Y410427D02*
X651637Y412542D01*
G01D02*
X669271Y425357D01*
G01X639002Y404538D02*
X668618Y426057D01*
G01X634875Y404030D02*
X636961Y406607D01*
G01X634137Y404629D02*
X634395Y404947D01*
G01X634875Y404030D02*
X636961Y406607D01*
G01X634395Y404947D02*
X636301Y407302D01*
G01X636961Y406607D02*
X666654Y428166D01*
G01X636301Y407302D02*
X641708Y411228D01*
G01X636961Y406607D02*
X666654Y428166D01*
G01X641708Y411228D02*
X665500Y428502D01*
G01X636961Y406607D02*
X666654Y428166D01*
G01X634285Y409411D02*
X664157Y431118D01*
G01X633625Y410106D02*
X663504Y431818D01*
G01X634285Y409411D02*
X664157Y431118D01*
G01X633625Y410106D02*
X663504Y431818D01*
G01X627585Y408701D02*
X622456Y404407D01*
G01X623320Y403891D02*
X628265Y408031D01*
G01X631347Y413347D02*
X627585Y408701D01*
G01X628265Y408031D02*
X629230Y409221D01*
G01X631347Y413347D02*
X627585Y408701D01*
G01X629231Y409223D02*
X632007Y412652D01*
G01X661275Y435090D02*
X631347Y413347D01*
G01X632007Y412652D02*
X661929Y434390D01*
G01X667849Y442928D02*
X661275Y435090D01*
G01X661929Y434390D02*
X668470Y442188D01*
G01X665500Y444572D02*
X659436Y437346D01*
G01X665500Y444572D02*
X659436Y437346D01*
G01X664771Y445184D02*
X658783Y438046D01*
G01X659436Y437346D02*
X630180Y416087D01*
G01X658783Y438046D02*
X632907Y419243D01*
G01X659436Y437346D02*
X630180Y416087D01*
G01D02*
X629465Y415567D01*
G01X632907Y419243D02*
X628805Y416262D01*
G01X629465Y415567D02*
X628189Y413992D01*
G01D02*
X626546Y411963D01*
G01X628805Y416262D02*
X626546Y413472D01*
G01X628189Y413992D02*
X626546Y411963D01*
G01D02*
X626418Y411805D01*
G01D02*
X626156Y411481D01*
G01X626546Y413472D02*
X625489Y412167D01*
G01X626156Y411481D02*
X618894Y405933D01*
G01X625489Y412167D02*
X618034Y406473D01*
G01X618894Y405933D02*
X618511Y404062D01*
G01X678599Y457934D02*
X662877Y448855D01*
G01D02*
X656489Y441240D01*
G01X663498Y448115D02*
X657142Y440540D01*
G01X656489Y441240D02*
X641810Y430571D01*
G01X657142Y440540D02*
X642163Y429652D01*
G01X641810Y430571D02*
X623600Y428659D01*
G01X642163Y429652D02*
X623894Y427734D01*
G01X623600Y428659D02*
X615557Y424163D01*
G01X623894Y427734D02*
X616177Y423420D01*
G01X615557Y424163D02*
X604278Y410479D01*
G01X616177Y423420D02*
X605011Y409874D01*
G01X603801Y408407D02*
X603229Y407713D01*
G01X613672Y426379D02*
X623769Y432176D01*
G01X613049Y427117D02*
X623470Y433100D01*
G01X623769Y432176D02*
X641145Y434002D01*
G01X623470Y433100D02*
X640792Y434921D01*
G01X641145Y434002D02*
X655350Y444329D01*
G01X640792Y434921D02*
X654697Y445029D01*
G01X655350Y444329D02*
X661014Y451082D01*
G01X654697Y445029D02*
X660393Y451822D01*
G01X661014Y451082D02*
X677761Y460751D01*
G01X660393Y451822D02*
X677381Y461629D01*
G01X609957Y429640D02*
X618807Y435425D01*
G01X610598Y428924D02*
X619238Y434571D01*
G01X618807Y435425D02*
X633082Y440732D01*
G01X619238Y434571D02*
X625410Y436865D01*
G01X618807Y435425D02*
X633082Y440732D01*
G01X627192Y437529D02*
X628789Y438122D01*
G01X618807Y435425D02*
X633082Y440732D01*
G01X630571Y438785D02*
X633313Y439804D01*
G01X633082Y440732D02*
X643156Y442077D01*
G01X633313Y439804D02*
X635567Y440105D01*
G01X633082Y440732D02*
X643156Y442077D01*
G01X637451Y440357D02*
X638888Y440548D01*
G01X633082Y440732D02*
X643156Y442077D01*
G01D02*
X644268Y442226D01*
G01X640772Y440801D02*
X644654Y441319D01*
G01X643156Y442077D02*
X644268Y442226D01*
G01D02*
X649389Y446292D01*
G01X644654Y441319D02*
X650056Y445607D01*
G01X649389Y446292D02*
X655210Y453227D01*
G01X650056Y445607D02*
X652653Y448702D01*
G01X649389Y446292D02*
X655210Y453227D01*
G01X653876Y450158D02*
X655002Y451500D01*
G01X649389Y446292D02*
X655210Y453227D01*
G01X655002Y451500D02*
X655831Y452487D01*
G01X655210Y453227D02*
X675911Y465177D01*
G01X655831Y452487D02*
X676291Y464299D01*
G01X652051Y454702D02*
X674815Y467846D01*
G01X674435Y468724D02*
X651430Y455442D01*
G01X646044Y447544D02*
X652051Y454702D01*
G01X651430Y455442D02*
X645355Y448201D01*
G01X644191Y445833D02*
X646044Y447544D01*
G01X645355Y448201D02*
X644477Y447391D01*
G01X644191Y445833D02*
X646044Y447544D01*
G01X644477Y447391D02*
X644476D01*
G01X644191Y445833D02*
X646044Y447544D01*
G01X644476Y447391D02*
X643602Y446583D01*
G01X643156Y445146D02*
X644191Y445833D01*
G01X643602Y446583D02*
X643156Y446287D01*
G01X642813Y444918D02*
X643156Y445146D01*
G01D02*
X644191Y445833D01*
G01X643156Y446287D02*
X642470Y445831D01*
G01X631762Y443438D02*
X642813Y444918D01*
G01D02*
X643156Y445146D01*
G01X642470Y445831D02*
X631526Y444366D01*
G01X616900Y437772D02*
X631762Y443438D01*
G01X631526Y444366D02*
X616900Y438790D01*
G01Y437772D02*
X631762Y443438D01*
G01X616900Y438790D02*
X616671Y438703D01*
G01X616839Y437749D02*
X616900Y437772D01*
G01D02*
X631762Y443438D01*
G01X616671Y438703D02*
X616397Y438598D01*
G01X607677Y431543D02*
X616839Y437749D01*
G01X616397Y438598D02*
X607031Y432253D01*
G01X661441Y409645D02*
X670645Y416569D01*
G01X660809Y410360D02*
X670194Y417420D01*
G01X649487Y404098D02*
X650182Y404816D01*
G01X651561Y406239D02*
X654214Y408976D01*
G01D02*
X668835Y419976D01*
G01X653583Y409691D02*
X668384Y420827D01*
G01X639002Y404538D02*
X668618Y426057D01*
G01X639662Y403842D02*
X640390Y404371D01*
G01X639002Y404538D02*
X668618Y426057D01*
G01X640390Y404371D02*
X641088Y404260D01*
G01X639002Y404538D02*
X668618Y426057D01*
G01X641928Y405488D02*
X642656Y406017D01*
G01X639002Y404538D02*
X668618Y426057D01*
G01X642656Y406017D02*
X643156Y405937D01*
G01X639002Y404538D02*
X668618Y426057D01*
G01X644194Y407134D02*
X644922Y407663D01*
G01X639002Y404538D02*
X668618Y426057D01*
G01X644922Y407663D02*
X645620Y407552D01*
G01X639002Y404538D02*
X668618Y426057D01*
G01X646460Y408781D02*
X647188Y409310D01*
G01X639002Y404538D02*
X668618Y426057D01*
G01X647188Y409310D02*
X647886Y409199D01*
G01X639002Y404538D02*
X668618Y426057D01*
G01X648726Y410427D02*
X651637Y412542D01*
G01X639002Y404538D02*
X668618Y426057D01*
G01X651637Y412542D02*
X669271Y425357D01*
G01X634137Y404629D02*
X634395Y404947D01*
G01X634137Y404629D02*
X634395Y404947D01*
G01D02*
X636301Y407302D01*
G01X634875Y404030D02*
X636961Y406607D01*
G01X636301Y407302D02*
X641708Y411228D01*
G01D02*
X665500Y428502D01*
G01X636961Y406607D02*
X666654Y428166D01*
G01X604150Y434807D02*
X607973Y438015D01*
G01X604828Y434135D02*
X608533Y437243D01*
G01X607973Y438015D02*
X613752Y441614D01*
G01X608533Y437243D02*
X614198Y440771D01*
G01X613752Y441614D02*
X629441Y448536D01*
G01X614198Y440771D02*
X629701Y447612D01*
G01X613752Y441614D02*
X629441Y448536D01*
G01D02*
X640034Y449951D01*
G01X629701Y447612D02*
X630695Y447744D01*
G01X629441Y448536D02*
X640034Y449951D01*
G01X632659Y448007D02*
X633650Y448139D01*
G01X629441Y448536D02*
X640034Y449951D01*
G01X635613Y448402D02*
X640267Y449023D01*
G01X640034Y449951D02*
X641857Y450637D01*
G01X640267Y449023D02*
X642405Y449828D01*
G01X641857Y450637D02*
X648980Y458430D01*
G01X642405Y449828D02*
X649583Y457680D01*
G01X648980Y458430D02*
X673209Y472417D01*
G01X649583Y457680D02*
X673589Y471539D01*
G01X604150Y434807D02*
X607973Y438015D01*
G01X604828Y434135D02*
X608533Y437243D01*
G01X607973Y438015D02*
X613752Y441614D01*
G01X608533Y437243D02*
X614198Y440771D01*
G01X613752Y441614D02*
X629441Y448536D01*
G01X614198Y440771D02*
X629701Y447612D01*
G01X613752Y441614D02*
X629441Y448536D01*
G01D02*
X640034Y449951D01*
G01X629701Y447612D02*
X630695Y447744D01*
G01X629441Y448536D02*
X640034Y449951D01*
G01X632659Y448007D02*
X633650Y448139D01*
G01X629441Y448536D02*
X640034Y449951D01*
G01X635613Y448402D02*
X640267Y449023D01*
G01X640034Y449951D02*
X641857Y450637D01*
G01X640267Y449023D02*
X642405Y449828D01*
G01X641857Y450637D02*
X648980Y458430D01*
G01X642405Y449828D02*
X649583Y457680D01*
G01X648980Y458430D02*
X673209Y472417D01*
G01X649583Y457680D02*
X673589Y471539D01*
G01X601873Y436629D02*
X606352Y440386D01*
G01D02*
X614463Y445652D01*
G01X616057Y446687D02*
X616811Y447177D01*
G01X618406Y448212D02*
X619160Y448702D01*
G01X620755Y449737D02*
X621509Y450227D01*
G01X623104Y451262D02*
X623470Y451500D01*
G01D02*
X625694Y452944D01*
G01X605785Y441152D02*
X625201Y453757D01*
G01X625694Y452944D02*
X626418Y453354D01*
G01D02*
X628772Y454686D01*
G01X630427Y455622D02*
X637909Y459856D01*
G01X625201Y453757D02*
X637524Y460730D01*
G01X637909Y459856D02*
X641160Y460916D01*
G01X642967Y461506D02*
X643156Y461568D01*
G01D02*
X643822Y461785D01*
G01X645629Y462375D02*
X646484Y462654D01*
G01X648292Y463244D02*
X651587Y464318D01*
G01X637524Y460730D02*
X651304Y465226D01*
G01X651587Y464318D02*
X655433Y465458D01*
G01X603991Y443381D02*
X616771Y452456D01*
G01X603409Y444134D02*
X616252Y453253D01*
G01X616771Y452456D02*
X632744Y461959D01*
G01X616252Y453253D02*
X616671Y453502D01*
G01X616771Y452456D02*
X632744Y461959D01*
G01X616671Y453502D02*
X632324Y462815D01*
G01X632744Y461959D02*
X642973Y465988D01*
G01X632324Y462815D02*
X636081Y464294D01*
G01X632744Y461959D02*
X642973Y465988D01*
G01X636081Y464294D02*
X642655Y466884D01*
G01X613672Y426379D02*
X623769Y432176D01*
G01X613049Y427117D02*
X623470Y433100D01*
G01X623769Y432176D02*
X641145Y434002D01*
G01X623470Y433100D02*
X640792Y434921D01*
G01X641145Y434002D02*
X655350Y444329D01*
G01X640792Y434921D02*
X654697Y445029D01*
G01X655350Y444329D02*
X661014Y451082D01*
G01X654697Y445029D02*
X660393Y451822D01*
G01X661014Y451082D02*
X677761Y460751D01*
G01X660393Y451822D02*
X677381Y461629D01*
G01X604828Y434135D02*
X608533Y437243D01*
G01X604150Y434807D02*
X607973Y438015D01*
G01X608533Y437243D02*
X614198Y440771D01*
G01X607973Y438015D02*
X613752Y441614D01*
G01X614198Y440771D02*
X629701Y447612D01*
G01D02*
X630695Y447744D01*
G01X613752Y441614D02*
X629441Y448536D01*
G01X629701Y447612D02*
X630695Y447744D01*
G01X632659Y448007D02*
X633650Y448139D01*
G01X635613Y448402D02*
X640267Y449023D01*
G01X629441Y448536D02*
X640034Y449951D01*
G01X640267Y449023D02*
X642405Y449828D01*
G01X640034Y449951D02*
X641857Y450637D01*
G01X642405Y449828D02*
X649583Y457680D01*
G01X641857Y450637D02*
X648980Y458430D01*
G01X649583Y457680D02*
X673589Y471539D01*
G01X648980Y458430D02*
X673209Y472417D01*
G01X601873Y436629D02*
X606352Y440386D01*
G01X605785Y441152D02*
X625201Y453757D01*
G01X606352Y440386D02*
X614463Y445652D01*
G01X605785Y441152D02*
X625201Y453757D01*
G01X616057Y446687D02*
X616811Y447177D01*
G01X605785Y441152D02*
X625201Y453757D01*
G01X618406Y448212D02*
X619160Y448702D01*
G01X605785Y441152D02*
X625201Y453757D01*
G01X620755Y449737D02*
X621509Y450227D01*
G01X605785Y441152D02*
X625201Y453757D01*
G01X623104Y451262D02*
X623470Y451500D01*
G01X605785Y441152D02*
X625201Y453757D01*
G01X623470Y451500D02*
X625694Y452944D01*
G01X625201Y453757D02*
X637524Y460730D01*
G01X625694Y452944D02*
X626418Y453354D01*
G01X625201Y453757D02*
X637524Y460730D01*
G01X626418Y453354D02*
X628772Y454686D01*
G01X625201Y453757D02*
X637524Y460730D01*
G01X630427Y455622D02*
X637909Y459856D01*
G01X637524Y460730D02*
X651304Y465226D01*
G01X637909Y459856D02*
X641160Y460916D01*
G01X637524Y460730D02*
X651304Y465226D01*
G01X642967Y461506D02*
X643156Y461568D01*
G01X637524Y460730D02*
X651304Y465226D01*
G01X643156Y461568D02*
X643822Y461785D01*
G01X637524Y460730D02*
X651304Y465226D01*
G01X645629Y462375D02*
X646484Y462654D01*
G01X637524Y460730D02*
X651304Y465226D01*
G01X648292Y463244D02*
X651587Y464318D01*
G01D02*
X655433Y465458D01*
G01X603409Y444134D02*
X616252Y453253D01*
G01X603991Y443381D02*
X616771Y452456D01*
G01X616252Y453253D02*
X616671Y453502D01*
G01D02*
X632324Y462815D01*
G01X616771Y452456D02*
X632744Y461959D01*
G01X632324Y462815D02*
X636081Y464294D01*
G01D02*
X642655Y466884D01*
G01X632744Y461959D02*
X642973Y465988D01*
G01X661929Y434390D02*
X668470Y442188D01*
G01X667849Y442928D02*
X661275Y435090D01*
G01X632007Y412652D02*
X661929Y434390D01*
G01X661275Y435090D02*
X631347Y413347D01*
G01X628265Y408031D02*
X629230Y409221D01*
G01X629231Y409223D02*
X632007Y412652D01*
G01X631347Y413347D02*
X627585Y408701D01*
G01X623320Y403891D02*
X628265Y408031D01*
G01X627585Y408701D02*
X622456Y404407D01*
G01X678599Y457934D02*
X662877Y448855D01*
G01X663498Y448115D02*
X657142Y440540D01*
G01X662877Y448855D02*
X656489Y441240D01*
G01X657142Y440540D02*
X642163Y429652D01*
G01X656489Y441240D02*
X641810Y430571D01*
G01X642163Y429652D02*
X623894Y427734D01*
G01X641810Y430571D02*
X623600Y428659D01*
G01X623894Y427734D02*
X616177Y423420D01*
G01X623600Y428659D02*
X615557Y424163D01*
G01X616177Y423420D02*
X605011Y409874D01*
G01X615557Y424163D02*
X604278Y410479D01*
G01X603801Y408407D02*
X603229Y407713D01*
G01X610598Y428924D02*
X619238Y434571D01*
G01X609957Y429640D02*
X618807Y435425D01*
G01X619238Y434571D02*
X625410Y436865D01*
G01X627192Y437529D02*
X628789Y438122D01*
G01X630571Y438785D02*
X633313Y439804D01*
G01X618807Y435425D02*
X633082Y440732D01*
G01X633313Y439804D02*
X635567Y440105D01*
G01X637451Y440357D02*
X638888Y440548D01*
G01X640772Y440801D02*
X644654Y441319D01*
G01X633082Y440732D02*
X643156Y442077D01*
G01X640772Y440801D02*
X644654Y441319D01*
G01D02*
X650056Y445607D01*
G01X643156Y442077D02*
X644268Y442226D01*
G01X644654Y441319D02*
X650056Y445607D01*
G01X644268Y442226D02*
X649389Y446292D01*
G01X650056Y445607D02*
X652653Y448702D01*
G01X653876Y450158D02*
X655002Y451500D01*
G01D02*
X655831Y452487D01*
G01X649389Y446292D02*
X655210Y453227D01*
G01X655831Y452487D02*
X676291Y464299D01*
G01X655210Y453227D02*
X675911Y465177D01*
G01X616397Y438598D02*
X607031Y432253D01*
G01X607677Y431543D02*
X616839Y437749D01*
G01X616671Y438703D02*
X616397Y438598D01*
G01X616839Y437749D02*
X616900Y437772D01*
G01X631526Y444366D02*
X616900Y438790D01*
G01D02*
X616671Y438703D01*
G01D02*
X616397Y438598D01*
G01X616900Y437772D02*
X631762Y443438D01*
G01X642470Y445831D02*
X631526Y444366D01*
G01X631762Y443438D02*
X642813Y444918D01*
G01X643156Y446287D02*
X642470Y445831D01*
G01D02*
X631526Y444366D01*
G01X642813Y444918D02*
X643156Y445146D01*
G01X643602Y446583D02*
X643156Y446287D01*
G01D02*
X642470Y445831D01*
G01X643156Y445146D02*
X644191Y445833D01*
G01X645355Y448201D02*
X644477Y447391D01*
G01D02*
X644476D01*
G01D02*
X643602Y446583D01*
G01X644191Y445833D02*
X646044Y447544D01*
G01X651430Y455442D02*
X645355Y448201D01*
G01X646044Y447544D02*
X652051Y454702D01*
G01X674435Y468724D02*
X651430Y455442D01*
G01X652051Y454702D02*
X674815Y467846D01*
G01X665500Y444572D02*
X659436Y437346D01*
G01X665500Y444572D02*
X659436Y437346D01*
G01X664771Y445184D02*
X658783Y438046D01*
G01X659436Y437346D02*
X630180Y416087D01*
G01X658783Y438046D02*
X632907Y419243D01*
G01X659436Y437346D02*
X630180Y416087D01*
G01D02*
X629465Y415567D01*
G01X632907Y419243D02*
X628805Y416262D01*
G01X629465Y415567D02*
X628189Y413992D01*
G01D02*
X626546Y411963D01*
G01X628805Y416262D02*
X626546Y413472D01*
G01X628189Y413992D02*
X626546Y411963D01*
G01D02*
X626418Y411805D01*
G01D02*
X626156Y411481D01*
G01X626546Y413472D02*
X625489Y412167D01*
G01X626156Y411481D02*
X618894Y405933D01*
G01X625489Y412167D02*
X618034Y406473D01*
G01X618894Y405933D02*
X618511Y404062D01*
G01X649487Y404098D02*
X650182Y404816D01*
G01X651561Y406239D02*
X654214Y408976D01*
G01D02*
X668835Y419976D01*
G01X653583Y409691D02*
X668384Y420827D01*
G01X634875Y404030D02*
X636961Y406607D01*
G01X634137Y404629D02*
X634395Y404947D01*
G01X634875Y404030D02*
X636961Y406607D01*
G01X634395Y404947D02*
X636301Y407302D01*
G01X636961Y406607D02*
X666654Y428166D01*
G01X636301Y407302D02*
X641708Y411228D01*
G01X636961Y406607D02*
X666654Y428166D01*
G01X641708Y411228D02*
X665500Y428502D01*
G01X636961Y406607D02*
X666654Y428166D01*
G01X649487Y404098D02*
X650182Y404816D01*
G01X651561Y406239D02*
X654214Y408976D01*
G01X653583Y409691D02*
X668384Y420827D01*
G01X654214Y408976D02*
X668835Y419976D01*
G01X661441Y409645D02*
X670645Y416569D01*
G01X660809Y410360D02*
X670194Y417420D01*
G01X639002Y404538D02*
X668618Y426057D01*
G01X639662Y403842D02*
X640390Y404371D01*
G01X639002Y404538D02*
X668618Y426057D01*
G01X640390Y404371D02*
X641088Y404260D01*
G01X639002Y404538D02*
X668618Y426057D01*
G01X641928Y405488D02*
X642656Y406017D01*
G01X639002Y404538D02*
X668618Y426057D01*
G01X642656Y406017D02*
X643156Y405937D01*
G01X639002Y404538D02*
X668618Y426057D01*
G01X644194Y407134D02*
X644922Y407663D01*
G01X639002Y404538D02*
X668618Y426057D01*
G01X644922Y407663D02*
X645620Y407552D01*
G01X639002Y404538D02*
X668618Y426057D01*
G01X646460Y408781D02*
X647188Y409310D01*
G01X639002Y404538D02*
X668618Y426057D01*
G01X647188Y409310D02*
X647886Y409199D01*
G01X639002Y404538D02*
X668618Y426057D01*
G01X648726Y410427D02*
X651637Y412542D01*
G01X639002Y404538D02*
X668618Y426057D01*
G01X651637Y412542D02*
X669271Y425357D01*
G01X651304Y465226D02*
X655055Y466337D01*
G01X655433Y465458D02*
X672068Y475061D01*
G01X655055Y466337D02*
X671688Y475939D01*
G01X642973Y465988D02*
X652931Y469152D01*
G01X642655Y466884D02*
X652594Y470043D01*
G01X652931Y469152D02*
X658368Y471550D01*
G01X652594Y470043D02*
X657937Y472399D01*
G01X658368Y471550D02*
X670495Y478551D01*
G01X657937Y472399D02*
X670085Y479412D01*
G01X651304Y465226D02*
X655055Y466337D01*
G01D02*
X671688Y475939D01*
G01X655433Y465458D02*
X672068Y475061D01*
G01X642655Y466884D02*
X652594Y470043D01*
G01X642973Y465988D02*
X652931Y469152D01*
G01X652594Y470043D02*
X657937Y472399D01*
G01X652931Y469152D02*
X658368Y471550D01*
G01X657937Y472399D02*
X670085Y479412D01*
G01X658368Y471550D02*
X670495Y478551D01*
G01X694900Y94600D02*
X707465Y92889D01*
G01X695086Y95534D02*
X707617Y93828D01*
G01X707465Y92889D02*
X709158Y92569D01*
G01X707617Y93828D02*
X709260Y93517D01*
G01X709158Y92569D02*
X714213Y92427D01*
G01X709260Y93517D02*
X714098Y93381D01*
G01X714213Y92427D02*
X735002Y98137D01*
G01X714098Y93381D02*
X734851Y99081D01*
G01X695086Y95534D02*
X707617Y93828D01*
G01X694900Y94600D02*
X707465Y92889D01*
G01X707617Y93828D02*
X709260Y93517D01*
G01X707465Y92889D02*
X709158Y92569D01*
G01X709260Y93517D02*
X714098Y93381D01*
G01X709158Y92569D02*
X714213Y92427D01*
G01X714098Y93381D02*
X734851Y99081D01*
G01X714213Y92427D02*
X735002Y98137D01*
G01X671825Y99629D02*
X686081Y96933D01*
G01X671823Y100597D02*
X686323Y97852D01*
G01X686081Y96933D02*
X694900Y94600D01*
G01X686323Y97852D02*
X695086Y95534D01*
G01X673084Y105672D02*
X695505Y99587D01*
G01X673051Y104696D02*
X695325Y98651D01*
G01X695505Y99587D02*
X714206Y97429D01*
G01X695325Y98651D02*
X714283Y96463D01*
G01X714206Y97429D02*
X734264Y103074D01*
G01X714283Y96463D02*
X734566Y102171D01*
G01X671823Y100597D02*
X686323Y97852D01*
G01X671825Y99629D02*
X686081Y96933D01*
G01X686323Y97852D02*
X695086Y95534D01*
G01X686081Y96933D02*
X694900Y94600D01*
G01X673051Y104696D02*
X695325Y98651D01*
G01X673084Y105672D02*
X695505Y99587D01*
G01X695325Y98651D02*
X714283Y96463D01*
G01X695505Y99587D02*
X714206Y97429D01*
G01X714283Y96463D02*
X734566Y102171D01*
G01X714206Y97429D02*
X734264Y103074D01*
G01X672065Y109473D02*
X672085Y109474D01*
G01D02*
X672087D01*
G01D02*
X677677Y109646D01*
G01X672174Y108525D02*
X672180Y108526D01*
G01X672065Y109473D02*
X672085Y109474D01*
G01D02*
X672087D01*
G01D02*
X677677Y109646D01*
G01X672180Y108526D02*
X677681Y108695D01*
G01X677677Y109646D02*
X696790Y109207D01*
G01X677681Y108695D02*
X696707Y108258D01*
G01X696790Y109207D02*
X707264Y107601D01*
G01X696707Y108258D02*
X707072Y106669D01*
G01X707264Y107601D02*
X722003Y103781D01*
G01X707072Y106669D02*
X722000Y102800D01*
G01X722003Y103781D02*
X728888Y105521D01*
G01X722000Y102800D02*
X729121Y104600D01*
G01X665540Y131959D02*
X672900Y130900D01*
G01X665689Y132898D02*
X672983Y131848D01*
G01X672900Y130900D02*
X680445Y130658D01*
G01X672983Y131848D02*
X680582Y131605D01*
G01X680445Y130658D02*
X723014Y119535D01*
G01X680582Y131605D02*
X722991Y120523D01*
G01X723014Y119535D02*
X739839Y124767D01*
G01X722991Y120523D02*
X739543Y125670D01*
G01X724580Y116902D02*
X723082Y116564D01*
G01X723090Y115591D02*
X724830Y115984D01*
G01X746290Y123846D02*
X724580Y116902D01*
G01X724830Y115984D02*
X746420Y122890D01*
G01X674362Y122429D02*
X679536Y121647D01*
G01X674385Y121464D02*
X679228Y120732D01*
G01X679536Y121647D02*
X685062Y118631D01*
G01X679228Y120732D02*
X684772Y117706D01*
G01X685062Y118631D02*
X695986Y117446D01*
G01X684772Y117706D02*
X695850Y116505D01*
G01X695986Y117446D02*
X723542Y112476D01*
G01X695850Y116505D02*
X723563Y111506D01*
G01X723542Y112476D02*
X727006Y113255D01*
G01X723563Y111506D02*
X727267Y112339D01*
G01X671778Y112514D02*
X695015Y112501D01*
G01X671684Y113465D02*
X695092Y113451D01*
G01X695015Y112501D02*
X708349Y110337D01*
G01X695092Y113451D02*
X708513Y111273D01*
G01X708349Y110337D02*
X724041Y107387D01*
G01X708513Y111273D02*
X723993Y108363D01*
G01X724041Y107387D02*
X730402Y109239D01*
G01X723993Y108363D02*
X730111Y110144D01*
G01X672174Y108525D02*
X672180Y108526D01*
G01X672174Y108525D02*
X672180Y108526D01*
G01D02*
X677681Y108695D01*
G01X672065Y109473D02*
X672085Y109474D01*
G01X672174Y108525D02*
X672180Y108526D01*
G01D02*
X677681Y108695D01*
G01X672085Y109474D02*
X672087D01*
G01X672174Y108525D02*
X672180Y108526D01*
G01D02*
X677681Y108695D01*
G01X672087Y109474D02*
X677677Y109646D01*
G01X677681Y108695D02*
X696707Y108258D01*
G01X677677Y109646D02*
X696790Y109207D01*
G01X696707Y108258D02*
X707072Y106669D01*
G01X696790Y109207D02*
X707264Y107601D01*
G01X707072Y106669D02*
X722000Y102800D01*
G01X707264Y107601D02*
X722003Y103781D01*
G01X722000Y102800D02*
X729121Y104600D01*
G01X722003Y103781D02*
X728888Y105521D01*
G01X673051Y104696D02*
X695325Y98651D01*
G01X673084Y105672D02*
X695505Y99587D01*
G01X695325Y98651D02*
X714283Y96463D01*
G01X695505Y99587D02*
X714206Y97429D01*
G01X714283Y96463D02*
X734566Y102171D01*
G01X714206Y97429D02*
X734264Y103074D01*
G01X665689Y132898D02*
X672983Y131848D01*
G01X665540Y131959D02*
X672900Y130900D01*
G01X672983Y131848D02*
X680582Y131605D01*
G01X672900Y130900D02*
X680445Y130658D01*
G01X680582Y131605D02*
X722991Y120523D01*
G01X680445Y130658D02*
X723014Y119535D01*
G01X722991Y120523D02*
X739543Y125670D01*
G01X723014Y119535D02*
X739839Y124767D01*
G01X724830Y115984D02*
X746420Y122890D01*
G01X746290Y123846D02*
X724580Y116902D01*
G01X723090Y115591D02*
X724830Y115984D01*
G01X724580Y116902D02*
X723082Y116564D01*
G01X674385Y121464D02*
X679228Y120732D01*
G01X674362Y122429D02*
X679536Y121647D01*
G01X679228Y120732D02*
X684772Y117706D01*
G01X679536Y121647D02*
X685062Y118631D01*
G01X684772Y117706D02*
X695850Y116505D01*
G01X685062Y118631D02*
X695986Y117446D01*
G01X695850Y116505D02*
X723563Y111506D01*
G01X695986Y117446D02*
X723542Y112476D01*
G01X723563Y111506D02*
X727267Y112339D01*
G01X723542Y112476D02*
X727006Y113255D01*
G01X671684Y113465D02*
X695092Y113451D01*
G01X671778Y112514D02*
X695015Y112501D01*
G01X695092Y113451D02*
X708513Y111273D01*
G01X695015Y112501D02*
X708349Y110337D01*
G01X708513Y111273D02*
X723993Y108363D01*
G01X708349Y110337D02*
X724041Y107387D01*
G01X723993Y108363D02*
X730111Y110144D01*
G01X724041Y107387D02*
X730402Y109239D01*
G01X665446Y152030D02*
X674173Y153752D01*
G01D02*
X728520Y135499D01*
G01X674110Y152771D02*
X728472Y134512D01*
G01X664175Y145827D02*
X666040Y145399D01*
G01X670133Y140179D02*
X665572Y144531D01*
G01X666040Y145399D02*
X670560Y141086D01*
G01X689396Y137906D02*
X670133Y140179D01*
G01X670560Y141086D02*
X688178Y139007D01*
G01X689396Y137906D02*
X670133Y140179D01*
G01X688178Y139007D02*
X689646Y138823D01*
G01X723534Y128573D02*
X689396Y137906D01*
G01X689646Y138823D02*
X723537Y129558D01*
G01X737203Y132225D02*
X723534Y128573D01*
G01X723537Y129558D02*
X736958Y133143D01*
G01X737203Y132225D02*
X723534Y128573D01*
G01X723057Y124696D02*
X744116Y131296D01*
G01X744233Y130337D02*
X723075Y123706D01*
G01X684182Y135335D02*
X723057Y124696D01*
G01X723075Y123706D02*
X683931Y134418D01*
G01X684027Y135364D02*
X684182Y135335D01*
G01X676108Y165647D02*
X712039Y152236D01*
G01X676176Y166636D02*
X712329Y153142D01*
G01X712039Y152236D02*
X728750Y147732D01*
G01X712329Y153142D02*
X728790Y148706D01*
G01X675047Y160983D02*
X696028Y153734D01*
G01Y153735D02*
X717010Y146485D01*
G01X675116Y161965D02*
X717275Y147399D01*
G01X717010Y146485D02*
X729298Y143578D01*
G01X717275Y147399D02*
X729296Y144555D01*
G01X731055Y140111D02*
X720384Y142306D01*
G01X731059Y139140D02*
X720133Y141387D01*
G01X720384Y142306D02*
X679128Y156439D01*
G01X720133Y141387D02*
X678851Y155529D01*
G01D02*
X673967Y156831D01*
G01X665446Y152030D02*
X674173Y153752D01*
G01X674110Y152771D02*
X728472Y134512D01*
G01X674173Y153752D02*
X728520Y135499D01*
G01X723537Y129558D02*
X736958Y133143D01*
G01X737203Y132225D02*
X723534Y128573D01*
G01X689646Y138823D02*
X723537Y129558D01*
G01X723534Y128573D02*
X689396Y137906D01*
G01X670560Y141086D02*
X688178Y139007D01*
G01D02*
X689646Y138823D01*
G01X689396Y137906D02*
X670133Y140179D01*
G01X666040Y145399D02*
X670560Y141086D01*
G01X670133Y140179D02*
X665572Y144531D01*
G01X664175Y145827D02*
X666040Y145399D01*
G01X684027Y135364D02*
X684182Y135335D01*
G01X723075Y123706D02*
X683931Y134418D01*
G01X684182Y135335D02*
X723057Y124696D01*
G01X744233Y130337D02*
X723075Y123706D01*
G01X723057Y124696D02*
X744116Y131296D01*
G01X676176Y166636D02*
X712329Y153142D01*
G01X676108Y165647D02*
X712039Y152236D01*
G01X712329Y153142D02*
X728790Y148706D01*
G01X712039Y152236D02*
X728750Y147732D01*
G01X675116Y161965D02*
X717275Y147399D01*
G01X675047Y160983D02*
X696028Y153734D01*
G01X675116Y161965D02*
X717275Y147399D01*
G01X696028Y153735D02*
X717010Y146485D01*
G01X717275Y147399D02*
X729296Y144555D01*
G01X717010Y146485D02*
X729298Y143578D01*
G01X731059Y139140D02*
X720133Y141387D01*
G01X731055Y140111D02*
X720384Y142306D01*
G01X720133Y141387D02*
X678851Y155529D01*
G01X720384Y142306D02*
X679128Y156439D01*
G01X678851Y155529D02*
X673967Y156831D01*
G01X724580Y116902D02*
X723082Y116564D01*
G01X723090Y115591D02*
X724830Y115984D01*
G01X746290Y123846D02*
X724580Y116902D01*
G01X724830Y115984D02*
X746420Y122890D01*
G01X672174Y108525D02*
X672180Y108526D01*
G01X672174Y108525D02*
X672180Y108526D01*
G01D02*
X677681Y108695D01*
G01X672065Y109473D02*
X672085Y109474D01*
G01X672174Y108525D02*
X672180Y108526D01*
G01D02*
X677681Y108695D01*
G01X672085Y109474D02*
X672087D01*
G01X672174Y108525D02*
X672180Y108526D01*
G01D02*
X677681Y108695D01*
G01X672087Y109474D02*
X677677Y109646D01*
G01X677681Y108695D02*
X696707Y108258D01*
G01X677677Y109646D02*
X696790Y109207D01*
G01X696707Y108258D02*
X707072Y106669D01*
G01X696790Y109207D02*
X707264Y107601D01*
G01X707072Y106669D02*
X722000Y102800D01*
G01X707264Y107601D02*
X722003Y103781D01*
G01X722000Y102800D02*
X729121Y104600D01*
G01X722003Y103781D02*
X728888Y105521D01*
G01X664175Y145827D02*
X666040Y145399D01*
G01X670133Y140179D02*
X665572Y144531D01*
G01X666040Y145399D02*
X670560Y141086D01*
G01X689396Y137906D02*
X670133Y140179D01*
G01X670560Y141086D02*
X688178Y139007D01*
G01X689396Y137906D02*
X670133Y140179D01*
G01X688178Y139007D02*
X689646Y138823D01*
G01X723534Y128573D02*
X689396Y137906D01*
G01X689646Y138823D02*
X723537Y129558D01*
G01X737203Y132225D02*
X723534Y128573D01*
G01X723537Y129558D02*
X736958Y133143D01*
G01X737203Y132225D02*
X723534Y128573D01*
G01X674362Y122429D02*
X679536Y121647D01*
G01X674385Y121464D02*
X679228Y120732D01*
G01X679536Y121647D02*
X685062Y118631D01*
G01X679228Y120732D02*
X684772Y117706D01*
G01X685062Y118631D02*
X695986Y117446D01*
G01X684772Y117706D02*
X695850Y116505D01*
G01X695986Y117446D02*
X723542Y112476D01*
G01X695850Y116505D02*
X723563Y111506D01*
G01X723542Y112476D02*
X727006Y113255D01*
G01X723563Y111506D02*
X727267Y112339D01*
G01X731055Y140111D02*
X720384Y142306D01*
G01X731059Y139140D02*
X720133Y141387D01*
G01X720384Y142306D02*
X679128Y156439D01*
G01X720133Y141387D02*
X678851Y155529D01*
G01D02*
X673967Y156831D01*
G01X684027Y135364D02*
X684182Y135335D01*
G01X723075Y123706D02*
X683931Y134418D01*
G01X684182Y135335D02*
X723057Y124696D01*
G01X744233Y130337D02*
X723075Y123706D01*
G01X723057Y124696D02*
X744116Y131296D01*
G01X671037Y176163D02*
X675261Y174686D01*
G01X675010Y173767D02*
X722353Y164299D01*
G01X675261Y174686D02*
X722556Y165228D01*
G01X722353Y164299D02*
X735830Y161094D01*
G01X722556Y165228D02*
X729233Y163640D01*
G01X722353Y164299D02*
X735830Y161094D01*
G01X673349Y171088D02*
X714334Y162903D01*
G01X673378Y170113D02*
X714116Y161977D01*
G01X714334Y162903D02*
X732284Y158024D01*
G01X714116Y161977D02*
X732061Y157100D01*
G01X679128Y156439D02*
X673995Y157807D01*
G01X679754Y177733D02*
X706967Y172289D01*
G01D02*
X725781Y168525D01*
G01X679511Y176812D02*
X725692Y167573D01*
G01X671037Y176163D02*
X675261Y174686D01*
G01D02*
X722556Y165228D01*
G01X675010Y173767D02*
X722353Y164299D01*
G01X722556Y165228D02*
X729233Y163640D01*
G01X722353Y164299D02*
X735830Y161094D01*
G01X673378Y170113D02*
X714116Y161977D01*
G01X673349Y171088D02*
X714334Y162903D01*
G01X714116Y161977D02*
X732061Y157100D01*
G01X714334Y162903D02*
X732284Y158024D01*
G01X679128Y156439D02*
X673995Y157807D01*
G01X679726Y181762D02*
X726585Y172390D01*
G01X679481Y180842D02*
X726496Y171438D01*
G01X679511Y176812D02*
X725692Y167573D01*
G01X679754Y177733D02*
X706967Y172289D01*
G01X679511Y176812D02*
X725692Y167573D01*
G01X706967Y172289D02*
X725781Y168525D01*
G01X681191Y185426D02*
X726940Y176276D01*
G01X680930Y184509D02*
X726848Y175325D01*
G01X679481Y180842D02*
X726496Y171438D01*
G01X679726Y181762D02*
X726585Y172390D01*
G01X683694Y192797D02*
X726923Y184260D01*
G01X683694Y192797D02*
X726923Y184260D01*
G01X726739Y183327D02*
X683414Y191883D01*
G01X727302Y180122D02*
X682314Y189118D01*
G01X727212Y179171D02*
X682049Y188202D01*
G01X682314Y189118D02*
X671372Y193310D01*
G01D02*
X671371D01*
G01X680930Y184509D02*
X726848Y175325D01*
G01X681191Y185426D02*
X726940Y176276D01*
G01X726739Y183327D02*
X683414Y191883D01*
G01X683694Y192797D02*
X726923Y184260D01*
G01X726739Y183327D02*
X683414Y191883D01*
G01X727212Y179171D02*
X682049Y188202D01*
G01X727302Y180122D02*
X682314Y189118D01*
G01D02*
X671372Y193310D01*
G01D02*
X671371D01*
G01X679128Y156439D02*
X673995Y157807D01*
G01X683694Y192797D02*
X726923Y184260D01*
G01X683694Y192797D02*
X726923Y184260D01*
G01X726739Y183327D02*
X683414Y191883D01*
G01X679726Y181762D02*
X726585Y172390D01*
G01X679481Y180842D02*
X726496Y171438D01*
G01X679511Y176812D02*
X725692Y167573D01*
G01X679754Y177733D02*
X706967Y172289D01*
G01X679511Y176812D02*
X725692Y167573D01*
G01X706967Y172289D02*
X725781Y168525D01*
G01X673378Y170113D02*
X714116Y161977D01*
G01X673349Y171088D02*
X714334Y162903D01*
G01X714116Y161977D02*
X732061Y157100D01*
G01X714334Y162903D02*
X732284Y158024D01*
G01X671037Y176163D02*
X675261Y174686D01*
G01X675010Y173767D02*
X722353Y164299D01*
G01X675261Y174686D02*
X722556Y165228D01*
G01X722353Y164299D02*
X735830Y161094D01*
G01X722556Y165228D02*
X729233Y163640D01*
G01X722353Y164299D02*
X735830Y161094D01*
G01X727212Y179171D02*
X682049Y188202D01*
G01X727302Y180122D02*
X682314Y189118D01*
G01D02*
X671372Y193310D01*
G01D02*
X671371D01*
G01X696340Y302439D02*
X695439D01*
G01X695611Y303389D02*
X696398D01*
G01X695611D02*
X696398D01*
G01X696340Y302439D02*
X695439D01*
G01X667897Y379037D02*
X675622Y390754D01*
G01X668655Y378460D02*
X676334Y390107D01*
G01X675622Y390754D02*
X681189Y395247D01*
G01X676334Y390107D02*
X681622Y394374D01*
G01X681189Y395247D02*
X707777Y401782D01*
G01X681622Y394374D02*
X708144Y400893D01*
G01X707777Y401782D02*
X713494Y405219D01*
G01X708144Y400893D02*
X713923Y404368D01*
G01X672567Y391879D02*
X677755Y396847D01*
G01X671832Y392492D02*
X677187Y397620D01*
G01X677755Y396847D02*
X679382Y397742D01*
G01X677187Y397620D02*
X679034Y398635D01*
G01X679382Y397742D02*
X706692Y404460D01*
G01X679034Y398635D02*
X706325Y405349D01*
G01X668866Y395012D02*
X674722Y400620D01*
G01X669601Y394399D02*
X675290Y399847D01*
G01X674722Y400620D02*
X677640Y402227D01*
G01X675290Y399847D02*
X677989Y401334D01*
G01X677640Y402227D02*
X702042Y408227D01*
G01X677989Y401334D02*
X702409Y407338D01*
G01X666638Y396837D02*
X673223Y403144D01*
G01X665903Y397450D02*
X672655Y403917D01*
G01X663533Y399137D02*
X672046Y407292D01*
G01X668655Y378460D02*
X676334Y390107D01*
G01X667897Y379037D02*
X675622Y390754D01*
G01X676334Y390107D02*
X681622Y394374D01*
G01X675622Y390754D02*
X681189Y395247D01*
G01X681622Y394374D02*
X708144Y400893D01*
G01X681189Y395247D02*
X707777Y401782D01*
G01X708144Y400893D02*
X713923Y404368D01*
G01X707777Y401782D02*
X713494Y405219D01*
G01X671832Y392492D02*
X677187Y397620D01*
G01X672567Y391879D02*
X677755Y396847D01*
G01X677187Y397620D02*
X679034Y398635D01*
G01X677755Y396847D02*
X679382Y397742D01*
G01X679034Y398635D02*
X706325Y405349D01*
G01X679382Y397742D02*
X706692Y404460D01*
G01X671832Y392492D02*
X677187Y397620D01*
G01X672567Y391879D02*
X677755Y396847D01*
G01X677187Y397620D02*
X679034Y398635D01*
G01X677755Y396847D02*
X679382Y397742D01*
G01X679034Y398635D02*
X706325Y405349D01*
G01X679382Y397742D02*
X706692Y404460D01*
G01X669601Y394399D02*
X675290Y399847D01*
G01X668866Y395012D02*
X674722Y400620D01*
G01X675290Y399847D02*
X677989Y401334D01*
G01X674722Y400620D02*
X677640Y402227D01*
G01X677989Y401334D02*
X702409Y407338D01*
G01X677640Y402227D02*
X702042Y408227D01*
G01X665903Y397450D02*
X672655Y403917D01*
G01X666638Y396837D02*
X673223Y403144D01*
G01X663533Y399137D02*
X672046Y407292D01*
G01X671904Y346362D02*
Y348916D01*
G01X670954Y346322D02*
Y349446D01*
G01Y346322D02*
Y349446D01*
G01X671904Y346362D02*
Y348916D01*
G01X668866Y395012D02*
X674722Y400620D01*
G01X669601Y394399D02*
X675290Y399847D01*
G01X674722Y400620D02*
X677640Y402227D01*
G01X675290Y399847D02*
X677989Y401334D01*
G01X677640Y402227D02*
X702042Y408227D01*
G01X677989Y401334D02*
X702409Y407338D01*
G01X666638Y396837D02*
X673223Y403144D01*
G01X665903Y397450D02*
X672655Y403917D01*
G01X665903Y397450D02*
X672655Y403917D01*
G01X666638Y396837D02*
X673223Y403144D01*
G01X669601Y394399D02*
X675290Y399847D01*
G01X668866Y395012D02*
X674722Y400620D01*
G01X675290Y399847D02*
X677989Y401334D01*
G01X674722Y400620D02*
X677640Y402227D01*
G01X677989Y401334D02*
X702409Y407338D01*
G01X677640Y402227D02*
X702042Y408227D01*
G01X663533Y399137D02*
X672046Y407292D01*
G01X713494Y405219D02*
X730059Y412074D01*
G01X713923Y404368D02*
X730327Y411156D01*
G01X663504Y431818D02*
X670233Y439836D01*
G01X670232D02*
X670341Y439965D01*
G01X664157Y431118D02*
X670961Y439225D01*
G01X670341Y439965D02*
X682775Y447131D01*
G01X670961Y439225D02*
X683155Y446252D01*
G01X682775Y447131D02*
X689183Y449061D01*
G01X683155Y446252D02*
X689352Y448119D01*
G01X689183Y449061D02*
X706967Y450176D01*
G01X689352Y448119D02*
X706967Y449224D01*
G01Y450176D02*
X729788Y451607D01*
G01X706967Y449224D02*
X730129Y450676D01*
G01X688579Y451890D02*
X730226Y454501D01*
G01X729885Y455432D02*
X688410Y452832D01*
G01X681650Y449798D02*
X688579Y451890D01*
G01X688410Y452832D02*
X681270Y450676D01*
G01X668470Y442188D02*
X681650Y449798D01*
G01X681270Y450676D02*
X667849Y442928D01*
G01X761715Y472392D02*
X721012Y458703D01*
G01X761715Y472392D02*
X721012Y458703D01*
G01X760700Y471047D02*
X721196Y457762D01*
G01X721012Y458703D02*
X687713Y456615D01*
G01X721196Y457762D02*
X687883Y455673D01*
G01X687713Y456615D02*
X679766Y454214D01*
G01X687883Y455673D02*
X680146Y453336D01*
G01X679766Y454214D02*
X665367Y445893D01*
G01X680146Y453336D02*
X665988Y445154D01*
G01X665367Y445893D02*
X664772Y445183D01*
G01X665988Y445154D02*
X665500Y444572D01*
G01X665367Y445893D02*
X664772Y445183D01*
G01X760700Y475067D02*
X720466Y461534D01*
G01X760700Y476070D02*
X720281Y462475D01*
G01X720466Y461534D02*
X686821Y459423D01*
G01X720281Y462475D02*
X686652Y460365D01*
G01X686821Y459423D02*
X678979Y457056D01*
G01X686652Y460365D02*
X678599Y457934D01*
G01X678979Y457056D02*
X663498Y448115D01*
G01X677381Y461629D02*
X685627Y464118D01*
G01X677761Y460751D02*
X685796Y463176D01*
G01X685627Y464118D02*
X719538Y466245D01*
G01X685796Y463176D02*
X719722Y465304D01*
G01X676291Y464299D02*
X685069Y466949D01*
G01X706692Y404460D02*
X713343Y408458D01*
G01X706325Y405349D02*
X712916Y409311D01*
G01X713343Y408458D02*
X717543Y410169D01*
G01X712916Y409311D02*
X717141Y411032D01*
G01X717543Y410169D02*
X717704Y410254D01*
G01X717141Y411032D02*
X717221Y411074D01*
G01X717704Y410254D02*
X720457Y412053D01*
G01X717221Y411074D02*
X720040Y412916D01*
G01X720457Y412053D02*
X728454Y414718D01*
G01X720040Y412916D02*
X728284Y415663D01*
G01X702042Y408227D02*
X711247Y413761D01*
G01X702409Y407338D02*
X711662Y412901D01*
G01X711247Y413761D02*
X713795Y414711D01*
G01X711662Y412901D02*
X714127Y413819D01*
G01X713795Y414711D02*
X719600Y417800D01*
G01X714241Y413872D02*
X719900Y416883D01*
G01X719600Y417800D02*
X727200Y418900D01*
G01X719900Y416883D02*
X727298Y417954D01*
G01X673223Y403144D02*
X676564Y404985D01*
G01X672655Y403917D02*
X676215Y405878D01*
G01X676564Y404985D02*
X693672Y409193D01*
G01X676215Y405878D02*
X693208Y410058D01*
G01X693672Y409193D02*
X695161Y410561D01*
G01D02*
X695812Y410532D01*
G01X693208Y410058D02*
X694517Y411260D01*
G01X695161Y410561D02*
X695812Y410532D01*
G01X696503Y411795D02*
X697167Y412405D01*
G01D02*
X697818Y412376D01*
G01X698509Y413639D02*
X699173Y414249D01*
G01D02*
X699824Y414220D01*
G01X700515Y415484D02*
X706710Y421179D01*
G01X694517Y411261D02*
X706195Y421997D01*
G01X706710Y421179D02*
X707991Y421692D01*
G01X706195Y421997D02*
X707720Y422607D01*
G01X707991Y421692D02*
X714008Y422889D01*
G01X707720Y422607D02*
X713909Y423838D01*
G01X714008Y422889D02*
X719096Y422949D01*
G01X713909Y423838D02*
X719100Y423900D01*
G01X719096Y422949D02*
X733347Y422657D01*
G01X719100Y423900D02*
X733367Y423607D01*
G01X672046Y407292D02*
X682783Y412673D01*
G01X671492Y408077D02*
X682414Y413552D01*
G01X682783Y412673D02*
X697201Y417611D01*
G01X682414Y413552D02*
X696704Y418446D01*
G01X697201Y417611D02*
X706618Y426265D01*
G01X696704Y418446D02*
X706222Y427193D01*
G01X706618Y426265D02*
X726098Y427489D01*
G01X706222Y427193D02*
X726093Y428441D01*
G01X670632Y411214D02*
X671324Y411199D01*
G01X672062Y412585D02*
X672784Y413276D01*
G01D02*
X674626Y413906D01*
G01X676500Y414549D02*
X695202Y420950D01*
G01X672278Y414107D02*
X694705Y421785D01*
G01X695202Y420950D02*
X705029Y429984D01*
G01X694705Y421785D02*
X704633Y430912D01*
G01X705029Y429984D02*
X734373Y431824D01*
G01X704633Y430912D02*
X734087Y432758D01*
G01X670194Y417420D02*
X692709Y425124D01*
G01X670645Y416569D02*
X693206Y424289D01*
G01X692709Y425124D02*
X703045Y434629D01*
G01X693206Y424289D02*
X703441Y433701D01*
G01X703045Y434629D02*
X733676Y436549D01*
G01X703441Y433701D02*
X733950Y435614D01*
G01X668384Y420827D02*
X690718Y428469D01*
G01X668835Y419976D02*
X691215Y427634D01*
G01X690718Y428469D02*
X701460Y438346D01*
G01X691215Y427634D02*
X701856Y437418D01*
G01X701460Y438346D02*
X731174Y440234D01*
G01X701856Y437419D02*
X732574Y439371D01*
G01X669271Y425357D02*
X675573Y432864D01*
G01X668618Y426057D02*
X674953Y433603D01*
G01X675573Y432864D02*
X686395Y439113D01*
G01X674953Y433603D02*
X686015Y439991D01*
G01X686395Y439113D02*
X691251Y440580D01*
G01X686015Y439991D02*
X691081Y441522D01*
G01X691251Y440580D02*
X730011Y443034D01*
G01X691081Y441522D02*
X729669Y443965D01*
G01X665500Y428502D02*
X666001Y428866D01*
G01X666654Y428166D02*
X673433Y436243D01*
G01X666001Y428866D02*
X672812Y436983D01*
G01X673433Y436243D02*
X684331Y442534D01*
G01X672812Y436983D02*
X678783Y440429D01*
G01X673433Y436243D02*
X684331Y442534D01*
G01X678783Y440429D02*
X683951Y443412D01*
G01X684331Y442534D02*
X690407Y444367D01*
G01X683951Y443412D02*
X690238Y445309D01*
G01X690407Y444367D02*
X706967Y445406D01*
G01X690238Y445309D02*
X706967Y446358D01*
G01Y445406D02*
X730029Y446852D01*
G01X706967Y446358D02*
X729688Y447783D01*
G01X713923Y404368D02*
X730327Y411156D01*
G01X713494Y405219D02*
X730059Y412074D01*
G01X664157Y431118D02*
X670961Y439225D01*
G01X663504Y431818D02*
X670233Y439836D01*
G01X664157Y431118D02*
X670961Y439225D01*
G01X670232Y439836D02*
X670341Y439965D01*
G01X670961Y439225D02*
X683155Y446252D01*
G01X670341Y439965D02*
X682775Y447131D01*
G01X683155Y446252D02*
X689352Y448119D01*
G01X682775Y447131D02*
X689183Y449061D01*
G01X689352Y448119D02*
X706967Y449224D01*
G01X689183Y449061D02*
X706967Y450176D01*
G01Y449224D02*
X730129Y450676D01*
G01X706967Y450176D02*
X729788Y451607D01*
G01X664157Y431118D02*
X670961Y439225D01*
G01X663504Y431818D02*
X670233Y439836D01*
G01X664157Y431118D02*
X670961Y439225D01*
G01X670232Y439836D02*
X670341Y439965D01*
G01X670961Y439225D02*
X683155Y446252D01*
G01X670341Y439965D02*
X682775Y447131D01*
G01X683155Y446252D02*
X689352Y448119D01*
G01X682775Y447131D02*
X689183Y449061D01*
G01X689352Y448119D02*
X706967Y449224D01*
G01X689183Y449061D02*
X706967Y450176D01*
G01Y449224D02*
X730129Y450676D01*
G01X706967Y450176D02*
X729788Y451607D01*
G01X681270Y450676D02*
X667849Y442928D01*
G01X668470Y442188D02*
X681650Y449798D01*
G01X688410Y452832D02*
X681270Y450676D01*
G01X681650Y449798D02*
X688579Y451890D01*
G01X729885Y455432D02*
X688410Y452832D01*
G01X688579Y451890D02*
X730226Y454501D01*
G01X760700Y471047D02*
X721196Y457762D01*
G01X761715Y472392D02*
X721012Y458703D01*
G01X721196Y457762D02*
X687883Y455673D01*
G01X721012Y458703D02*
X687713Y456615D01*
G01X687883Y455673D02*
X680146Y453336D01*
G01X687713Y456615D02*
X679766Y454214D01*
G01X680146Y453336D02*
X665988Y445154D01*
G01X679766Y454214D02*
X665367Y445893D01*
G01X665988Y445154D02*
X665500Y444572D01*
G01X665367Y445893D02*
X664772Y445183D01*
G01X665988Y445154D02*
X665500Y444572D01*
G01X760700Y476070D02*
X720281Y462475D01*
G01X760700Y476070D02*
X720281Y462475D01*
G01X760700Y475067D02*
X720466Y461534D01*
G01X720281Y462475D02*
X686652Y460365D01*
G01X720466Y461534D02*
X686821Y459423D01*
G01X686652Y460365D02*
X678599Y457934D01*
G01X686821Y459423D02*
X678979Y457056D01*
G01D02*
X663498Y448115D01*
G01X677761Y460751D02*
X685796Y463176D01*
G01X677381Y461629D02*
X685627Y464118D01*
G01X685796Y463176D02*
X719722Y465304D01*
G01X685627Y464118D02*
X719538Y466245D01*
G01X676291Y464299D02*
X685069Y466949D01*
G01X706325Y405349D02*
X712916Y409311D01*
G01X706692Y404460D02*
X713343Y408458D01*
G01X712916Y409311D02*
X717141Y411032D01*
G01X713343Y408458D02*
X717543Y410169D01*
G01X717141Y411032D02*
X717221Y411074D01*
G01X717543Y410169D02*
X717704Y410254D01*
G01X717221Y411074D02*
X720040Y412916D01*
G01X717704Y410254D02*
X720457Y412053D01*
G01X720040Y412916D02*
X728284Y415663D01*
G01X720457Y412053D02*
X728454Y414718D01*
G01X706325Y405349D02*
X712916Y409311D01*
G01X706692Y404460D02*
X713343Y408458D01*
G01X712916Y409311D02*
X717141Y411032D01*
G01X713343Y408458D02*
X717543Y410169D01*
G01X717141Y411032D02*
X717221Y411074D01*
G01X717543Y410169D02*
X717704Y410254D01*
G01X717221Y411074D02*
X720040Y412916D01*
G01X717704Y410254D02*
X720457Y412053D01*
G01X720040Y412916D02*
X728284Y415663D01*
G01X720457Y412053D02*
X728454Y414718D01*
G01X702409Y407338D02*
X711662Y412901D01*
G01X702042Y408227D02*
X711247Y413761D01*
G01X711662Y412901D02*
X714127Y413819D01*
G01X711247Y413761D02*
X713795Y414711D01*
G01X714241Y413872D02*
X719900Y416883D01*
G01X713795Y414711D02*
X719600Y417800D01*
G01X719900Y416883D02*
X727298Y417954D01*
G01X719600Y417800D02*
X727200Y418900D01*
G01X672655Y403917D02*
X676215Y405878D01*
G01X673223Y403144D02*
X676564Y404985D01*
G01X676215Y405878D02*
X693208Y410058D01*
G01X676564Y404985D02*
X693672Y409193D01*
G01X693208Y410058D02*
X694517Y411260D01*
G01X693672Y409193D02*
X695161Y410561D01*
G01X693208Y410058D02*
X694517Y411260D01*
G01Y411261D02*
X706195Y421997D01*
G01X695161Y410561D02*
X695812Y410532D01*
G01X694517Y411261D02*
X706195Y421997D01*
G01X696503Y411795D02*
X697167Y412405D01*
G01X694517Y411261D02*
X706195Y421997D01*
G01X697167Y412405D02*
X697818Y412376D01*
G01X694517Y411261D02*
X706195Y421997D01*
G01X698509Y413639D02*
X699173Y414249D01*
G01X694517Y411261D02*
X706195Y421997D01*
G01X699173Y414249D02*
X699824Y414220D01*
G01X694517Y411261D02*
X706195Y421997D01*
G01X700515Y415484D02*
X706710Y421179D01*
G01X706195Y421997D02*
X707720Y422607D01*
G01X706710Y421179D02*
X707991Y421692D01*
G01X707720Y422607D02*
X713909Y423838D01*
G01X707991Y421692D02*
X714008Y422889D01*
G01X713909Y423838D02*
X719100Y423900D01*
G01X714008Y422889D02*
X719096Y422949D01*
G01X719100Y423900D02*
X733367Y423607D01*
G01X719096Y422949D02*
X733347Y422657D01*
G01X671492Y408077D02*
X682414Y413552D01*
G01X672046Y407292D02*
X682783Y412673D01*
G01X682414Y413552D02*
X696704Y418446D01*
G01X682783Y412673D02*
X697201Y417611D01*
G01X696704Y418446D02*
X706222Y427193D01*
G01X697201Y417611D02*
X706618Y426265D01*
G01X706222Y427193D02*
X726093Y428441D01*
G01X706618Y426265D02*
X726098Y427489D01*
G01X670632Y411214D02*
X671324Y411199D01*
G01X672062Y412585D02*
X672784Y413276D01*
G01X672278Y414107D02*
X694705Y421785D01*
G01X672784Y413276D02*
X674626Y413906D01*
G01X672278Y414107D02*
X694705Y421785D01*
G01X676500Y414549D02*
X695202Y420950D01*
G01X694705Y421785D02*
X704633Y430912D01*
G01X695202Y420950D02*
X705029Y429984D01*
G01X704633Y430912D02*
X734087Y432758D01*
G01X705029Y429984D02*
X734373Y431824D01*
G01X670645Y416569D02*
X693206Y424289D01*
G01X670194Y417420D02*
X692709Y425124D01*
G01X693206Y424289D02*
X703441Y433701D01*
G01X692709Y425124D02*
X703045Y434629D01*
G01X703441Y433701D02*
X733950Y435614D01*
G01X703045Y434629D02*
X733676Y436549D01*
G01X668835Y419976D02*
X691215Y427634D01*
G01X668384Y420827D02*
X690718Y428469D01*
G01X691215Y427634D02*
X701856Y437418D01*
G01X690718Y428469D02*
X701460Y438346D01*
G01X701856Y437419D02*
X732574Y439371D01*
G01X701460Y438346D02*
X731174Y440234D01*
G01X701856Y437419D02*
X732574Y439371D01*
G01X668618Y426057D02*
X674953Y433603D01*
G01X669271Y425357D02*
X675573Y432864D01*
G01X674953Y433603D02*
X686015Y439991D01*
G01X675573Y432864D02*
X686395Y439113D01*
G01X686015Y439991D02*
X691081Y441522D01*
G01X686395Y439113D02*
X691251Y440580D01*
G01X691081Y441522D02*
X729669Y443965D01*
G01X691251Y440580D02*
X730011Y443034D01*
G01X665500Y428502D02*
X666001Y428866D01*
G01D02*
X672812Y436983D01*
G01X666654Y428166D02*
X673433Y436243D01*
G01X672812Y436983D02*
X678783Y440429D01*
G01D02*
X683951Y443412D01*
G01X673433Y436243D02*
X684331Y442534D01*
G01X683951Y443412D02*
X690238Y445309D01*
G01X684331Y442534D02*
X690407Y444367D01*
G01X690238Y445309D02*
X706967Y446358D01*
G01X690407Y444367D02*
X706967Y445406D01*
G01Y446358D02*
X729688Y447783D01*
G01X706967Y445406D02*
X730029Y446852D01*
G01X677761Y460751D02*
X685796Y463176D01*
G01X677381Y461629D02*
X685627Y464118D01*
G01X685796Y463176D02*
X719722Y465304D01*
G01X685627Y464118D02*
X719538Y466245D01*
G01X688579Y451890D02*
X730226Y454501D01*
G01X729885Y455432D02*
X688410Y452832D01*
G01X681650Y449798D02*
X688579Y451890D01*
G01X688410Y452832D02*
X681270Y450676D01*
G01X668470Y442188D02*
X681650Y449798D01*
G01X681270Y450676D02*
X667849Y442928D01*
G01X760700Y475067D02*
X720466Y461534D01*
G01X760700Y476070D02*
X720281Y462475D01*
G01X720466Y461534D02*
X686821Y459423D01*
G01X720281Y462475D02*
X686652Y460365D01*
G01X686821Y459423D02*
X678979Y457056D01*
G01X686652Y460365D02*
X678599Y457934D01*
G01X678979Y457056D02*
X663498Y448115D01*
G01X676291Y464299D02*
X685069Y466949D01*
G01X760700Y471047D02*
X721196Y457762D01*
G01X761715Y472392D02*
X721012Y458703D01*
G01X721196Y457762D02*
X687883Y455673D01*
G01X721012Y458703D02*
X687713Y456615D01*
G01X687883Y455673D02*
X680146Y453336D01*
G01X687713Y456615D02*
X679766Y454214D01*
G01X680146Y453336D02*
X665988Y445154D01*
G01X679766Y454214D02*
X665367Y445893D01*
G01X665988Y445154D02*
X665500Y444572D01*
G01X665367Y445893D02*
X664772Y445183D01*
G01X665988Y445154D02*
X665500Y444572D01*
G01X668835Y419976D02*
X691215Y427634D01*
G01X668384Y420827D02*
X690718Y428469D01*
G01X691215Y427634D02*
X701856Y437418D01*
G01X690718Y428469D02*
X701460Y438346D01*
G01X701856Y437419D02*
X732574Y439371D01*
G01X701460Y438346D02*
X731174Y440234D01*
G01X701856Y437419D02*
X732574Y439371D01*
G01X665500Y428502D02*
X666001Y428866D01*
G01X666654Y428166D02*
X673433Y436243D01*
G01X666001Y428866D02*
X672812Y436983D01*
G01X673433Y436243D02*
X684331Y442534D01*
G01X672812Y436983D02*
X678783Y440429D01*
G01X673433Y436243D02*
X684331Y442534D01*
G01X678783Y440429D02*
X683951Y443412D01*
G01X684331Y442534D02*
X690407Y444367D01*
G01X683951Y443412D02*
X690238Y445309D01*
G01X690407Y444367D02*
X706967Y445406D01*
G01X690238Y445309D02*
X706967Y446358D01*
G01Y445406D02*
X730029Y446852D01*
G01X706967Y446358D02*
X729688Y447783D01*
G01X702042Y408227D02*
X711247Y413761D01*
G01X702409Y407338D02*
X711662Y412901D01*
G01X711247Y413761D02*
X713795Y414711D01*
G01X711662Y412901D02*
X714127Y413819D01*
G01X713795Y414711D02*
X719600Y417800D01*
G01X714241Y413872D02*
X719900Y416883D01*
G01X719600Y417800D02*
X727200Y418900D01*
G01X719900Y416883D02*
X727298Y417954D01*
G01X673223Y403144D02*
X676564Y404985D01*
G01X672655Y403917D02*
X676215Y405878D01*
G01X676564Y404985D02*
X693672Y409193D01*
G01X676215Y405878D02*
X693208Y410058D01*
G01X693672Y409193D02*
X695161Y410561D01*
G01D02*
X695812Y410532D01*
G01X693208Y410058D02*
X694517Y411260D01*
G01X695161Y410561D02*
X695812Y410532D01*
G01X696503Y411795D02*
X697167Y412405D01*
G01D02*
X697818Y412376D01*
G01X698509Y413639D02*
X699173Y414249D01*
G01D02*
X699824Y414220D01*
G01X700515Y415484D02*
X706710Y421179D01*
G01X694517Y411261D02*
X706195Y421997D01*
G01X706710Y421179D02*
X707991Y421692D01*
G01X706195Y421997D02*
X707720Y422607D01*
G01X707991Y421692D02*
X714008Y422889D01*
G01X707720Y422607D02*
X713909Y423838D01*
G01X714008Y422889D02*
X719096Y422949D01*
G01X713909Y423838D02*
X719100Y423900D01*
G01X719096Y422949D02*
X733347Y422657D01*
G01X719100Y423900D02*
X733367Y423607D01*
G01X668384Y420827D02*
X690718Y428469D01*
G01X668835Y419976D02*
X691215Y427634D01*
G01X690718Y428469D02*
X701460Y438346D01*
G01X691215Y427634D02*
X701856Y437418D01*
G01X701460Y438346D02*
X731174Y440234D01*
G01X701856Y437419D02*
X732574Y439371D01*
G01X672655Y403917D02*
X676215Y405878D01*
G01X673223Y403144D02*
X676564Y404985D01*
G01X676215Y405878D02*
X693208Y410058D01*
G01X676564Y404985D02*
X693672Y409193D01*
G01X693208Y410058D02*
X694517Y411260D01*
G01X693672Y409193D02*
X695161Y410561D01*
G01X693208Y410058D02*
X694517Y411260D01*
G01Y411261D02*
X706195Y421997D01*
G01X695161Y410561D02*
X695812Y410532D01*
G01X694517Y411261D02*
X706195Y421997D01*
G01X696503Y411795D02*
X697167Y412405D01*
G01X694517Y411261D02*
X706195Y421997D01*
G01X697167Y412405D02*
X697818Y412376D01*
G01X694517Y411261D02*
X706195Y421997D01*
G01X698509Y413639D02*
X699173Y414249D01*
G01X694517Y411261D02*
X706195Y421997D01*
G01X699173Y414249D02*
X699824Y414220D01*
G01X694517Y411261D02*
X706195Y421997D01*
G01X700515Y415484D02*
X706710Y421179D01*
G01X706195Y421997D02*
X707720Y422607D01*
G01X706710Y421179D02*
X707991Y421692D01*
G01X707720Y422607D02*
X713909Y423838D01*
G01X707991Y421692D02*
X714008Y422889D01*
G01X713909Y423838D02*
X719100Y423900D01*
G01X714008Y422889D02*
X719096Y422949D01*
G01X719100Y423900D02*
X733367Y423607D01*
G01X719096Y422949D02*
X733347Y422657D01*
G01X670645Y416569D02*
X693206Y424289D01*
G01X670194Y417420D02*
X692709Y425124D01*
G01X693206Y424289D02*
X703441Y433701D01*
G01X692709Y425124D02*
X703045Y434629D01*
G01X703441Y433701D02*
X733950Y435614D01*
G01X703045Y434629D02*
X733676Y436549D01*
G01X668618Y426057D02*
X674953Y433603D01*
G01X669271Y425357D02*
X675573Y432864D01*
G01X674953Y433603D02*
X686015Y439991D01*
G01X675573Y432864D02*
X686395Y439113D01*
G01X686015Y439991D02*
X691081Y441522D01*
G01X686395Y439113D02*
X691251Y440580D01*
G01X691081Y441522D02*
X729669Y443965D01*
G01X691251Y440580D02*
X730011Y443034D01*
G01X670632Y411214D02*
X671324Y411199D01*
G01X672062Y412585D02*
X672784Y413276D01*
G01D02*
X674626Y413906D01*
G01X676500Y414549D02*
X695202Y420950D01*
G01X672278Y414107D02*
X694705Y421785D01*
G01X695202Y420950D02*
X705029Y429984D01*
G01X694705Y421785D02*
X704633Y430912D01*
G01X705029Y429984D02*
X734373Y431824D01*
G01X704633Y430912D02*
X734087Y432758D01*
G01X702409Y407338D02*
X711662Y412901D01*
G01X702042Y408227D02*
X711247Y413761D01*
G01X711662Y412901D02*
X714127Y413819D01*
G01X711247Y413761D02*
X713795Y414711D01*
G01X714241Y413872D02*
X719900Y416883D01*
G01X713795Y414711D02*
X719600Y417800D01*
G01X719900Y416883D02*
X727298Y417954D01*
G01X719600Y417800D02*
X727200Y418900D01*
G01X671492Y408077D02*
X682414Y413552D01*
G01X672046Y407292D02*
X682783Y412673D01*
G01X682414Y413552D02*
X696704Y418446D01*
G01X682783Y412673D02*
X697201Y417611D01*
G01X696704Y418446D02*
X706222Y427193D01*
G01X697201Y417611D02*
X706618Y426265D01*
G01X706222Y427193D02*
X726093Y428441D01*
G01X706618Y426265D02*
X726098Y427489D01*
G01X670632Y411214D02*
X671324Y411199D01*
G01X672062Y412585D02*
X672784Y413276D01*
G01X672278Y414107D02*
X694705Y421785D01*
G01X672784Y413276D02*
X674626Y413906D01*
G01X672278Y414107D02*
X694705Y421785D01*
G01X676500Y414549D02*
X695202Y420950D01*
G01X694705Y421785D02*
X704633Y430912D01*
G01X695202Y420950D02*
X705029Y429984D01*
G01X704633Y430912D02*
X734087Y432758D01*
G01X705029Y429984D02*
X734373Y431824D01*
G01X719538Y466245D02*
X760309Y479958D01*
G01X719722Y465304D02*
X760484Y479014D01*
G01X675911Y465177D02*
X684900Y467891D01*
G01X685069Y466949D02*
X718986Y469076D01*
G01X684900Y467891D02*
X718802Y470017D01*
G01X718986Y469076D02*
X759781Y482796D01*
G01X718802Y470017D02*
X759605Y483740D01*
G01X684162Y471661D02*
X674435Y468724D01*
G01X674815Y467846D02*
X684331Y470719D01*
G01X718063Y473788D02*
X684162Y471661D01*
G01X684331Y470719D02*
X718248Y472847D01*
G01X758897Y487522D02*
X718063Y473788D01*
G01X718248Y472847D02*
X759073Y486578D01*
G01X719722Y465304D02*
X760484Y479014D01*
G01X719538Y466245D02*
X760309Y479958D01*
G01X675911Y465177D02*
X684900Y467891D01*
G01D02*
X718802Y470017D01*
G01X685069Y466949D02*
X718986Y469076D01*
G01X718802Y470017D02*
X759605Y483740D01*
G01X718986Y469076D02*
X759781Y482796D01*
G01X718248Y472847D02*
X759073Y486578D01*
G01X758897Y487522D02*
X718063Y473788D01*
G01X684331Y470719D02*
X718248Y472847D01*
G01X718063Y473788D02*
X684162Y471661D01*
G01X674815Y467846D02*
X684331Y470719D01*
G01X684162Y471661D02*
X674435Y468724D01*
G01X673209Y472417D02*
X683138Y475413D01*
G01X673589Y471539D02*
X683307Y474471D01*
G01X683138Y475413D02*
X717320Y477558D01*
G01X683307Y474471D02*
X717504Y476617D01*
G01X717320Y477558D02*
X758199Y491306D01*
G01X717504Y476617D02*
X757800Y490169D01*
G01X717320Y477558D02*
X758199Y491306D01*
G01X673209Y472417D02*
X683138Y475413D01*
G01X673589Y471539D02*
X683307Y474471D01*
G01X683138Y475413D02*
X717320Y477558D01*
G01X683307Y474471D02*
X717504Y476617D01*
G01X717320Y477558D02*
X758199Y491306D01*
G01X717504Y476617D02*
X757800Y490169D01*
G01X717320Y477558D02*
X758199Y491306D01*
G01X672068Y475061D02*
X682621Y478245D01*
G01X671688Y475939D02*
X682452Y479187D01*
G01X682621Y478245D02*
X716768Y480388D01*
G01X682452Y479187D02*
X716584Y481329D01*
G01X716768Y480388D02*
X757666Y494144D01*
G01X716584Y481329D02*
X757490Y495088D01*
G01X670495Y478551D02*
X678260Y481520D01*
G01X670085Y479412D02*
X677991Y482435D01*
G01X678260Y481520D02*
X683386Y482594D01*
G01X677991Y482435D02*
X683178Y483522D01*
G01X683386Y482594D02*
X712070Y489428D01*
G01X683178Y483522D02*
X711870Y490357D01*
G01X712070Y489428D02*
X756036Y497888D01*
G01X711870Y490357D02*
X755925Y498835D01*
G01X719722Y465304D02*
X760484Y479014D01*
G01X719538Y466245D02*
X760309Y479958D01*
G01X673589Y471539D02*
X683307Y474471D01*
G01X673209Y472417D02*
X683138Y475413D01*
G01X683307Y474471D02*
X717504Y476617D01*
G01X683138Y475413D02*
X717320Y477558D01*
G01X717504Y476617D02*
X757800Y490169D01*
G01X717320Y477558D02*
X758199Y491306D01*
G01X671688Y475939D02*
X682452Y479187D01*
G01X672068Y475061D02*
X682621Y478245D01*
G01X682452Y479187D02*
X716584Y481329D01*
G01X682621Y478245D02*
X716768Y480388D01*
G01X716584Y481329D02*
X757490Y495088D01*
G01X716768Y480388D02*
X757666Y494144D01*
G01X670085Y479412D02*
X677991Y482435D01*
G01X670495Y478551D02*
X678260Y481520D01*
G01X677991Y482435D02*
X683178Y483522D01*
G01X678260Y481520D02*
X683386Y482594D01*
G01X683178Y483522D02*
X711870Y490357D01*
G01X683386Y482594D02*
X712070Y489428D01*
G01X711870Y490357D02*
X755925Y498835D01*
G01X712070Y489428D02*
X756036Y497888D01*
G01X675911Y465177D02*
X684900Y467891D01*
G01X685069Y466949D02*
X718986Y469076D01*
G01X684900Y467891D02*
X718802Y470017D01*
G01X718986Y469076D02*
X759781Y482796D01*
G01X718802Y470017D02*
X759605Y483740D01*
G01X684162Y471661D02*
X674435Y468724D01*
G01X674815Y467846D02*
X684331Y470719D01*
G01X718063Y473788D02*
X684162Y471661D01*
G01X684331Y470719D02*
X718248Y472847D01*
G01X758897Y487522D02*
X718063Y473788D01*
G01X718248Y472847D02*
X759073Y486578D01*
G01X735002Y98137D02*
X746960Y98732D01*
G01X734851Y99081D02*
X746561Y99664D01*
G01X746960Y98732D02*
X754171Y105570D01*
G01X746561Y99664D02*
X753784Y106513D01*
G01X754171Y105570D02*
X763978Y105768D01*
G01D02*
X763979D01*
G01D02*
X773788Y105966D01*
G01X753784Y106513D02*
X773726Y106915D01*
G01X773788Y105966D02*
X776277Y106241D01*
G01X773726Y106915D02*
X776162Y107185D01*
G01X776277Y106241D02*
X820172Y112107D01*
G01X776162Y107185D02*
X819944Y113035D01*
G01X734264Y103074D02*
X752441Y110137D01*
G01X734566Y102171D02*
X752613Y109184D01*
G01X752441Y110137D02*
X771104Y109885D01*
G01X752613Y109184D02*
X771156Y108934D01*
G01X771104Y109885D02*
X775945Y110484D01*
G01X771156Y108934D02*
X776073Y109542D01*
G01X775945Y110484D02*
X820816Y117155D01*
G01X776073Y109542D02*
X821052Y116229D01*
G01X734851Y99081D02*
X746561Y99664D01*
G01X735002Y98137D02*
X746960Y98732D01*
G01X746561Y99664D02*
X753784Y106513D01*
G01X746960Y98732D02*
X754171Y105570D01*
G01X753784Y106513D02*
X773726Y106915D01*
G01X754171Y105570D02*
X763978Y105768D01*
G01X753784Y106513D02*
X773726Y106915D01*
G01X763978Y105768D02*
X763979D01*
G01X753784Y106513D02*
X773726Y106915D01*
G01X763979Y105768D02*
X773788Y105966D01*
G01X773726Y106915D02*
X776162Y107185D01*
G01X773788Y105966D02*
X776277Y106241D01*
G01X776162Y107185D02*
X819944Y113035D01*
G01X776277Y106241D02*
X820172Y112107D01*
G01X734566Y102171D02*
X752613Y109184D01*
G01X734264Y103074D02*
X752441Y110137D01*
G01X752613Y109184D02*
X771156Y108934D01*
G01X752441Y110137D02*
X771104Y109885D01*
G01X771156Y108934D02*
X776073Y109542D01*
G01X771104Y109885D02*
X775945Y110484D01*
G01X776073Y109542D02*
X821052Y116229D01*
G01X775945Y110484D02*
X820816Y117155D01*
G01X728888Y105521D02*
X729719Y105805D01*
G01D02*
X752713Y113560D01*
G01X729121Y104600D02*
X730023Y104905D01*
G01X728888Y105521D02*
X729719Y105805D01*
G01D02*
X752713Y113560D01*
G01X730023Y104905D02*
X752856Y112605D01*
G01X752713Y113560D02*
X771945Y113032D01*
G01X752856Y112605D02*
X771997Y112080D01*
G01X771945Y113032D02*
X776855Y113702D01*
G01X771997Y112080D02*
X776995Y112762D01*
G01X776855Y113702D02*
X820228Y120674D01*
G01X776995Y112762D02*
X820473Y119751D01*
G01X739839Y124767D02*
X746401Y127027D01*
G01X739543Y125670D02*
X746273Y127988D01*
G01X746401Y127027D02*
X774098Y125195D01*
G01X746273Y127988D02*
X774035Y126152D01*
G01X774098Y125195D02*
X818697Y134114D01*
G01X774035Y126152D02*
X818421Y135028D01*
G01X772577Y122801D02*
X746290Y123846D01*
G01X746420Y122890D02*
X772638Y121847D01*
G01X776441Y123451D02*
X772577Y122801D01*
G01X772638Y121847D02*
X776609Y122515D01*
G01X818445Y131461D02*
X776441Y123451D01*
G01X776609Y122515D02*
X818704Y130543D01*
G01X727006Y113255D02*
X746940Y120176D01*
G01X727267Y112339D02*
X747093Y119223D01*
G01X746940Y120176D02*
X773148Y119778D01*
G01X747093Y119223D02*
X773216Y118826D01*
G01X773148Y119778D02*
X777505Y120469D01*
G01D02*
X777507D01*
G01X777519Y120472D02*
X777527Y120473D01*
G01X773216Y118826D02*
X777693Y119536D01*
G01X777505Y120469D02*
X777507D01*
G01X777519Y120472D02*
X777527Y120473D01*
G01D02*
X818588Y127730D01*
G01X777693Y119536D02*
X818829Y126807D01*
G01X730402Y109239D02*
X749738Y116066D01*
G01X730111Y110144D02*
X749592Y117022D01*
G01X749738Y116066D02*
X772298Y115264D01*
G01X749592Y117022D02*
X772245Y116217D01*
G01X772298Y115264D02*
X775970Y115805D01*
G01X772245Y116217D02*
X775821Y116744D01*
G01X775970Y115805D02*
X820356Y123382D01*
G01X775821Y116744D02*
X820120Y124306D01*
G01X729121Y104600D02*
X730023Y104905D01*
G01D02*
X752856Y112605D01*
G01X728888Y105521D02*
X729719Y105805D01*
G01X729121Y104600D02*
X730023Y104905D01*
G01D02*
X752856Y112605D01*
G01X729719Y105805D02*
X752713Y113560D01*
G01X752856Y112605D02*
X771997Y112080D01*
G01X752713Y113560D02*
X771945Y113032D01*
G01X771997Y112080D02*
X776995Y112762D01*
G01X771945Y113032D02*
X776855Y113702D01*
G01X776995Y112762D02*
X820473Y119751D01*
G01X776855Y113702D02*
X820228Y120674D01*
G01X734566Y102171D02*
X752613Y109184D01*
G01X734264Y103074D02*
X752441Y110137D01*
G01X752613Y109184D02*
X771156Y108934D01*
G01X752441Y110137D02*
X771104Y109885D01*
G01X771156Y108934D02*
X776073Y109542D01*
G01X771104Y109885D02*
X775945Y110484D01*
G01X776073Y109542D02*
X821052Y116229D01*
G01X775945Y110484D02*
X820816Y117155D01*
G01X739543Y125670D02*
X746273Y127988D01*
G01X739839Y124767D02*
X746401Y127027D01*
G01X746273Y127988D02*
X774035Y126152D01*
G01X746401Y127027D02*
X774098Y125195D01*
G01X774035Y126152D02*
X818421Y135028D01*
G01X774098Y125195D02*
X818697Y134114D01*
G01X776609Y122515D02*
X818704Y130543D01*
G01X818445Y131461D02*
X776441Y123451D01*
G01X772638Y121847D02*
X776609Y122515D01*
G01X776441Y123451D02*
X772577Y122801D01*
G01X746420Y122890D02*
X772638Y121847D01*
G01X772577Y122801D02*
X746290Y123846D01*
G01X727267Y112339D02*
X747093Y119223D01*
G01X727006Y113255D02*
X746940Y120176D01*
G01X747093Y119223D02*
X773216Y118826D01*
G01X746940Y120176D02*
X773148Y119778D01*
G01X773216Y118826D02*
X777693Y119536D01*
G01X773148Y119778D02*
X777505Y120469D01*
G01X773216Y118826D02*
X777693Y119536D01*
G01D02*
X818829Y126807D01*
G01X777505Y120469D02*
X777507D01*
G01X773216Y118826D02*
X777693Y119536D01*
G01D02*
X818829Y126807D01*
G01X777519Y120472D02*
X777527Y120473D01*
G01X777693Y119536D02*
X818829Y126807D01*
G01X777527Y120473D02*
X818588Y127730D01*
G01X730111Y110144D02*
X749592Y117022D01*
G01X730402Y109239D02*
X749738Y116066D01*
G01X749592Y117022D02*
X772245Y116217D01*
G01X749738Y116066D02*
X772298Y115264D01*
G01X772245Y116217D02*
X775821Y116744D01*
G01X772298Y115264D02*
X775970Y115805D01*
G01X775821Y116744D02*
X820120Y124306D01*
G01X775970Y115805D02*
X820356Y123382D01*
G01X728520Y135499D02*
X734325Y136837D01*
G01D02*
X734326D01*
G01D02*
X739710Y138079D01*
G01X728472Y134512D02*
X739772Y137118D01*
G01X739710Y138079D02*
X750375Y137039D01*
G01X739772Y137118D02*
X750303Y136091D01*
G01X750375Y137039D02*
X775155Y135710D01*
G01X750303Y136091D02*
X775224Y134754D01*
G01X775155Y135710D02*
X810995Y142879D01*
G01X775224Y134754D02*
X811313Y141973D01*
G01X742196Y133554D02*
X737203Y132225D01*
G01X736958Y133142D02*
X737140Y133191D01*
G01X742196Y133554D02*
X737203Y132225D01*
G01X737141Y133192D02*
X742100Y134512D01*
G01X774874Y131605D02*
X742196Y133554D01*
G01X742100Y134512D02*
X774808Y132561D01*
G01X812599Y139148D02*
X774874Y131605D01*
G01X774808Y132561D02*
X812300Y140058D01*
G01X774658Y129417D02*
X814392Y137364D01*
G01X814680Y136452D02*
X774723Y128461D01*
G01X744116Y131296D02*
X774658Y129417D01*
G01X774723Y128461D02*
X744233Y130337D01*
G01X748885Y156361D02*
X751479Y154708D01*
G01X749403Y157159D02*
X751927Y155551D01*
G01X751479Y154708D02*
X757993Y152013D01*
G01X751927Y155551D02*
X758228Y152944D01*
G01X757993Y152013D02*
X775296Y150222D01*
G01X758228Y152944D02*
X775251Y151182D01*
G01X775296Y150222D02*
X801559Y155475D01*
G01X775251Y151182D02*
X801188Y156370D01*
G01X732284Y158024D02*
X746051Y155116D01*
G01X732061Y157100D02*
X745683Y154222D01*
G01X746051Y155116D02*
X747195Y154378D01*
G01D02*
X750747Y152085D01*
G01X745683Y154222D02*
X750294Y151246D01*
G01X750747Y152085D02*
X757165Y149243D01*
G01X750294Y151246D02*
X756936Y148304D01*
G01X757165Y149243D02*
X775518Y148123D01*
G01X756936Y148304D02*
X775583Y147167D01*
G01X775518Y148123D02*
X804169Y153854D01*
G01X775583Y147167D02*
X804538Y152958D01*
G01X728750Y147732D02*
X734210Y148728D01*
G01X734211Y148727D02*
X734257Y148736D01*
G01D02*
X734260D01*
G01X728790Y148706D02*
X734258Y149706D01*
G01X734211Y148727D02*
X734257Y148736D01*
G01D02*
X734260D01*
G01D02*
X750905Y145408D01*
G01X734258Y149706D02*
X751026Y146353D01*
G01X750905Y145408D02*
X775191Y144025D01*
G01X751026Y146353D02*
X775124Y144981D01*
G01X775191Y144025D02*
X806613Y150309D01*
G01X775124Y144981D02*
X806252Y151206D01*
G01X729298Y143578D02*
X734087Y144730D01*
G01X729296Y144555D02*
X734041Y145697D01*
G01X734087Y144730D02*
X751176Y142287D01*
G01X734041Y145697D02*
X751271Y143234D01*
G01X751176Y142287D02*
X775053Y140897D01*
G01X751271Y143234D02*
X774986Y141853D01*
G01X775053Y140897D02*
X808505Y147587D01*
G01X774986Y141853D02*
X808159Y148487D01*
G01X810002Y145768D02*
X775023Y138772D01*
G01X810339Y144866D02*
X775092Y137816D01*
G01X775023Y138772D02*
X750585Y140081D01*
G01X775092Y137816D02*
X750492Y139134D01*
G01X750585Y140081D02*
X738765Y141764D01*
G01X750492Y139134D02*
X738799Y140799D01*
G01X738765Y141764D02*
X731055Y140111D01*
G01X738799Y140799D02*
X731059Y139140D01*
G01X728472Y134512D02*
X739772Y137118D01*
G01X728520Y135499D02*
X734325Y136837D01*
G01X728472Y134512D02*
X739772Y137118D01*
G01X734325Y136837D02*
X734326D01*
G01X728472Y134512D02*
X739772Y137118D01*
G01X734326Y136837D02*
X739710Y138079D01*
G01X739772Y137118D02*
X750303Y136091D01*
G01X739710Y138079D02*
X750375Y137039D01*
G01X750303Y136091D02*
X775224Y134754D01*
G01X750375Y137039D02*
X775155Y135710D01*
G01X775224Y134754D02*
X811313Y141973D01*
G01X775155Y135710D02*
X810995Y142879D01*
G01X774808Y132561D02*
X812300Y140058D01*
G01X812599Y139148D02*
X774874Y131605D01*
G01X742100Y134512D02*
X774808Y132561D01*
G01X774874Y131605D02*
X742196Y133554D01*
G01X736958Y133142D02*
X737140Y133191D01*
G01X737141Y133192D02*
X742100Y134512D01*
G01X742196Y133554D02*
X737203Y132225D01*
G01X736958Y133142D02*
X737140Y133191D01*
G01X774723Y128461D02*
X744233Y130337D01*
G01X744116Y131296D02*
X774658Y129417D01*
G01X814680Y136452D02*
X774723Y128461D01*
G01X774658Y129417D02*
X814392Y137364D01*
G01X766099Y158034D02*
X777659Y154763D01*
G01X765700Y157159D02*
X777621Y153786D01*
G01X777659Y154763D02*
X798336Y158900D01*
G01X777621Y153786D02*
X798694Y158002D01*
G01X749403Y157159D02*
X751927Y155551D01*
G01X748885Y156361D02*
X751479Y154708D01*
G01X751927Y155551D02*
X758228Y152944D01*
G01X751479Y154708D02*
X757993Y152013D01*
G01X758228Y152944D02*
X775251Y151182D01*
G01X757993Y152013D02*
X775296Y150222D01*
G01X775251Y151182D02*
X801188Y156370D01*
G01X775296Y150222D02*
X801559Y155475D01*
G01X732061Y157100D02*
X745683Y154222D01*
G01X732284Y158024D02*
X746051Y155116D01*
G01X745683Y154222D02*
X750294Y151246D01*
G01X746051Y155116D02*
X747195Y154378D01*
G01X745683Y154222D02*
X750294Y151246D01*
G01X747195Y154378D02*
X750747Y152085D01*
G01X750294Y151246D02*
X756936Y148304D01*
G01X750747Y152085D02*
X757165Y149243D01*
G01X756936Y148304D02*
X775583Y147167D01*
G01X757165Y149243D02*
X775518Y148123D01*
G01X775583Y147167D02*
X804538Y152958D01*
G01X775518Y148123D02*
X804169Y153854D01*
G01X728790Y148706D02*
X734258Y149706D01*
G01X728750Y147732D02*
X734210Y148728D01*
G01X728790Y148706D02*
X734258Y149706D01*
G01D02*
X751026Y146353D01*
G01X734211Y148727D02*
X734257Y148736D01*
G01X728790Y148706D02*
X734258Y149706D01*
G01D02*
X751026Y146353D01*
G01X734257Y148736D02*
X734260D01*
G01X734258Y149706D02*
X751026Y146353D01*
G01X734260Y148736D02*
X750905Y145408D01*
G01X751026Y146353D02*
X775124Y144981D01*
G01X750905Y145408D02*
X775191Y144025D01*
G01X775124Y144981D02*
X806252Y151206D01*
G01X775191Y144025D02*
X806613Y150309D01*
G01X729296Y144555D02*
X734041Y145697D01*
G01X729298Y143578D02*
X734087Y144730D01*
G01X734041Y145697D02*
X751271Y143234D01*
G01X734087Y144730D02*
X751176Y142287D01*
G01X751271Y143234D02*
X774986Y141853D01*
G01X751176Y142287D02*
X775053Y140897D01*
G01X774986Y141853D02*
X808159Y148487D01*
G01X775053Y140897D02*
X808505Y147587D01*
G01X810339Y144866D02*
X775092Y137816D01*
G01X810002Y145768D02*
X775023Y138772D01*
G01X775092Y137816D02*
X750492Y139134D01*
G01X775023Y138772D02*
X750585Y140081D01*
G01X750492Y139134D02*
X738799Y140799D01*
G01X750585Y140081D02*
X738765Y141764D01*
G01X738799Y140799D02*
X731059Y139140D01*
G01X738765Y141764D02*
X731055Y140111D01*
G01X765700Y157159D02*
X777621Y153786D01*
G01X766099Y158034D02*
X777659Y154763D01*
G01X777621Y153786D02*
X798694Y158002D01*
G01X777659Y154763D02*
X798336Y158900D01*
G01X772577Y122801D02*
X746290Y123846D01*
G01X746420Y122890D02*
X772638Y121847D01*
G01X776441Y123451D02*
X772577Y122801D01*
G01X772638Y121847D02*
X776609Y122515D01*
G01X818445Y131461D02*
X776441Y123451D01*
G01X776609Y122515D02*
X818704Y130543D01*
G01X729121Y104600D02*
X730023Y104905D01*
G01D02*
X752856Y112605D01*
G01X728888Y105521D02*
X729719Y105805D01*
G01X729121Y104600D02*
X730023Y104905D01*
G01D02*
X752856Y112605D01*
G01X729719Y105805D02*
X752713Y113560D01*
G01X752856Y112605D02*
X771997Y112080D01*
G01X752713Y113560D02*
X771945Y113032D01*
G01X771997Y112080D02*
X776995Y112762D01*
G01X771945Y113032D02*
X776855Y113702D01*
G01X776995Y112762D02*
X820473Y119751D01*
G01X776855Y113702D02*
X820228Y120674D01*
G01X742196Y133554D02*
X737203Y132225D01*
G01X736958Y133142D02*
X737140Y133191D01*
G01X742196Y133554D02*
X737203Y132225D01*
G01X737141Y133192D02*
X742100Y134512D01*
G01X774874Y131605D02*
X742196Y133554D01*
G01X742100Y134512D02*
X774808Y132561D01*
G01X812599Y139148D02*
X774874Y131605D01*
G01X774808Y132561D02*
X812300Y140058D01*
G01X727006Y113255D02*
X746940Y120176D01*
G01X727267Y112339D02*
X747093Y119223D01*
G01X746940Y120176D02*
X773148Y119778D01*
G01X747093Y119223D02*
X773216Y118826D01*
G01X773148Y119778D02*
X777505Y120469D01*
G01D02*
X777507D01*
G01X777519Y120472D02*
X777527Y120473D01*
G01X773216Y118826D02*
X777693Y119536D01*
G01X777505Y120469D02*
X777507D01*
G01X777519Y120472D02*
X777527Y120473D01*
G01D02*
X818588Y127730D01*
G01X777693Y119536D02*
X818829Y126807D01*
G01X810002Y145768D02*
X775023Y138772D01*
G01X810339Y144866D02*
X775092Y137816D01*
G01X775023Y138772D02*
X750585Y140081D01*
G01X775092Y137816D02*
X750492Y139134D01*
G01X750585Y140081D02*
X738765Y141764D01*
G01X750492Y139134D02*
X738799Y140799D01*
G01X738765Y141764D02*
X731055Y140111D01*
G01X738799Y140799D02*
X731059Y139140D01*
G01X774723Y128461D02*
X744233Y130337D01*
G01X744116Y131296D02*
X774658Y129417D01*
G01X814680Y136452D02*
X774723Y128461D01*
G01X774658Y129417D02*
X814392Y137364D01*
G01X765700Y157159D02*
X777621Y153786D01*
G01X766099Y158034D02*
X777659Y154763D01*
G01X777621Y153786D02*
X798694Y158002D01*
G01X777659Y154763D02*
X798336Y158900D01*
G01X732061Y157100D02*
X745683Y154222D01*
G01X732284Y158024D02*
X746051Y155116D01*
G01X745683Y154222D02*
X750294Y151246D01*
G01X746051Y155116D02*
X747195Y154378D01*
G01X745683Y154222D02*
X750294Y151246D01*
G01X747195Y154378D02*
X750747Y152085D01*
G01X750294Y151246D02*
X756936Y148304D01*
G01X750747Y152085D02*
X757165Y149243D01*
G01X756936Y148304D02*
X775583Y147167D01*
G01X757165Y149243D02*
X775518Y148123D01*
G01X775583Y147167D02*
X804538Y152958D01*
G01X775518Y148123D02*
X804169Y153854D01*
G01X748885Y156361D02*
X751479Y154708D01*
G01X749403Y157159D02*
X751927Y155551D01*
G01X751479Y154708D02*
X757993Y152013D01*
G01X751927Y155551D02*
X758228Y152944D01*
G01X757993Y152013D02*
X775296Y150222D01*
G01X758228Y152944D02*
X775251Y151182D01*
G01X775296Y150222D02*
X801559Y155475D01*
G01X775251Y151182D02*
X801188Y156370D01*
G01X729233Y163641D02*
X735910Y162052D01*
G01X735830Y161094D02*
X741201Y161452D01*
G01X735910Y162052D02*
X741458Y162422D01*
G01X741201Y161452D02*
X748885Y156361D01*
G01X741458Y162422D02*
X749403Y157159D01*
G01X725781Y168525D02*
X743800Y168730D01*
G01X725692Y167573D02*
X743669Y167778D01*
G01X744052Y168733D02*
X745068Y167739D01*
G01X743669Y167778D02*
X743800Y167650D01*
G01X744052Y168733D02*
X745068Y167739D01*
G01X743800Y167650D02*
X744122Y167334D01*
G01X745068Y167739D02*
X745090Y165855D01*
G01X744122Y167334D02*
X744144Y165450D01*
G01X745090Y165855D02*
X745545Y165410D01*
G01D02*
X747096Y165428D01*
G01X744144Y165450D02*
X745162Y164455D01*
G01X745545Y165410D02*
X747096Y165428D01*
G01X745162Y164455D02*
X747195Y164478D01*
G01X745545Y165410D02*
X747096Y165428D01*
G01X747195Y164478D02*
X747501Y164482D01*
G01X747096Y165428D02*
X747195Y165529D01*
G01D02*
X747540Y165882D01*
G01X747501Y164482D02*
X748495Y165499D01*
G01X747540Y165882D02*
X747518Y167767D01*
G01X748495Y165499D02*
X748473Y167384D01*
G01X747518Y167767D02*
X748512Y168783D01*
G01X748473Y167384D02*
X748916Y167837D01*
G01X748512Y168783D02*
X751909Y168821D01*
G01X748916Y167837D02*
X751587Y167867D01*
G01X751909Y168821D02*
X763916Y159465D01*
G01X751587Y167867D02*
X763362Y158691D01*
G01X763916Y159465D02*
X766099Y158034D01*
G01X763362Y158691D02*
X765700Y157159D01*
G01X729233Y163641D02*
X735910Y162052D01*
G01D02*
X741458Y162422D01*
G01X735830Y161094D02*
X741201Y161452D01*
G01X741458Y162422D02*
X749403Y157159D01*
G01X741201Y161452D02*
X748885Y156361D01*
G01X726585Y172390D02*
X752789Y172665D01*
G01X726496Y171438D02*
X752487Y171711D01*
G01X752789Y172665D02*
X766946Y162498D01*
G01X752487Y171711D02*
X766482Y161660D01*
G01X766946Y162498D02*
X777880Y158028D01*
G01X766482Y161660D02*
X777785Y157040D01*
G01X777880Y158028D02*
X796410Y161729D01*
G01X777785Y157040D02*
X796781Y160833D01*
G01X725692Y167573D02*
X743669Y167778D01*
G01X725781Y168525D02*
X743800Y168730D01*
G01X743669Y167778D02*
X743800Y167650D01*
G01D02*
X744122Y167334D01*
G01X744052Y168733D02*
X745068Y167739D01*
G01X744122Y167334D02*
X744144Y165450D01*
G01X745068Y167739D02*
X745090Y165855D01*
G01X744144Y165450D02*
X745162Y164455D01*
G01X745090Y165855D02*
X745545Y165410D01*
G01X744144Y165450D02*
X745162Y164455D01*
G01D02*
X747195Y164478D01*
G01D02*
X747501Y164482D01*
G01X745545Y165410D02*
X747096Y165428D01*
G01X747501Y164482D02*
X748495Y165499D01*
G01X747096Y165428D02*
X747195Y165529D01*
G01X747501Y164482D02*
X748495Y165499D01*
G01X747195Y165529D02*
X747540Y165882D01*
G01X748495Y165499D02*
X748473Y167384D01*
G01X747540Y165882D02*
X747518Y167767D01*
G01X748473Y167384D02*
X748916Y167837D01*
G01X747518Y167767D02*
X748512Y168783D01*
G01X748916Y167837D02*
X751587Y167867D01*
G01X748512Y168783D02*
X751909Y168821D01*
G01X751587Y167867D02*
X763362Y158691D01*
G01X751909Y168821D02*
X763916Y159465D01*
G01X763362Y158691D02*
X765700Y157159D01*
G01X763916Y159465D02*
X766099Y158034D01*
G01X726940Y176276D02*
X752893Y176369D01*
G01X726848Y175325D02*
X752614Y175417D01*
G01X752893Y176369D02*
X769212Y165839D01*
G01X752614Y175417D02*
X768696Y165041D01*
G01X769212Y165839D02*
X769226Y165833D01*
G01D02*
X779020Y161396D01*
G01X768834Y164966D02*
X778906Y160404D01*
G01X779020Y161396D02*
X794107Y164410D01*
G01X778906Y160404D02*
X794478Y163515D01*
G01X726496Y171438D02*
X752487Y171711D01*
G01X726585Y172390D02*
X752789Y172665D01*
G01X752487Y171711D02*
X766482Y161660D01*
G01X752789Y172665D02*
X766946Y162498D01*
G01X766482Y161660D02*
X777785Y157040D01*
G01X766946Y162498D02*
X777880Y158028D01*
G01X777785Y157040D02*
X796781Y160833D01*
G01X777880Y158028D02*
X796410Y161729D01*
G01X781423Y168039D02*
X789955Y169748D01*
G01X790325Y168853D02*
X781316Y167048D01*
G01X773250Y171623D02*
X781423Y168039D01*
G01X781316Y167048D02*
X772764Y170798D01*
G01X756364Y184486D02*
X773250Y171623D01*
G01X772764Y170798D02*
X756049Y183530D01*
G01X726930Y184258D02*
X727933Y184060D01*
G01D02*
X756364Y184486D01*
G01X756049Y183530D02*
X727847Y183108D01*
G01X726930Y184258D02*
X727933Y184060D01*
G01X727847Y183108D02*
X726746Y183326D01*
G01X726930Y184258D02*
X727933Y184060D01*
G01X726746Y183326D02*
X726743D01*
G01X726923Y184260D02*
X726927Y184259D01*
G01X726930Y184258D02*
X727933Y184060D01*
G01X726743Y183326D02*
X726739Y183327D01*
G01X726923Y184260D02*
X726927Y184259D01*
G01X791605Y166989D02*
X780941Y164856D01*
G01X791976Y166094D02*
X780837Y163866D01*
G01X780941Y164856D02*
X771931Y168737D01*
G01X780837Y163866D02*
X771475Y167899D01*
G01X771931Y168737D02*
X754591Y180331D01*
G01X771475Y167899D02*
X754306Y179378D01*
G01X754591Y180331D02*
X727302Y180122D01*
G01X754306Y179378D02*
X727212Y179171D01*
G01X726848Y175325D02*
X752614Y175417D01*
G01X726940Y176276D02*
X752893Y176369D01*
G01X752614Y175417D02*
X768696Y165041D01*
G01X752893Y176369D02*
X769212Y165839D01*
G01X768834Y164966D02*
X778906Y160404D01*
G01X769212Y165839D02*
X769226Y165833D01*
G01X768834Y164966D02*
X778906Y160404D01*
G01X769226Y165833D02*
X779020Y161396D01*
G01X778906Y160404D02*
X794478Y163515D01*
G01X779020Y161396D02*
X794107Y164410D01*
G01X726746Y183326D02*
X726743D01*
G01D02*
X726739Y183327D01*
G01X726923Y184260D02*
X726927Y184259D01*
G01X756049Y183530D02*
X727847Y183108D01*
G01D02*
X726746Y183326D01*
G01D02*
X726743D01*
G01D02*
X726739Y183327D01*
G01X726930Y184258D02*
X727933Y184060D01*
G01X756049Y183530D02*
X727847Y183108D01*
G01X727933Y184060D02*
X756364Y184486D01*
G01X772764Y170798D02*
X756049Y183530D01*
G01X756364Y184486D02*
X773250Y171623D01*
G01X781316Y167048D02*
X772764Y170798D01*
G01X773250Y171623D02*
X781423Y168039D01*
G01X790325Y168853D02*
X781316Y167048D01*
G01X781423Y168039D02*
X789955Y169748D01*
G01X791976Y166094D02*
X780837Y163866D01*
G01X791605Y166989D02*
X780941Y164856D01*
G01X780837Y163866D02*
X771475Y167899D01*
G01X780941Y164856D02*
X771931Y168737D01*
G01X771475Y167899D02*
X754306Y179378D01*
G01X771931Y168737D02*
X754591Y180331D01*
G01X754306Y179378D02*
X727212Y179171D01*
G01X754591Y180331D02*
X727302Y180122D01*
G01X781423Y168039D02*
X789955Y169748D01*
G01X790325Y168853D02*
X781316Y167048D01*
G01X773250Y171623D02*
X781423Y168039D01*
G01X781316Y167048D02*
X772764Y170798D01*
G01X756364Y184486D02*
X773250Y171623D01*
G01X772764Y170798D02*
X756049Y183530D01*
G01X726930Y184258D02*
X727933Y184060D01*
G01D02*
X756364Y184486D01*
G01X756049Y183530D02*
X727847Y183108D01*
G01X726930Y184258D02*
X727933Y184060D01*
G01X727847Y183108D02*
X726746Y183326D01*
G01X726930Y184258D02*
X727933Y184060D01*
G01X726746Y183326D02*
X726743D01*
G01X726923Y184260D02*
X726927Y184259D01*
G01X726930Y184258D02*
X727933Y184060D01*
G01X726743Y183326D02*
X726739Y183327D01*
G01X726923Y184260D02*
X726927Y184259D01*
G01X726585Y172390D02*
X752789Y172665D01*
G01X726496Y171438D02*
X752487Y171711D01*
G01X752789Y172665D02*
X766946Y162498D01*
G01X752487Y171711D02*
X766482Y161660D01*
G01X766946Y162498D02*
X777880Y158028D01*
G01X766482Y161660D02*
X777785Y157040D01*
G01X777880Y158028D02*
X796410Y161729D01*
G01X777785Y157040D02*
X796781Y160833D01*
G01X725692Y167573D02*
X743669Y167778D01*
G01X725781Y168525D02*
X743800Y168730D01*
G01X743669Y167778D02*
X743800Y167650D01*
G01D02*
X744122Y167334D01*
G01X744052Y168733D02*
X745068Y167739D01*
G01X744122Y167334D02*
X744144Y165450D01*
G01X745068Y167739D02*
X745090Y165855D01*
G01X744144Y165450D02*
X745162Y164455D01*
G01X745090Y165855D02*
X745545Y165410D01*
G01X744144Y165450D02*
X745162Y164455D01*
G01D02*
X747195Y164478D01*
G01D02*
X747501Y164482D01*
G01X745545Y165410D02*
X747096Y165428D01*
G01X747501Y164482D02*
X748495Y165499D01*
G01X747096Y165428D02*
X747195Y165529D01*
G01X747501Y164482D02*
X748495Y165499D01*
G01X747195Y165529D02*
X747540Y165882D01*
G01X748495Y165499D02*
X748473Y167384D01*
G01X747540Y165882D02*
X747518Y167767D01*
G01X748473Y167384D02*
X748916Y167837D01*
G01X747518Y167767D02*
X748512Y168783D01*
G01X748916Y167837D02*
X751587Y167867D01*
G01X748512Y168783D02*
X751909Y168821D01*
G01X751587Y167867D02*
X763362Y158691D01*
G01X751909Y168821D02*
X763916Y159465D01*
G01X763362Y158691D02*
X765700Y157159D01*
G01X763916Y159465D02*
X766099Y158034D01*
G01X729233Y163641D02*
X735910Y162052D01*
G01X735830Y161094D02*
X741201Y161452D01*
G01X735910Y162052D02*
X741458Y162422D01*
G01X741201Y161452D02*
X748885Y156361D01*
G01X741458Y162422D02*
X749403Y157159D01*
G01X791976Y166094D02*
X780837Y163866D01*
G01X791605Y166989D02*
X780941Y164856D01*
G01X780837Y163866D02*
X771475Y167899D01*
G01X780941Y164856D02*
X771931Y168737D01*
G01X771475Y167899D02*
X754306Y179378D01*
G01X771931Y168737D02*
X754591Y180331D01*
G01X754306Y179378D02*
X727212Y179171D01*
G01X754591Y180331D02*
X727302Y180122D01*
G01X730059Y412074D02*
X759854Y417394D01*
G01X730327Y411156D02*
X760343Y416515D01*
G01X759854Y417394D02*
X773663Y432766D01*
G01X760343Y416515D02*
X774187Y431927D01*
G01X773663Y432766D02*
X783878Y435671D01*
G01X774187Y431927D02*
X783948Y434703D01*
G01X783878Y435671D02*
X789209Y434959D01*
G01X783948Y434703D02*
X788864Y434046D01*
G01X729788Y451607D02*
X736699Y456751D01*
G01X730129Y450676D02*
X737145Y455898D01*
G01X736699Y456751D02*
X737004Y456854D01*
G01D02*
X765646Y466485D01*
G01X737145Y455898D02*
X765822Y465541D01*
G01X735843Y458680D02*
X765117Y468524D01*
G01X764941Y469468D02*
X735397Y459533D01*
G01X730226Y454501D02*
X731174Y455206D01*
G01D02*
X735843Y458680D01*
G01X735397Y459533D02*
X729885Y455432D01*
G01X728454Y414718D02*
X734059Y414917D01*
G01X728284Y415663D02*
X733961Y415865D01*
G01X734059Y414917D02*
X755537Y418742D01*
G01X733961Y415865D02*
X753169Y419286D01*
G01X734059Y414917D02*
X755537Y418742D01*
G01X753169Y419286D02*
X755254Y419649D01*
G01X755537Y418742D02*
X759137Y419869D01*
G01X755254Y419649D02*
X758575Y420690D01*
G01X759137Y419869D02*
X772471Y436577D01*
G01X758575Y420690D02*
X771728Y437169D01*
G01X772471Y436577D02*
X773822Y438000D01*
G01X771781Y437231D02*
X773260Y438789D01*
G01X773822Y438000D02*
X775687Y438847D01*
G01X773260Y438789D02*
X775462Y439789D01*
G01X775687Y438847D02*
X778089Y438952D01*
G01X775462Y439789D02*
X778132Y439905D01*
G01X778089Y438952D02*
X790959Y437227D01*
G01X778132Y439905D02*
X791304Y438140D01*
G01X727200Y418900D02*
X734352Y419345D01*
G01D02*
X734464Y419350D01*
G01X727298Y417954D02*
X734464Y418400D01*
G01X734352Y419345D02*
X734464Y419350D01*
G01D02*
X735850D01*
G01X734464Y418400D02*
X735935D01*
G01X735850Y419350D02*
X752516Y422337D01*
G01X735935Y418400D02*
X752769Y421416D01*
G01X752516Y422337D02*
X757222Y424098D01*
G01X752769Y421416D02*
X757800Y423300D01*
G01X757222Y424098D02*
X768859Y438612D01*
G01X757800Y423300D02*
X769576Y437986D01*
G01X768859Y438612D02*
X769858Y439665D01*
G01D02*
X769865Y439672D01*
G01X769576Y437986D02*
X770548Y439010D01*
G01X769858Y439665D02*
X769865Y439672D01*
G01D02*
X771895Y441810D01*
G01X770548Y439010D02*
X770555Y439017D01*
G01X769865Y439672D02*
X771895Y441810D01*
G01X770555Y439017D02*
X772461Y441025D01*
G01X771895Y441810D02*
X773861Y442729D01*
G01X772461Y441025D02*
X774092Y441788D01*
G01X773861Y442729D02*
X778335Y442923D01*
G01X774092Y441788D02*
X778292Y441970D01*
G01X778335Y442923D02*
X794178Y440803D01*
G01X778292Y441970D02*
X793833Y439890D01*
G01X733347Y422657D02*
X737660D01*
G01X733367Y423607D02*
X737617D01*
G01X737660Y422657D02*
X747646Y423552D01*
G01X737617Y423607D02*
X747460Y424490D01*
G01X747646Y423552D02*
X750721Y424513D01*
G01X747460Y424490D02*
X750394Y425407D01*
G01X750721Y424513D02*
X756530Y426958D01*
G01X750394Y425407D02*
X755946Y427743D01*
G01X756530Y426958D02*
X767148Y439803D01*
G01X755946Y427743D02*
X766436Y440434D01*
G01X767148Y439803D02*
X770674Y443517D01*
G01X766436Y440434D02*
X770081Y444274D01*
G01X770674Y443517D02*
X772825Y444743D01*
G01X770081Y444274D02*
X772554Y445683D01*
G01X772825Y444743D02*
X778422Y444986D01*
G01X772554Y445683D02*
X778465Y445939D01*
G01X778422Y444986D02*
X796715Y442545D01*
G01X778465Y445939D02*
X797060Y443458D01*
G01X726098Y427489D02*
X746127Y426441D01*
G01X726093Y428441D02*
X745989Y427400D01*
G01X746127Y426441D02*
X751424Y428306D01*
G01X745989Y427400D02*
X750918Y429136D01*
G01X751424Y428306D02*
X757803Y434331D01*
G01X750918Y429136D02*
X757131Y435005D01*
G01X757803Y434331D02*
X769268Y446410D01*
G01X757131Y435005D02*
X768693Y447185D01*
G01X769268Y446410D02*
X771868Y447714D01*
G01X768693Y447185D02*
X771624Y448655D01*
G01X771868Y447714D02*
X778722Y448008D01*
G01X771624Y448655D02*
X778765Y448961D01*
G01X778722Y448008D02*
X799572Y445217D01*
G01X778765Y448961D02*
X799915Y446130D01*
G01X734373Y431824D02*
X739760Y434992D01*
G01X734087Y432758D02*
X739463Y435920D01*
G01X739760Y434992D02*
X746933Y435627D01*
G01X739463Y435920D02*
X746974Y436585D01*
G01X746933Y435627D02*
X750611Y434981D01*
G01X746974Y436585D02*
X750494Y435967D01*
G01X750611Y434981D02*
X756078Y437360D01*
G01X750494Y435967D02*
X755494Y438142D01*
G01X756078Y437360D02*
X766395Y449636D01*
G01X755494Y438142D02*
X765862Y450480D01*
G01X766395Y449636D02*
X770315Y450652D01*
G01X765862Y450480D02*
X770173Y451597D01*
G01X770315Y450652D02*
X778921Y451032D01*
G01X770173Y451597D02*
X778963Y451985D01*
G01X778921Y451032D02*
X805480Y447474D01*
G01X778963Y451985D02*
X805636Y448412D01*
G01X733676Y436549D02*
X743441Y441989D01*
G01X733950Y435614D02*
X744067Y441249D01*
G01X743441Y441989D02*
X747982Y447665D01*
G01X744067Y441249D02*
X748550Y446853D01*
G01X747982Y447665D02*
X768396Y454531D01*
G01X748550Y446853D02*
X768572Y453587D01*
G01X768396Y454531D02*
X779254Y455005D01*
G01X768572Y453587D02*
X779211Y454052D01*
G01X779254Y455005D02*
X816070Y450066D01*
G01X779211Y454052D02*
X815994Y449117D01*
G01X779254Y455005D02*
X816070Y450066D01*
G01X731174Y440234D02*
X732299Y440306D01*
G01X731174Y440234D02*
X732299Y440306D01*
G01D02*
X741899Y445653D01*
G01X732574Y439371D02*
X742525Y444914D01*
G01X741899Y445653D02*
X743800Y448037D01*
G01D02*
X745373Y450009D01*
G01X742525Y444914D02*
X745942Y449197D01*
G01X745373Y450009D02*
X767671Y457508D01*
G01X745942Y449197D02*
X767847Y456564D01*
G01X767671Y457508D02*
X779481Y458020D01*
G01X767847Y456564D02*
X779438Y457067D01*
G01X779481Y458020D02*
X812507Y453597D01*
G01X779438Y457067D02*
X812475Y452642D01*
G01X730011Y443034D02*
X739860Y450371D01*
G01X729669Y443965D02*
X739413Y451224D01*
G01X739860Y450371D02*
X767246Y459581D01*
G01X739413Y451224D02*
X767072Y460525D01*
G01X767246Y459581D02*
X779677Y460092D01*
G01X767072Y460525D02*
X779721Y461046D01*
G01X779677Y460093D02*
X808644Y456210D01*
G01X779721Y461046D02*
X808676Y457165D01*
G01X730029Y446852D02*
X738442Y453114D01*
G01X729688Y447783D02*
X737004Y453229D01*
G01X730029Y446852D02*
X738442Y453114D01*
G01X737004Y453229D02*
X737996Y453967D01*
G01X738442Y453114D02*
X766525Y462557D01*
G01X737996Y453967D02*
X766349Y463501D01*
G01X766525Y462557D02*
X779690Y463134D01*
G01X766349Y463501D02*
X779733Y464087D01*
G01X779690Y463134D02*
X804708Y459771D01*
G01X779733Y464087D02*
X804741Y460726D01*
G01X730327Y411156D02*
X760343Y416515D01*
G01X730059Y412074D02*
X759854Y417394D01*
G01X760343Y416515D02*
X774187Y431927D01*
G01X759854Y417394D02*
X773663Y432766D01*
G01X774187Y431927D02*
X783948Y434703D01*
G01X773663Y432766D02*
X783878Y435671D01*
G01X783948Y434703D02*
X788864Y434046D01*
G01X783878Y435671D02*
X789209Y434959D01*
G01X730129Y450676D02*
X737145Y455898D01*
G01X729788Y451607D02*
X736699Y456751D01*
G01X737145Y455898D02*
X765822Y465541D01*
G01X736699Y456751D02*
X737004Y456854D01*
G01X737145Y455898D02*
X765822Y465541D01*
G01X737004Y456854D02*
X765646Y466485D01*
G01X730129Y450676D02*
X737145Y455898D01*
G01X729788Y451607D02*
X736699Y456751D01*
G01X737145Y455898D02*
X765822Y465541D01*
G01X736699Y456751D02*
X737004Y456854D01*
G01X737145Y455898D02*
X765822Y465541D01*
G01X737004Y456854D02*
X765646Y466485D01*
G01X735397Y459533D02*
X729885Y455432D01*
G01X730226Y454501D02*
X731174Y455206D01*
G01X735397Y459533D02*
X729885Y455432D01*
G01X731174Y455206D02*
X735843Y458680D01*
G01X764941Y469468D02*
X735397Y459533D01*
G01X735843Y458680D02*
X765117Y468524D01*
G01X728284Y415663D02*
X733961Y415865D01*
G01X728454Y414718D02*
X734059Y414917D01*
G01X733961Y415865D02*
X753169Y419286D01*
G01D02*
X755254Y419649D01*
G01X734059Y414917D02*
X755537Y418742D01*
G01X755254Y419649D02*
X758575Y420690D01*
G01X755537Y418742D02*
X759137Y419869D01*
G01X758575Y420690D02*
X771728Y437169D01*
G01X759137Y419869D02*
X772471Y436577D01*
G01X771781Y437231D02*
X773260Y438789D01*
G01X772471Y436577D02*
X773822Y438000D01*
G01X773260Y438789D02*
X775462Y439789D01*
G01X773822Y438000D02*
X775687Y438847D01*
G01X775462Y439789D02*
X778132Y439905D01*
G01X775687Y438847D02*
X778089Y438952D01*
G01X778132Y439905D02*
X791304Y438140D01*
G01X778089Y438952D02*
X790959Y437227D01*
G01X728284Y415663D02*
X733961Y415865D01*
G01X728454Y414718D02*
X734059Y414917D01*
G01X733961Y415865D02*
X753169Y419286D01*
G01D02*
X755254Y419649D01*
G01X734059Y414917D02*
X755537Y418742D01*
G01X755254Y419649D02*
X758575Y420690D01*
G01X755537Y418742D02*
X759137Y419869D01*
G01X758575Y420690D02*
X771728Y437169D01*
G01X759137Y419869D02*
X772471Y436577D01*
G01X771781Y437231D02*
X773260Y438789D01*
G01X772471Y436577D02*
X773822Y438000D01*
G01X773260Y438789D02*
X775462Y439789D01*
G01X773822Y438000D02*
X775687Y438847D01*
G01X775462Y439789D02*
X778132Y439905D01*
G01X775687Y438847D02*
X778089Y438952D01*
G01X778132Y439905D02*
X791304Y438140D01*
G01X778089Y438952D02*
X790959Y437227D01*
G01X727298Y417954D02*
X734464Y418400D01*
G01X727200Y418900D02*
X734352Y419345D01*
G01X727298Y417954D02*
X734464Y418400D01*
G01D02*
X735935D01*
G01X734352Y419345D02*
X734464Y419350D01*
G01Y418400D02*
X735935D01*
G01X734464Y419350D02*
X735850D01*
G01X735935Y418400D02*
X752769Y421416D01*
G01X735850Y419350D02*
X752516Y422337D01*
G01X752769Y421416D02*
X757800Y423300D01*
G01X752516Y422337D02*
X757222Y424098D01*
G01X757800Y423300D02*
X769576Y437986D01*
G01X757222Y424098D02*
X768859Y438612D01*
G01X769576Y437986D02*
X770548Y439010D01*
G01X768859Y438612D02*
X769858Y439665D01*
G01X769576Y437986D02*
X770548Y439010D01*
G01D02*
X770555Y439017D01*
G01X769858Y439665D02*
X769865Y439672D01*
G01X770548Y439010D02*
X770555Y439017D01*
G01D02*
X772461Y441025D01*
G01X769865Y439672D02*
X771895Y441810D01*
G01X772461Y441025D02*
X774092Y441788D01*
G01X771895Y441810D02*
X773861Y442729D01*
G01X774092Y441788D02*
X778292Y441970D01*
G01X773861Y442729D02*
X778335Y442923D01*
G01X778292Y441970D02*
X793833Y439890D01*
G01X778335Y442923D02*
X794178Y440803D01*
G01X733367Y423607D02*
X737617D01*
G01X733347Y422657D02*
X737660D01*
G01X737617Y423607D02*
X747460Y424490D01*
G01X737660Y422657D02*
X747646Y423552D01*
G01X747460Y424490D02*
X750394Y425407D01*
G01X747646Y423552D02*
X750721Y424513D01*
G01X750394Y425407D02*
X755946Y427743D01*
G01X750721Y424513D02*
X756530Y426958D01*
G01X755946Y427743D02*
X766436Y440434D01*
G01X756530Y426958D02*
X767148Y439803D01*
G01X766436Y440434D02*
X770081Y444274D01*
G01X767148Y439803D02*
X770674Y443517D01*
G01X770081Y444274D02*
X772554Y445683D01*
G01X770674Y443517D02*
X772825Y444743D01*
G01X772554Y445683D02*
X778465Y445939D01*
G01X772825Y444743D02*
X778422Y444986D01*
G01X778465Y445939D02*
X797060Y443458D01*
G01X778422Y444986D02*
X796715Y442545D01*
G01X726093Y428441D02*
X745989Y427400D01*
G01X726098Y427489D02*
X746127Y426441D01*
G01X745989Y427400D02*
X750918Y429136D01*
G01X746127Y426441D02*
X751424Y428306D01*
G01X750918Y429136D02*
X757131Y435005D01*
G01X751424Y428306D02*
X757803Y434331D01*
G01X757131Y435005D02*
X768693Y447185D01*
G01X757803Y434331D02*
X769268Y446410D01*
G01X768693Y447185D02*
X771624Y448655D01*
G01X769268Y446410D02*
X771868Y447714D01*
G01X771624Y448655D02*
X778765Y448961D01*
G01X771868Y447714D02*
X778722Y448008D01*
G01X778765Y448961D02*
X799915Y446130D01*
G01X778722Y448008D02*
X799572Y445217D01*
G01X734087Y432758D02*
X739463Y435920D01*
G01X734373Y431824D02*
X739760Y434992D01*
G01X739463Y435920D02*
X746974Y436585D01*
G01X739760Y434992D02*
X746933Y435627D01*
G01X746974Y436585D02*
X750494Y435967D01*
G01X746933Y435627D02*
X750611Y434981D01*
G01X750494Y435967D02*
X755494Y438142D01*
G01X750611Y434981D02*
X756078Y437360D01*
G01X755494Y438142D02*
X765862Y450480D01*
G01X756078Y437360D02*
X766395Y449636D01*
G01X765862Y450480D02*
X770173Y451597D01*
G01X766395Y449636D02*
X770315Y450652D01*
G01X770173Y451597D02*
X778963Y451985D01*
G01X770315Y450652D02*
X778921Y451032D01*
G01X778963Y451985D02*
X805636Y448412D01*
G01X778921Y451032D02*
X805480Y447474D01*
G01X733950Y435614D02*
X744067Y441249D01*
G01X733676Y436549D02*
X743441Y441989D01*
G01X744067Y441249D02*
X748550Y446853D01*
G01X743441Y441989D02*
X747982Y447665D01*
G01X748550Y446853D02*
X768572Y453587D01*
G01X747982Y447665D02*
X768396Y454531D01*
G01X768572Y453587D02*
X779211Y454052D01*
G01X768396Y454531D02*
X779254Y455005D01*
G01X779211Y454052D02*
X815994Y449117D01*
G01X779254Y455005D02*
X816070Y450066D01*
G01X779211Y454052D02*
X815994Y449117D01*
G01X732574Y439371D02*
X742525Y444914D01*
G01X731174Y440234D02*
X732299Y440306D01*
G01X732574Y439371D02*
X742525Y444914D01*
G01X732299Y440306D02*
X741899Y445653D01*
G01X742525Y444914D02*
X745942Y449197D01*
G01X741899Y445653D02*
X743800Y448037D01*
G01X742525Y444914D02*
X745942Y449197D01*
G01X743800Y448037D02*
X745373Y450009D01*
G01X745942Y449197D02*
X767847Y456564D01*
G01X745373Y450009D02*
X767671Y457508D01*
G01X767847Y456564D02*
X779438Y457067D01*
G01X767671Y457508D02*
X779481Y458020D01*
G01X779438Y457067D02*
X812475Y452642D01*
G01X779481Y458020D02*
X812507Y453597D01*
G01X729669Y443965D02*
X739413Y451224D01*
G01X730011Y443034D02*
X739860Y450371D01*
G01X739413Y451224D02*
X767072Y460525D01*
G01X739860Y450371D02*
X767246Y459581D01*
G01X767072Y460525D02*
X779721Y461046D01*
G01X767246Y459581D02*
X779677Y460092D01*
G01X779721Y461046D02*
X808676Y457165D01*
G01X779677Y460093D02*
X808644Y456210D01*
G01X729688Y447783D02*
X737004Y453229D01*
G01D02*
X737996Y453967D01*
G01X730029Y446852D02*
X738442Y453114D01*
G01X737996Y453967D02*
X766349Y463501D01*
G01X738442Y453114D02*
X766525Y462557D01*
G01X766349Y463501D02*
X779733Y464087D01*
G01X766525Y462557D02*
X779690Y463134D01*
G01X779733Y464087D02*
X804741Y460726D01*
G01X779690Y463134D02*
X804708Y459771D01*
G01X735843Y458680D02*
X765117Y468524D01*
G01X764941Y469468D02*
X735397Y459533D01*
G01X730226Y454501D02*
X731174Y455206D01*
G01D02*
X735843Y458680D01*
G01X735397Y459533D02*
X729885Y455432D01*
G01X732574Y439371D02*
X742525Y444914D01*
G01X731174Y440234D02*
X732299Y440306D01*
G01X732574Y439371D02*
X742525Y444914D01*
G01X732299Y440306D02*
X741899Y445653D01*
G01X742525Y444914D02*
X745942Y449197D01*
G01X741899Y445653D02*
X743800Y448037D01*
G01X742525Y444914D02*
X745942Y449197D01*
G01X743800Y448037D02*
X745373Y450009D01*
G01X745942Y449197D02*
X767847Y456564D01*
G01X745373Y450009D02*
X767671Y457508D01*
G01X767847Y456564D02*
X779438Y457067D01*
G01X767671Y457508D02*
X779481Y458020D01*
G01X779438Y457067D02*
X812475Y452642D01*
G01X779481Y458020D02*
X812507Y453597D01*
G01X730029Y446852D02*
X738442Y453114D01*
G01X729688Y447783D02*
X737004Y453229D01*
G01X730029Y446852D02*
X738442Y453114D01*
G01X737004Y453229D02*
X737996Y453967D01*
G01X738442Y453114D02*
X766525Y462557D01*
G01X737996Y453967D02*
X766349Y463501D01*
G01X766525Y462557D02*
X779690Y463134D01*
G01X766349Y463501D02*
X779733Y464087D01*
G01X779690Y463134D02*
X804708Y459771D01*
G01X779733Y464087D02*
X804741Y460726D01*
G01X727200Y418900D02*
X734352Y419345D01*
G01D02*
X734464Y419350D01*
G01X727298Y417954D02*
X734464Y418400D01*
G01X734352Y419345D02*
X734464Y419350D01*
G01D02*
X735850D01*
G01X734464Y418400D02*
X735935D01*
G01X735850Y419350D02*
X752516Y422337D01*
G01X735935Y418400D02*
X752769Y421416D01*
G01X752516Y422337D02*
X757222Y424098D01*
G01X752769Y421416D02*
X757800Y423300D01*
G01X757222Y424098D02*
X768859Y438612D01*
G01X757800Y423300D02*
X769576Y437986D01*
G01X768859Y438612D02*
X769858Y439665D01*
G01D02*
X769865Y439672D01*
G01X769576Y437986D02*
X770548Y439010D01*
G01X769858Y439665D02*
X769865Y439672D01*
G01D02*
X771895Y441810D01*
G01X770548Y439010D02*
X770555Y439017D01*
G01X769865Y439672D02*
X771895Y441810D01*
G01X770555Y439017D02*
X772461Y441025D01*
G01X771895Y441810D02*
X773861Y442729D01*
G01X772461Y441025D02*
X774092Y441788D01*
G01X773861Y442729D02*
X778335Y442923D01*
G01X774092Y441788D02*
X778292Y441970D01*
G01X778335Y442923D02*
X794178Y440803D01*
G01X778292Y441970D02*
X793833Y439890D01*
G01X733347Y422657D02*
X737660D01*
G01X733367Y423607D02*
X737617D01*
G01X737660Y422657D02*
X747646Y423552D01*
G01X737617Y423607D02*
X747460Y424490D01*
G01X747646Y423552D02*
X750721Y424513D01*
G01X747460Y424490D02*
X750394Y425407D01*
G01X750721Y424513D02*
X756530Y426958D01*
G01X750394Y425407D02*
X755946Y427743D01*
G01X756530Y426958D02*
X767148Y439803D01*
G01X755946Y427743D02*
X766436Y440434D01*
G01X767148Y439803D02*
X770674Y443517D01*
G01X766436Y440434D02*
X770081Y444274D01*
G01X770674Y443517D02*
X772825Y444743D01*
G01X770081Y444274D02*
X772554Y445683D01*
G01X772825Y444743D02*
X778422Y444986D01*
G01X772554Y445683D02*
X778465Y445939D01*
G01X778422Y444986D02*
X796715Y442545D01*
G01X778465Y445939D02*
X797060Y443458D01*
G01X731174Y440234D02*
X732299Y440306D01*
G01X731174Y440234D02*
X732299Y440306D01*
G01D02*
X741899Y445653D01*
G01X732574Y439371D02*
X742525Y444914D01*
G01X741899Y445653D02*
X743800Y448037D01*
G01D02*
X745373Y450009D01*
G01X742525Y444914D02*
X745942Y449197D01*
G01X745373Y450009D02*
X767671Y457508D01*
G01X745942Y449197D02*
X767847Y456564D01*
G01X767671Y457508D02*
X779481Y458020D01*
G01X767847Y456564D02*
X779438Y457067D01*
G01X779481Y458020D02*
X812507Y453597D01*
G01X779438Y457067D02*
X812475Y452642D01*
G01X733367Y423607D02*
X737617D01*
G01X733347Y422657D02*
X737660D01*
G01X737617Y423607D02*
X747460Y424490D01*
G01X737660Y422657D02*
X747646Y423552D01*
G01X747460Y424490D02*
X750394Y425407D01*
G01X747646Y423552D02*
X750721Y424513D01*
G01X750394Y425407D02*
X755946Y427743D01*
G01X750721Y424513D02*
X756530Y426958D01*
G01X755946Y427743D02*
X766436Y440434D01*
G01X756530Y426958D02*
X767148Y439803D01*
G01X766436Y440434D02*
X770081Y444274D01*
G01X767148Y439803D02*
X770674Y443517D01*
G01X770081Y444274D02*
X772554Y445683D01*
G01X770674Y443517D02*
X772825Y444743D01*
G01X772554Y445683D02*
X778465Y445939D01*
G01X772825Y444743D02*
X778422Y444986D01*
G01X778465Y445939D02*
X797060Y443458D01*
G01X778422Y444986D02*
X796715Y442545D01*
G01X733950Y435614D02*
X744067Y441249D01*
G01X733676Y436549D02*
X743441Y441989D01*
G01X744067Y441249D02*
X748550Y446853D01*
G01X743441Y441989D02*
X747982Y447665D01*
G01X748550Y446853D02*
X768572Y453587D01*
G01X747982Y447665D02*
X768396Y454531D01*
G01X768572Y453587D02*
X779211Y454052D01*
G01X768396Y454531D02*
X779254Y455005D01*
G01X779211Y454052D02*
X815994Y449117D01*
G01X779254Y455005D02*
X816070Y450066D01*
G01X779211Y454052D02*
X815994Y449117D01*
G01X729669Y443965D02*
X739413Y451224D01*
G01X730011Y443034D02*
X739860Y450371D01*
G01X739413Y451224D02*
X767072Y460525D01*
G01X739860Y450371D02*
X767246Y459581D01*
G01X767072Y460525D02*
X779721Y461046D01*
G01X767246Y459581D02*
X779677Y460092D01*
G01X779721Y461046D02*
X808676Y457165D01*
G01X779677Y460093D02*
X808644Y456210D01*
G01X734373Y431824D02*
X739760Y434992D01*
G01X734087Y432758D02*
X739463Y435920D01*
G01X739760Y434992D02*
X746933Y435627D01*
G01X739463Y435920D02*
X746974Y436585D01*
G01X746933Y435627D02*
X750611Y434981D01*
G01X746974Y436585D02*
X750494Y435967D01*
G01X750611Y434981D02*
X756078Y437360D01*
G01X750494Y435967D02*
X755494Y438142D01*
G01X756078Y437360D02*
X766395Y449636D01*
G01X755494Y438142D02*
X765862Y450480D01*
G01X766395Y449636D02*
X770315Y450652D01*
G01X765862Y450480D02*
X770173Y451597D01*
G01X770315Y450652D02*
X778921Y451032D01*
G01X770173Y451597D02*
X778963Y451985D01*
G01X778921Y451032D02*
X805480Y447474D01*
G01X778963Y451985D02*
X805636Y448412D01*
G01X727298Y417954D02*
X734464Y418400D01*
G01X727200Y418900D02*
X734352Y419345D01*
G01X727298Y417954D02*
X734464Y418400D01*
G01D02*
X735935D01*
G01X734352Y419345D02*
X734464Y419350D01*
G01Y418400D02*
X735935D01*
G01X734464Y419350D02*
X735850D01*
G01X735935Y418400D02*
X752769Y421416D01*
G01X735850Y419350D02*
X752516Y422337D01*
G01X752769Y421416D02*
X757800Y423300D01*
G01X752516Y422337D02*
X757222Y424098D01*
G01X757800Y423300D02*
X769576Y437986D01*
G01X757222Y424098D02*
X768859Y438612D01*
G01X769576Y437986D02*
X770548Y439010D01*
G01X768859Y438612D02*
X769858Y439665D01*
G01X769576Y437986D02*
X770548Y439010D01*
G01D02*
X770555Y439017D01*
G01X769858Y439665D02*
X769865Y439672D01*
G01X770548Y439010D02*
X770555Y439017D01*
G01D02*
X772461Y441025D01*
G01X769865Y439672D02*
X771895Y441810D01*
G01X772461Y441025D02*
X774092Y441788D01*
G01X771895Y441810D02*
X773861Y442729D01*
G01X774092Y441788D02*
X778292Y441970D01*
G01X773861Y442729D02*
X778335Y442923D01*
G01X778292Y441970D02*
X793833Y439890D01*
G01X778335Y442923D02*
X794178Y440803D01*
G01X726093Y428441D02*
X745989Y427400D01*
G01X726098Y427489D02*
X746127Y426441D01*
G01X745989Y427400D02*
X750918Y429136D01*
G01X746127Y426441D02*
X751424Y428306D01*
G01X750918Y429136D02*
X757131Y435005D01*
G01X751424Y428306D02*
X757803Y434331D01*
G01X757131Y435005D02*
X768693Y447185D01*
G01X757803Y434331D02*
X769268Y446410D01*
G01X768693Y447185D02*
X771624Y448655D01*
G01X769268Y446410D02*
X771868Y447714D01*
G01X771624Y448655D02*
X778765Y448961D01*
G01X771868Y447714D02*
X778722Y448008D01*
G01X778765Y448961D02*
X799915Y446130D01*
G01X778722Y448008D02*
X799572Y445217D01*
G01X734087Y432758D02*
X739463Y435920D01*
G01X734373Y431824D02*
X739760Y434992D01*
G01X739463Y435920D02*
X746974Y436585D01*
G01X739760Y434992D02*
X746933Y435627D01*
G01X746974Y436585D02*
X750494Y435967D01*
G01X746933Y435627D02*
X750611Y434981D01*
G01X750494Y435967D02*
X755494Y438142D01*
G01X750611Y434981D02*
X756078Y437360D01*
G01X755494Y438142D02*
X765862Y450480D01*
G01X756078Y437360D02*
X766395Y449636D01*
G01X765862Y450480D02*
X770173Y451597D01*
G01X766395Y449636D02*
X770315Y450652D01*
G01X770173Y451597D02*
X778963Y451985D01*
G01X770315Y450652D02*
X778921Y451032D01*
G01X778963Y451985D02*
X805636Y448412D01*
G01X778921Y451032D02*
X805480Y447474D01*
G01X765646Y466485D02*
X779898Y467107D01*
G01X765822Y465541D02*
X779856Y466154D01*
G01X779898Y467107D02*
X801087Y464307D01*
G01X779856Y466154D02*
X801055Y463352D01*
G01X780157Y469182D02*
X797073Y466909D01*
G01X797106Y467864D02*
X780837Y470049D01*
G01X765117Y468524D02*
X780157Y469181D01*
G01Y469182D02*
X797073Y466909D01*
G01X780837Y470049D02*
X780200Y470135D01*
G01X765117Y468524D02*
X780157Y469181D01*
G01X780200Y470135D02*
X764941Y469468D01*
G01X793400Y471441D02*
X780095Y473185D01*
G01X793369Y470486D02*
X780053Y472232D01*
G01X780095Y473185D02*
X761715Y472392D01*
G01X780053Y472232D02*
X761891Y471448D01*
G01D02*
X760700Y471047D01*
G01X793615Y474321D02*
X780514Y476073D01*
G01X793647Y475276D02*
X780557Y477026D01*
G01X780514Y476073D02*
X761184Y475230D01*
G01X780557Y477026D02*
X761008Y476174D01*
G01X780514Y476073D02*
X761184Y475230D01*
G01D02*
X760700Y475067D01*
G01X761008Y476174D02*
X760700Y476070D01*
G01X761184Y475230D02*
X760700Y475067D01*
G01X760309Y479958D02*
X760700Y479975D01*
G01D02*
X780846Y480834D01*
G01X760484Y479014D02*
X780803Y479881D01*
G01X780846Y480834D02*
X793793Y479098D01*
G01X780803Y479881D02*
X793760Y478143D01*
G01X759781Y482796D02*
X780870Y483715D01*
G01X759605Y483740D02*
X780913Y484668D01*
G01X780870Y483715D02*
X793877Y481976D01*
G01X780913Y484668D02*
X793910Y482931D01*
G01X781092Y488488D02*
X758897Y487522D01*
G01X759073Y486578D02*
X781049Y487535D01*
G01X794051Y486755D02*
X781092Y488488D01*
G01X781049Y487535D02*
X794018Y485800D01*
G01X765822Y465541D02*
X779856Y466154D01*
G01X765646Y466485D02*
X779898Y467107D01*
G01X779856Y466154D02*
X801055Y463352D01*
G01X779898Y467107D02*
X801087Y464307D01*
G01X765822Y465541D02*
X779856Y466154D01*
G01X765646Y466485D02*
X779898Y467107D01*
G01X779856Y466154D02*
X801055Y463352D01*
G01X779898Y467107D02*
X801087Y464307D01*
G01X780837Y470049D02*
X780200Y470135D01*
G01D02*
X764941Y469468D01*
G01X765117Y468524D02*
X780157Y469181D01*
G01X797106Y467864D02*
X780837Y470049D01*
G01D02*
X780200Y470135D01*
G01X780157Y469182D02*
X797073Y466909D01*
G01X793369Y470486D02*
X780053Y472232D01*
G01X793400Y471441D02*
X780095Y473185D01*
G01X780053Y472232D02*
X761891Y471448D01*
G01X780095Y473185D02*
X761715Y472392D01*
G01X761891Y471448D02*
X760700Y471047D01*
G01X793647Y475276D02*
X780557Y477026D01*
G01X793615Y474321D02*
X780514Y476073D01*
G01X780557Y477026D02*
X761008Y476174D01*
G01D02*
X760700Y476070D01*
G01X780514Y476073D02*
X761184Y475230D01*
G01X761008Y476174D02*
X760700Y476070D01*
G01X761184Y475230D02*
X760700Y475067D01*
G01X760484Y479014D02*
X780803Y479881D01*
G01X760309Y479958D02*
X760700Y479975D01*
G01X760484Y479014D02*
X780803Y479881D01*
G01X760700Y479975D02*
X780846Y480834D01*
G01X780803Y479881D02*
X793760Y478143D01*
G01X780846Y480834D02*
X793793Y479098D01*
G01X759605Y483740D02*
X780913Y484668D01*
G01X759781Y482796D02*
X780870Y483715D01*
G01X780913Y484668D02*
X793910Y482931D01*
G01X780870Y483715D02*
X793877Y481976D01*
G01X781049Y487535D02*
X794018Y485800D01*
G01X794051Y486755D02*
X781092Y488488D01*
G01X759073Y486578D02*
X781049Y487535D01*
G01X781092Y488488D02*
X758897Y487522D01*
G01X757800Y490169D02*
X758375Y490362D01*
G01X758199Y491306D02*
X780872Y492295D01*
G01X758375Y490362D02*
X780830Y491342D01*
G01X780872Y492295D02*
X793988Y490569D01*
G01X780830Y491342D02*
X793957Y489614D01*
G01X757800Y490169D02*
X758375Y490362D01*
G01X758199Y491306D02*
X780872Y492295D01*
G01X758375Y490362D02*
X780830Y491342D01*
G01X780872Y492295D02*
X793988Y490569D01*
G01X780830Y491342D02*
X793957Y489614D01*
G01X757666Y494144D02*
X781440Y495180D01*
G01X757490Y495088D02*
X757800Y495102D01*
G01X757666Y494144D02*
X781440Y495180D01*
G01X757800Y495102D02*
X781482Y496133D01*
G01X781440Y495180D02*
X794343Y493458D01*
G01X781482Y496133D02*
X794375Y494413D01*
G01X756036Y497888D02*
X781567Y498998D01*
G01X755925Y498835D02*
X781610Y499951D01*
G01X781567Y498998D02*
X794378Y497278D01*
G01X781610Y499951D02*
X794411Y498233D01*
G01X760484Y479014D02*
X780803Y479881D01*
G01X760309Y479958D02*
X760700Y479975D01*
G01X760484Y479014D02*
X780803Y479881D01*
G01X760700Y479975D02*
X780846Y480834D01*
G01X780803Y479881D02*
X793760Y478143D01*
G01X780846Y480834D02*
X793793Y479098D01*
G01X757800Y490169D02*
X758375Y490362D01*
G01D02*
X780830Y491342D01*
G01X758199Y491306D02*
X780872Y492295D01*
G01X780830Y491342D02*
X793957Y489614D01*
G01X780872Y492295D02*
X793988Y490569D01*
G01X757490Y495088D02*
X757800Y495102D01*
G01D02*
X781482Y496133D01*
G01X757666Y494144D02*
X781440Y495180D01*
G01X781482Y496133D02*
X794375Y494413D01*
G01X781440Y495180D02*
X794343Y493458D01*
G01X755925Y498835D02*
X781610Y499951D01*
G01X756036Y497888D02*
X781567Y498998D01*
G01X781610Y499951D02*
X794411Y498233D01*
G01X781567Y498998D02*
X794378Y497278D01*
G01X780157Y469182D02*
X797073Y466909D01*
G01X797106Y467864D02*
X780837Y470049D01*
G01X765117Y468524D02*
X780157Y469181D01*
G01Y469182D02*
X797073Y466909D01*
G01X780837Y470049D02*
X780200Y470135D01*
G01X765117Y468524D02*
X780157Y469181D01*
G01X780200Y470135D02*
X764941Y469468D01*
G01X793615Y474321D02*
X780514Y476073D01*
G01X793647Y475276D02*
X780557Y477026D01*
G01X780514Y476073D02*
X761184Y475230D01*
G01X780557Y477026D02*
X761008Y476174D01*
G01X780514Y476073D02*
X761184Y475230D01*
G01D02*
X760700Y475067D01*
G01X761008Y476174D02*
X760700Y476070D01*
G01X761184Y475230D02*
X760700Y475067D01*
G01X759781Y482796D02*
X780870Y483715D01*
G01X759605Y483740D02*
X780913Y484668D01*
G01X780870Y483715D02*
X793877Y481976D01*
G01X780913Y484668D02*
X793910Y482931D01*
G01X781092Y488488D02*
X758897Y487522D01*
G01X759073Y486578D02*
X781049Y487535D01*
G01X794051Y486755D02*
X781092Y488488D01*
G01X781049Y487535D02*
X794018Y485800D01*
G01X793369Y470486D02*
X780053Y472232D01*
G01X793400Y471441D02*
X780095Y473185D01*
G01X780053Y472232D02*
X761891Y471448D01*
G01X780095Y473185D02*
X761715Y472392D01*
G01X761891Y471448D02*
X760700Y471047D01*
G01X820172Y112107D02*
X822881Y113090D01*
G01X819944Y113035D02*
X822543Y113978D01*
G01X822881Y113090D02*
X824000Y113535D01*
G01D02*
X825333Y114066D01*
G01X822543Y113978D02*
X825191Y115032D01*
G01X825333Y114066D02*
X833786Y113335D01*
G01X825191Y115032D02*
X833745Y114293D01*
G01X833786Y113335D02*
X836095Y113733D01*
G01X833745Y114293D02*
X835917Y114667D01*
G01X836095Y113733D02*
X875578Y121935D01*
G01X835917Y114667D02*
X875578Y122906D01*
G01X820816Y117155D02*
X824000Y118322D01*
G01X821052Y116229D02*
X824000Y117309D01*
G01X820816Y117155D02*
X824000Y118322D01*
G01D02*
X825172Y118751D01*
G01X824000Y117309D02*
X825322Y117794D01*
G01X825172Y118751D02*
X834179Y118393D01*
G01X825322Y117794D02*
X834259Y117439D01*
G01X834179Y118393D02*
X875578Y127093D01*
G01X834259Y117439D02*
X875578Y126121D01*
G01X819944Y113035D02*
X822543Y113978D01*
G01X820172Y112107D02*
X822881Y113090D01*
G01X822543Y113978D02*
X825191Y115032D01*
G01X822881Y113090D02*
X824000Y113535D01*
G01X822543Y113978D02*
X825191Y115032D01*
G01X824000Y113535D02*
X825333Y114066D01*
G01X825191Y115032D02*
X833745Y114293D01*
G01X825333Y114066D02*
X833786Y113335D01*
G01X833745Y114293D02*
X835917Y114667D01*
G01X833786Y113335D02*
X836095Y113733D01*
G01X835917Y114667D02*
X875578Y122906D01*
G01X836095Y113733D02*
X875578Y121935D01*
G01X821052Y116229D02*
X824000Y117309D01*
G01D02*
X825322Y117794D01*
G01X820816Y117155D02*
X824000Y118322D01*
G01Y117309D02*
X825322Y117794D01*
G01X824000Y118322D02*
X825172Y118751D01*
G01X825322Y117794D02*
X834259Y117439D01*
G01X825172Y118751D02*
X834179Y118393D01*
G01X834259Y117439D02*
X875578Y126121D01*
G01X834179Y118393D02*
X875578Y127093D01*
G01X820228Y120674D02*
X824644Y122338D01*
G01X820473Y119751D02*
X824000Y121079D01*
G01X820228Y120674D02*
X824644Y122338D01*
G01X824000Y121079D02*
X824822Y121389D01*
G01X824644Y122338D02*
X832619Y122422D01*
G01X824822Y121389D02*
X832690Y121472D01*
G01X832619Y122422D02*
X837814Y123148D01*
G01X832690Y121472D02*
X837979Y122211D01*
G01X837814Y123148D02*
X886197Y133448D01*
G01X837979Y122211D02*
X875578Y130215D01*
G01X837814Y123148D02*
X886197Y133448D01*
G01X818697Y134114D02*
X822201Y135548D01*
G01D02*
X822203D01*
G01D02*
X825709Y136983D01*
G01X818421Y135028D02*
X825445Y137902D01*
G01X825709Y136983D02*
X831668Y138016D01*
G01X825445Y137902D02*
X831493Y138951D01*
G01X831668Y138016D02*
X875578Y146797D01*
G01X831493Y138951D02*
X887232Y150097D01*
G01X820545Y132254D02*
X818445Y131461D01*
G01X818704Y130543D02*
X820891Y131369D01*
G01X825060Y134077D02*
X820545Y132254D01*
G01X820891Y131369D02*
X825278Y133140D01*
G01X832093Y134589D02*
X825060Y134077D01*
G01X825278Y133140D02*
X832225Y133646D01*
G01X885877Y145786D02*
X832093Y134589D01*
G01X832225Y133646D02*
X875578Y142671D01*
G01X885877Y145786D02*
X832093Y134589D01*
G01X885877Y145786D02*
X832093Y134589D01*
G01X818588Y127730D02*
X825688Y130285D01*
G01X818829Y126807D02*
X825878Y129343D01*
G01X825688Y130285D02*
X833366Y130659D01*
G01X825878Y129343D02*
X833488Y129713D01*
G01X833366Y130659D02*
X875578Y139605D01*
G01X833488Y129713D02*
X875578Y138634D01*
G01X820356Y123382D02*
X826400Y125458D01*
G01X820120Y124306D02*
X826230Y126405D01*
G01X826400Y125458D02*
X834296Y125658D01*
G01X826230Y126405D02*
X834213Y126607D01*
G01X834296Y125658D02*
X836665Y126016D01*
G01X834213Y126607D02*
X836494Y126951D01*
G01X836665Y126016D02*
X875578Y134413D01*
G01X836494Y126951D02*
X875578Y135386D01*
G01X820473Y119751D02*
X824000Y121079D01*
G01D02*
X824822Y121389D01*
G01X820228Y120674D02*
X824644Y122338D01*
G01X824822Y121389D02*
X832690Y121472D01*
G01X824644Y122338D02*
X832619Y122422D01*
G01X832690Y121472D02*
X837979Y122211D01*
G01X832619Y122422D02*
X837814Y123148D01*
G01X837979Y122211D02*
X875578Y130215D01*
G01X837814Y123148D02*
X886197Y133448D01*
G01X821052Y116229D02*
X824000Y117309D01*
G01D02*
X825322Y117794D01*
G01X820816Y117155D02*
X824000Y118322D01*
G01Y117309D02*
X825322Y117794D01*
G01X824000Y118322D02*
X825172Y118751D01*
G01X825322Y117794D02*
X834259Y117439D01*
G01X825172Y118751D02*
X834179Y118393D01*
G01X834259Y117439D02*
X875578Y126121D01*
G01X834179Y118393D02*
X875578Y127093D01*
G01X818421Y135028D02*
X825445Y137902D01*
G01X818697Y134114D02*
X822201Y135548D01*
G01X818421Y135028D02*
X825445Y137902D01*
G01X822201Y135548D02*
X822203D01*
G01X818421Y135028D02*
X825445Y137902D01*
G01X822203Y135548D02*
X825709Y136983D01*
G01X825445Y137902D02*
X831493Y138951D01*
G01X825709Y136983D02*
X831668Y138016D01*
G01X831493Y138951D02*
X887232Y150097D01*
G01X831668Y138016D02*
X875578Y146797D01*
G01X831493Y138951D02*
X887232Y150097D01*
G01X832225Y133646D02*
X875578Y142671D01*
G01X885877Y145786D02*
X832093Y134589D01*
G01X825278Y133140D02*
X832225Y133646D01*
G01X832093Y134589D02*
X825060Y134077D01*
G01X820891Y131369D02*
X825278Y133140D01*
G01X825060Y134077D02*
X820545Y132254D01*
G01X818704Y130543D02*
X820891Y131369D01*
G01X820545Y132254D02*
X818445Y131461D01*
G01X818829Y126807D02*
X825878Y129343D01*
G01X818588Y127730D02*
X825688Y130285D01*
G01X825878Y129343D02*
X833488Y129713D01*
G01X825688Y130285D02*
X833366Y130659D01*
G01X833488Y129713D02*
X875578Y138634D01*
G01X833366Y130659D02*
X875578Y139605D01*
G01X820120Y124306D02*
X826230Y126405D01*
G01X820356Y123382D02*
X826400Y125458D01*
G01X826230Y126405D02*
X834213Y126607D01*
G01X826400Y125458D02*
X834296Y125658D01*
G01X834213Y126607D02*
X836494Y126951D01*
G01X834296Y125658D02*
X836665Y126016D01*
G01X836494Y126951D02*
X875578Y135386D01*
G01X836665Y126016D02*
X875578Y134413D01*
G01X810995Y142879D02*
X823261Y149221D01*
G01X811313Y141973D02*
X823565Y148308D01*
G01X810995Y142879D02*
X823261Y149221D01*
G01D02*
X830614Y150445D01*
G01X823565Y148308D02*
X824000Y148380D01*
G01X823261Y149221D02*
X830614Y150445D01*
G01X824000Y148380D02*
X830785Y149510D01*
G01X830614Y150445D02*
X875578Y159438D01*
G01X830785Y149510D02*
X875578Y158469D01*
G01X824451Y144679D02*
X824000Y144469D01*
G01D02*
X812599Y139148D01*
G01X812300Y140058D02*
X824174Y145599D01*
G01X830703Y145608D02*
X824451Y144679D01*
G01X824174Y145599D02*
X830540Y146545D01*
G01X875578Y154584D02*
X830703Y145608D01*
G01X830540Y146545D02*
X875578Y155553D01*
G01X830521Y142651D02*
X830608Y142664D01*
G01D02*
X875578Y151659D01*
G01Y150690D02*
X830773Y141728D01*
G01X825579Y142273D02*
X830521Y142651D01*
G01D02*
X830608Y142664D01*
G01D02*
X875578Y151659D01*
G01X830773Y141728D02*
X830630Y141706D01*
G01X825579Y142273D02*
X830521Y142651D01*
G01D02*
X830608Y142664D01*
G01X830630Y141706D02*
X825813Y141338D01*
G01X814392Y137364D02*
X825579Y142273D01*
G01X825813Y141338D02*
X814680Y136452D01*
G01X801559Y155475D02*
X818595Y166833D01*
G01X804169Y153854D02*
X819530Y164020D01*
G01X804538Y152958D02*
X819899Y163124D01*
G01X806613Y150309D02*
X820932Y159446D01*
G01X806252Y151206D02*
X820571Y160344D01*
G01X808505Y147587D02*
X822967Y156214D01*
G01X808159Y148487D02*
X822641Y157126D01*
G01X875578Y163350D02*
X830515Y154337D01*
G01X890018Y165269D02*
X830684Y153401D01*
G01X830515Y154337D02*
X822891Y153108D01*
G01X830684Y153401D02*
X823212Y152197D01*
G01X822891Y153108D02*
X810002Y145768D01*
G01X823212Y152197D02*
X810339Y144866D01*
G01X811313Y141973D02*
X823565Y148308D01*
G01D02*
X824000Y148380D01*
G01X810995Y142879D02*
X823261Y149221D01*
G01X823565Y148308D02*
X824000Y148380D01*
G01D02*
X830785Y149510D01*
G01X823261Y149221D02*
X830614Y150445D01*
G01X830785Y149510D02*
X875578Y158469D01*
G01X830614Y150445D02*
X875578Y159438D01*
G01X830540Y146545D02*
X875578Y155553D01*
G01Y154584D02*
X830703Y145608D01*
G01X824174Y145599D02*
X830540Y146545D01*
G01X830703Y145608D02*
X824451Y144679D01*
G01X812300Y140058D02*
X824174Y145599D01*
G01X824451Y144679D02*
X824000Y144469D01*
G01X812300Y140058D02*
X824174Y145599D01*
G01X824000Y144469D02*
X812599Y139148D01*
G01X825813Y141338D02*
X814680Y136452D01*
G01X814392Y137364D02*
X825579Y142273D01*
G01X830773Y141728D02*
X830630Y141706D01*
G01D02*
X825813Y141338D01*
G01X825579Y142273D02*
X830521Y142651D01*
G01X875578Y150690D02*
X830773Y141728D01*
G01D02*
X830630Y141706D01*
G01D02*
X825813Y141338D01*
G01X830521Y142651D02*
X830608Y142664D01*
G01X875578Y150690D02*
X830773Y141728D01*
G01D02*
X830630Y141706D01*
G01X830608Y142664D02*
X875578Y151659D01*
G01X801559Y155475D02*
X818595Y166833D01*
G01X804538Y152958D02*
X819899Y163124D01*
G01X804169Y153854D02*
X819530Y164020D01*
G01X806252Y151206D02*
X820571Y160344D01*
G01X806613Y150309D02*
X820932Y159446D01*
G01X808159Y148487D02*
X822641Y157126D01*
G01X808505Y147587D02*
X822967Y156214D01*
G01X890018Y165269D02*
X830684Y153401D01*
G01X890018Y165269D02*
X830684Y153401D01*
G01X875578Y163350D02*
X830515Y154337D01*
G01X830684Y153401D02*
X823212Y152197D01*
G01X830515Y154337D02*
X822891Y153108D01*
G01X823212Y152197D02*
X810339Y144866D01*
G01X822891Y153108D02*
X810002Y145768D01*
G01X820545Y132254D02*
X818445Y131461D01*
G01X818704Y130543D02*
X820891Y131369D01*
G01X825060Y134077D02*
X820545Y132254D01*
G01X820891Y131369D02*
X825278Y133140D01*
G01X832093Y134589D02*
X825060Y134077D01*
G01X825278Y133140D02*
X832225Y133646D01*
G01X885877Y145786D02*
X832093Y134589D01*
G01X832225Y133646D02*
X875578Y142671D01*
G01X885877Y145786D02*
X832093Y134589D01*
G01X885877Y145786D02*
X832093Y134589D01*
G01X820473Y119751D02*
X824000Y121079D01*
G01D02*
X824822Y121389D01*
G01X820228Y120674D02*
X824644Y122338D01*
G01X824822Y121389D02*
X832690Y121472D01*
G01X824644Y122338D02*
X832619Y122422D01*
G01X832690Y121472D02*
X837979Y122211D01*
G01X832619Y122422D02*
X837814Y123148D01*
G01X837979Y122211D02*
X875578Y130215D01*
G01X837814Y123148D02*
X886197Y133448D01*
G01X824451Y144679D02*
X824000Y144469D01*
G01D02*
X812599Y139148D01*
G01X812300Y140058D02*
X824174Y145599D01*
G01X830703Y145608D02*
X824451Y144679D01*
G01X824174Y145599D02*
X830540Y146545D01*
G01X875578Y154584D02*
X830703Y145608D01*
G01X830540Y146545D02*
X875578Y155553D01*
G01X818588Y127730D02*
X825688Y130285D01*
G01X818829Y126807D02*
X825878Y129343D01*
G01X825688Y130285D02*
X833366Y130659D01*
G01X825878Y129343D02*
X833488Y129713D01*
G01X833366Y130659D02*
X875578Y139605D01*
G01X833488Y129713D02*
X875578Y138634D01*
G01Y163350D02*
X830515Y154337D01*
G01X890018Y165269D02*
X830684Y153401D01*
G01X830515Y154337D02*
X822891Y153108D01*
G01X830684Y153401D02*
X823212Y152197D01*
G01X822891Y153108D02*
X810002Y145768D01*
G01X823212Y152197D02*
X810339Y144866D01*
G01X825813Y141338D02*
X814680Y136452D01*
G01X814392Y137364D02*
X825579Y142273D01*
G01X830773Y141728D02*
X830630Y141706D01*
G01D02*
X825813Y141338D01*
G01X825579Y142273D02*
X830521Y142651D01*
G01X875578Y150690D02*
X830773Y141728D01*
G01D02*
X830630Y141706D01*
G01D02*
X825813Y141338D01*
G01X830521Y142651D02*
X830608Y142664D01*
G01X875578Y150690D02*
X830773Y141728D01*
G01D02*
X830630Y141706D01*
G01X830608Y142664D02*
X875578Y151659D01*
G01X804538Y152958D02*
X819899Y163124D01*
G01X804169Y153854D02*
X819530Y164020D01*
G01X801559Y155475D02*
X818595Y166833D01*
G01X801188Y156370D02*
X818224Y167728D01*
G01X818595Y166833D02*
X891872Y181490D01*
G01X818224Y167728D02*
X891872Y182459D01*
G01X819530Y164020D02*
X875578Y175229D01*
G01X819899Y163124D02*
X875578Y174259D01*
G01X820932Y159446D02*
X875578Y170269D01*
G01X820571Y160344D02*
X875578Y171238D01*
G01X822967Y156214D02*
X830515Y157347D01*
G01D02*
X830560Y157355D01*
G01X822641Y157126D02*
X830361Y158285D01*
G01X822967Y156214D02*
X830515Y157347D01*
G01D02*
X830560Y157355D01*
G01D02*
X875578Y166359D01*
G01X830361Y158285D02*
X830384Y158289D01*
G01X830515Y157347D02*
X830560Y157355D01*
G01D02*
X875578Y166359D01*
G01X830384Y158289D02*
X875578Y167328D01*
G01X798336Y158900D02*
X818447Y171527D01*
G01X798694Y158002D02*
X818813Y170635D01*
G01X818447Y171527D02*
X831303Y174377D01*
G01X818813Y170635D02*
X831499Y173447D01*
G01X831303Y174377D02*
X875578Y183236D01*
G01X831499Y173447D02*
X875578Y182267D01*
G01X801188Y156370D02*
X818224Y167728D01*
G01D02*
X891872Y182459D01*
G01X818595Y166833D02*
X891872Y181490D01*
G01X819899Y163124D02*
X875578Y174259D01*
G01X819530Y164020D02*
X875578Y175229D01*
G01X820571Y160344D02*
X875578Y171238D01*
G01X820932Y159446D02*
X875578Y170269D01*
G01X822641Y157126D02*
X830361Y158285D01*
G01D02*
X830384Y158289D01*
G01X822967Y156214D02*
X830515Y157347D01*
G01X822641Y157126D02*
X830361Y158285D01*
G01D02*
X830384Y158289D01*
G01D02*
X875578Y167328D01*
G01X830515Y157347D02*
X830560Y157355D01*
G01X830361Y158285D02*
X830384Y158289D01*
G01D02*
X875578Y167328D01*
G01X830560Y157355D02*
X875578Y166359D01*
G01X796410Y161729D02*
X816893Y175384D01*
G01X796781Y160833D02*
X817014Y174322D01*
G01X796410Y161729D02*
X816893Y175384D01*
G01X817014Y174322D02*
X817264Y174489D01*
G01X816893Y175384D02*
X875578Y187123D01*
G01X817264Y174489D02*
X875578Y186154D01*
G01X798694Y158002D02*
X818813Y170635D01*
G01X798336Y158900D02*
X818447Y171527D01*
G01X818813Y170635D02*
X831499Y173447D01*
G01X818447Y171527D02*
X831303Y174377D01*
G01X831499Y173447D02*
X875578Y182267D01*
G01X831303Y174377D02*
X875578Y183236D01*
G01X794107Y164410D02*
X816173Y179121D01*
G01X794478Y163515D02*
X816544Y178226D01*
G01X816173Y179121D02*
X875578Y191004D01*
G01X816544Y178226D02*
X875578Y190035D01*
G01X796781Y160833D02*
X817014Y174322D01*
G01D02*
X817264Y174489D01*
G01X796410Y161729D02*
X816893Y175384D01*
G01X817264Y174489D02*
X875578Y186154D01*
G01X816893Y175384D02*
X875578Y187123D01*
G01X815570Y186767D02*
X897303Y203125D01*
G01X815570Y186767D02*
X897303Y203125D01*
G01X897392Y202173D02*
X815940Y185872D01*
G01X789955Y169748D02*
X815570Y186767D01*
G01X815940Y185872D02*
X790325Y168853D01*
G01X875578Y194888D02*
X815401Y182853D01*
G01X875578Y193919D02*
X815772Y181958D01*
G01X815401Y182853D02*
X791605Y166989D01*
G01X815772Y181958D02*
X791976Y166094D01*
G01X794478Y163515D02*
X816544Y178226D01*
G01X794107Y164410D02*
X816173Y179121D01*
G01X816544Y178226D02*
X875578Y190035D01*
G01X816173Y179121D02*
X875578Y191004D01*
G01X815940Y185872D02*
X790325Y168853D01*
G01X789955Y169748D02*
X815570Y186767D01*
G01X897392Y202173D02*
X815940Y185872D01*
G01X815570Y186767D02*
X897303Y203125D01*
G01X875578Y193919D02*
X815772Y181958D01*
G01X875578Y194888D02*
X815401Y182853D01*
G01X815772Y181958D02*
X791976Y166094D01*
G01X815401Y182853D02*
X791605Y166989D01*
G01X815570Y186767D02*
X897303Y203125D01*
G01X815570Y186767D02*
X897303Y203125D01*
G01X897392Y202173D02*
X815940Y185872D01*
G01X789955Y169748D02*
X815570Y186767D01*
G01X815940Y185872D02*
X790325Y168853D01*
G01X796410Y161729D02*
X816893Y175384D01*
G01X796781Y160833D02*
X817014Y174322D01*
G01X796410Y161729D02*
X816893Y175384D01*
G01X817014Y174322D02*
X817264Y174489D01*
G01X816893Y175384D02*
X875578Y187123D01*
G01X817264Y174489D02*
X875578Y186154D01*
G01X798694Y158002D02*
X818813Y170635D01*
G01X798336Y158900D02*
X818447Y171527D01*
G01X818813Y170635D02*
X831499Y173447D01*
G01X818447Y171527D02*
X831303Y174377D01*
G01X831499Y173447D02*
X875578Y182267D01*
G01X831303Y174377D02*
X875578Y183236D01*
G01X819899Y163124D02*
X875578Y174259D01*
G01X819530Y164020D02*
X875578Y175229D01*
G01X801188Y156370D02*
X818224Y167728D01*
G01X818595Y166833D02*
X891872Y181490D01*
G01X818224Y167728D02*
X891872Y182459D01*
G01X875578Y193919D02*
X815772Y181958D01*
G01X875578Y194888D02*
X815401Y182853D01*
G01X815772Y181958D02*
X791976Y166094D01*
G01X815401Y182853D02*
X791605Y166989D01*
G01X789209Y434959D02*
X794964Y431114D01*
G01X788864Y434046D02*
X794592Y430219D01*
G01X794964Y431114D02*
X847100Y420641D01*
G01X794592Y430219D02*
X847100Y419671D01*
G01Y420641D02*
X887319Y412561D01*
G01X847100Y419671D02*
X887248Y411606D01*
G01X801087Y464307D02*
X817888Y465402D01*
G01X801055Y463352D02*
X817824Y464445D01*
G01X817888Y465402D02*
X847100Y459536D01*
G01X817824Y464445D02*
X847100Y458566D01*
G01Y459536D02*
X890310Y450859D01*
G01X847100Y458566D02*
X890239Y449904D01*
G01X847100Y462455D02*
X890548Y453735D01*
G01X890619Y454690D02*
X847100Y463425D01*
G01X818075Y468281D02*
X847100Y462455D01*
G01Y463425D02*
X818139Y469238D01*
G01X790959Y437227D02*
X796065Y433817D01*
G01X791304Y438140D02*
X796437Y434712D01*
G01X796065Y433817D02*
X887605Y415440D01*
G01X796437Y434712D02*
X887676Y416395D01*
G01X794178Y440803D02*
X797919Y438304D01*
G01X793833Y439890D02*
X797547Y437409D01*
G01X797919Y438304D02*
X887965Y420224D01*
G01X797547Y437409D02*
X887894Y419269D01*
G01X796715Y442545D02*
X799035Y440995D01*
G01X797060Y443458D02*
X799407Y441890D01*
G01X799035Y440995D02*
X888180Y423098D01*
G01X799407Y441890D02*
X888251Y424053D01*
G01X799572Y445217D02*
X800526Y444583D01*
G01X799915Y446130D02*
X800896Y445478D01*
G01X800526Y444583D02*
X888457Y426927D01*
G01X800896Y445478D02*
X888528Y427882D01*
G01X805480Y447474D02*
X888738Y430756D01*
G01X805636Y448412D02*
X888809Y431711D01*
G01X816070Y450066D02*
X816967Y450042D01*
G01X816070Y450066D02*
X816967Y450042D01*
G01D02*
X889178Y435544D01*
G01X815994Y449117D02*
X816861Y449094D01*
G01X816967Y450042D02*
X889178Y435544D01*
G01X816861Y449094D02*
X889107Y434589D01*
G01X812507Y453597D02*
X817120Y453899D01*
G01X812475Y452642D02*
X817056Y452942D01*
G01X817120Y453899D02*
X889460Y439373D01*
G01X817056Y452942D02*
X889389Y438418D01*
G01X808644Y456210D02*
X817312Y456777D01*
G01D02*
X817315D01*
G01X808676Y457165D02*
X817378Y457734D01*
G01X817312Y456777D02*
X817315D01*
G01D02*
X889672Y442248D01*
G01X817378Y457734D02*
X889743Y443203D01*
G01X804708Y459771D02*
X817561Y460613D01*
G01X804741Y460726D02*
X817625Y461570D01*
G01X817561Y460613D02*
X847100Y454682D01*
G01X817625Y461570D02*
X847100Y455652D01*
G01Y454682D02*
X889961Y446077D01*
G01X847100Y455652D02*
X890032Y447032D01*
G01X788864Y434046D02*
X794592Y430219D01*
G01X789209Y434959D02*
X794964Y431114D01*
G01X794592Y430219D02*
X847100Y419671D01*
G01X794964Y431114D02*
X847100Y420641D01*
G01Y419671D02*
X887248Y411606D01*
G01X847100Y420641D02*
X887319Y412561D01*
G01X801055Y463352D02*
X817824Y464445D01*
G01X801087Y464307D02*
X817888Y465402D01*
G01X817824Y464445D02*
X847100Y458566D01*
G01X817888Y465402D02*
X847100Y459536D01*
G01Y458566D02*
X890239Y449904D01*
G01X847100Y459536D02*
X890310Y450859D01*
G01X801055Y463352D02*
X817824Y464445D01*
G01X801087Y464307D02*
X817888Y465402D01*
G01X817824Y464445D02*
X847100Y458566D01*
G01X817888Y465402D02*
X847100Y459536D01*
G01Y458566D02*
X890239Y449904D01*
G01X847100Y459536D02*
X890310Y450859D01*
G01X847100Y463425D02*
X818139Y469238D01*
G01X818075Y468281D02*
X847100Y462455D01*
G01X890619Y454690D02*
X847100Y463425D01*
G01Y462455D02*
X890548Y453735D01*
G01X791304Y438140D02*
X796437Y434712D01*
G01X790959Y437227D02*
X796065Y433817D01*
G01X796437Y434712D02*
X887676Y416395D01*
G01X796065Y433817D02*
X887605Y415440D01*
G01X791304Y438140D02*
X796437Y434712D01*
G01X790959Y437227D02*
X796065Y433817D01*
G01X796437Y434712D02*
X887676Y416395D01*
G01X796065Y433817D02*
X887605Y415440D01*
G01X793833Y439890D02*
X797547Y437409D01*
G01X794178Y440803D02*
X797919Y438304D01*
G01X797547Y437409D02*
X887894Y419269D01*
G01X797919Y438304D02*
X887965Y420224D01*
G01X797060Y443458D02*
X799407Y441890D01*
G01X796715Y442545D02*
X799035Y440995D01*
G01X799407Y441890D02*
X888251Y424053D01*
G01X799035Y440995D02*
X888180Y423098D01*
G01X799915Y446130D02*
X800896Y445478D01*
G01X799572Y445217D02*
X800526Y444583D01*
G01X800896Y445478D02*
X888528Y427882D01*
G01X800526Y444583D02*
X888457Y426927D01*
G01X805636Y448412D02*
X888809Y431711D01*
G01X805480Y447474D02*
X888738Y430756D01*
G01X815994Y449117D02*
X816861Y449094D01*
G01X815994Y449117D02*
X816861Y449094D01*
G01X816070Y450066D02*
X816967Y450042D01*
G01X815994Y449117D02*
X816861Y449094D01*
G01D02*
X889107Y434589D01*
G01X816967Y450042D02*
X889178Y435544D01*
G01X812475Y452642D02*
X817056Y452942D01*
G01X812507Y453597D02*
X817120Y453899D01*
G01X817056Y452942D02*
X889389Y438418D01*
G01X817120Y453899D02*
X889460Y439373D01*
G01X808676Y457165D02*
X817378Y457734D01*
G01X808644Y456210D02*
X817312Y456777D01*
G01X808676Y457165D02*
X817378Y457734D01*
G01D02*
X889743Y443203D01*
G01X817312Y456777D02*
X817315D01*
G01X817378Y457734D02*
X889743Y443203D01*
G01X817315Y456777D02*
X889672Y442248D01*
G01X804741Y460726D02*
X817625Y461570D01*
G01X804708Y459771D02*
X817561Y460613D01*
G01X817625Y461570D02*
X847100Y455652D01*
G01X817561Y460613D02*
X847100Y454682D01*
G01Y455652D02*
X890032Y447032D01*
G01X847100Y454682D02*
X889961Y446077D01*
G01X847100Y462455D02*
X890548Y453735D01*
G01X890619Y454690D02*
X847100Y463425D01*
G01X818075Y468281D02*
X847100Y462455D01*
G01Y463425D02*
X818139Y469238D01*
G01X812475Y452642D02*
X817056Y452942D01*
G01X812507Y453597D02*
X817120Y453899D01*
G01X817056Y452942D02*
X889389Y438418D01*
G01X817120Y453899D02*
X889460Y439373D01*
G01X804708Y459771D02*
X817561Y460613D01*
G01X804741Y460726D02*
X817625Y461570D01*
G01X817561Y460613D02*
X847100Y454682D01*
G01X817625Y461570D02*
X847100Y455652D01*
G01Y454682D02*
X889961Y446077D01*
G01X847100Y455652D02*
X890032Y447032D01*
G01X794178Y440803D02*
X797919Y438304D01*
G01X793833Y439890D02*
X797547Y437409D01*
G01X797919Y438304D02*
X887965Y420224D01*
G01X797547Y437409D02*
X887894Y419269D01*
G01X796715Y442545D02*
X799035Y440995D01*
G01X797060Y443458D02*
X799407Y441890D01*
G01X799035Y440995D02*
X888180Y423098D01*
G01X799407Y441890D02*
X888251Y424053D01*
G01X812507Y453597D02*
X817120Y453899D01*
G01X812475Y452642D02*
X817056Y452942D01*
G01X817120Y453899D02*
X889460Y439373D01*
G01X817056Y452942D02*
X889389Y438418D01*
G01X797060Y443458D02*
X799407Y441890D01*
G01X796715Y442545D02*
X799035Y440995D01*
G01X799407Y441890D02*
X888251Y424053D01*
G01X799035Y440995D02*
X888180Y423098D01*
G01X815994Y449117D02*
X816861Y449094D01*
G01X815994Y449117D02*
X816861Y449094D01*
G01X816070Y450066D02*
X816967Y450042D01*
G01X815994Y449117D02*
X816861Y449094D01*
G01D02*
X889107Y434589D01*
G01X816967Y450042D02*
X889178Y435544D01*
G01X808676Y457165D02*
X817378Y457734D01*
G01X808644Y456210D02*
X817312Y456777D01*
G01X808676Y457165D02*
X817378Y457734D01*
G01D02*
X889743Y443203D01*
G01X817312Y456777D02*
X817315D01*
G01X817378Y457734D02*
X889743Y443203D01*
G01X817315Y456777D02*
X889672Y442248D01*
G01X805480Y447474D02*
X888738Y430756D01*
G01X805636Y448412D02*
X888809Y431711D01*
G01X793833Y439890D02*
X797547Y437409D01*
G01X794178Y440803D02*
X797919Y438304D01*
G01X797547Y437409D02*
X887894Y419269D01*
G01X797919Y438304D02*
X887965Y420224D01*
G01X799915Y446130D02*
X800896Y445478D01*
G01X799572Y445217D02*
X800526Y444583D01*
G01X800896Y445478D02*
X888528Y427882D01*
G01X800526Y444583D02*
X888457Y426927D01*
G01X805636Y448412D02*
X888809Y431711D01*
G01X805480Y447474D02*
X888738Y430756D01*
G01X797073Y466909D02*
X818075Y468281D01*
G01X818139Y469238D02*
X797106Y467864D01*
G01X890876Y458518D02*
X847100Y467309D01*
G01X890805Y457563D02*
X847100Y466339D01*
G01Y467309D02*
X818395Y473073D01*
G01X847100Y466339D02*
X818331Y472116D01*
G01X818395Y473073D02*
X793400Y471441D01*
G01X818331Y472116D02*
X793369Y470486D01*
G01X891087Y461393D02*
X847100Y470225D01*
G01X891158Y462348D02*
X847100Y471195D01*
G01Y470225D02*
X818587Y475950D01*
G01X847100Y471195D02*
X818651Y476907D01*
G01X818587Y475950D02*
X793615Y474321D01*
G01X818651Y476907D02*
X793647Y475276D01*
G01X793793Y479098D02*
X818924Y480738D01*
G01X793760Y478143D02*
X818860Y479781D01*
G01X818924Y480738D02*
X891458Y466176D01*
G01X818860Y479781D02*
X891387Y465221D01*
G01X793877Y481976D02*
X819518Y483636D01*
G01X793910Y482931D02*
X819582Y484593D01*
G01X819518Y483636D02*
X892055Y469069D01*
G01X819582Y484593D02*
X892126Y470024D01*
G01X819818Y488430D02*
X794051Y486755D01*
G01X794018Y485800D02*
X819754Y487473D01*
G01X856248Y481121D02*
X819818Y488430D01*
G01X819754Y487473D02*
X892370Y472901D01*
G01X818139Y469238D02*
X797106Y467864D01*
G01X797073Y466909D02*
X818075Y468281D01*
G01X890805Y457563D02*
X847100Y466339D01*
G01X890876Y458518D02*
X847100Y467309D01*
G01Y466339D02*
X818331Y472116D01*
G01X847100Y467309D02*
X818395Y473073D01*
G01X818331Y472116D02*
X793369Y470486D01*
G01X818395Y473073D02*
X793400Y471441D01*
G01X891158Y462348D02*
X847100Y471195D01*
G01X891087Y461393D02*
X847100Y470225D01*
G01Y471195D02*
X818651Y476907D01*
G01X847100Y470225D02*
X818587Y475950D01*
G01X818651Y476907D02*
X793647Y475276D01*
G01X818587Y475950D02*
X793615Y474321D01*
G01X793760Y478143D02*
X818860Y479781D01*
G01X793793Y479098D02*
X818924Y480738D01*
G01X818860Y479781D02*
X891387Y465221D01*
G01X818924Y480738D02*
X891458Y466176D01*
G01X793910Y482931D02*
X819582Y484593D01*
G01X793877Y481976D02*
X819518Y483636D01*
G01X819582Y484593D02*
X892126Y470024D01*
G01X819518Y483636D02*
X892055Y469069D01*
G01X819754Y487473D02*
X892370Y472901D01*
G01X819754Y487473D02*
X892370Y472901D01*
G01X856248Y481121D02*
X819818Y488430D01*
G01X794018Y485800D02*
X819754Y487473D01*
G01X819818Y488430D02*
X794051Y486755D01*
G01X793988Y490569D02*
X820110Y492278D01*
G01X793957Y489614D02*
X820046Y491321D01*
G01X820110Y492278D02*
X892761Y477686D01*
G01X820046Y491321D02*
X892690Y476731D01*
G01X793988Y490569D02*
X820110Y492278D01*
G01X793957Y489614D02*
X820046Y491321D01*
G01X820110Y492278D02*
X892761Y477686D01*
G01X820046Y491321D02*
X892690Y476731D01*
G01X794343Y493458D02*
X820312Y495153D01*
G01X794375Y494413D02*
X820376Y496110D01*
G01X820312Y495153D02*
X892986Y480560D01*
G01X820376Y496110D02*
X893057Y481515D01*
G01X794378Y497278D02*
X820571Y498987D01*
G01X794411Y498233D02*
X820635Y499944D01*
G01X820571Y498987D02*
X888185Y485410D01*
G01X820635Y499944D02*
X888308Y486355D01*
G01X793760Y478143D02*
X818860Y479781D01*
G01X793793Y479098D02*
X818924Y480738D01*
G01X818860Y479781D02*
X891387Y465221D01*
G01X818924Y480738D02*
X891458Y466176D01*
G01X793957Y489614D02*
X820046Y491321D01*
G01X793988Y490569D02*
X820110Y492278D01*
G01X820046Y491321D02*
X892690Y476731D01*
G01X820110Y492278D02*
X892761Y477686D01*
G01X794375Y494413D02*
X820376Y496110D01*
G01X794343Y493458D02*
X820312Y495153D01*
G01X820376Y496110D02*
X893057Y481515D01*
G01X820312Y495153D02*
X892986Y480560D01*
G01X794411Y498233D02*
X820635Y499944D01*
G01X794378Y497278D02*
X820571Y498987D01*
G01X820635Y499944D02*
X888308Y486355D01*
G01X820571Y498987D02*
X888185Y485410D01*
G01X797073Y466909D02*
X818075Y468281D01*
G01X818139Y469238D02*
X797106Y467864D01*
G01X891087Y461393D02*
X847100Y470225D01*
G01X891158Y462348D02*
X847100Y471195D01*
G01Y470225D02*
X818587Y475950D01*
G01X847100Y471195D02*
X818651Y476907D01*
G01X818587Y475950D02*
X793615Y474321D01*
G01X818651Y476907D02*
X793647Y475276D01*
G01X793877Y481976D02*
X819518Y483636D01*
G01X793910Y482931D02*
X819582Y484593D01*
G01X819518Y483636D02*
X892055Y469069D01*
G01X819582Y484593D02*
X892126Y470024D01*
G01X819818Y488430D02*
X794051Y486755D01*
G01X794018Y485800D02*
X819754Y487473D01*
G01X856248Y481121D02*
X819818Y488430D01*
G01X819754Y487473D02*
X892370Y472901D01*
G01X890805Y457563D02*
X847100Y466339D01*
G01X890876Y458518D02*
X847100Y467309D01*
G01Y466339D02*
X818331Y472116D01*
G01X847100Y467309D02*
X818395Y473073D01*
G01X818331Y472116D02*
X793369Y470486D01*
G01X818395Y473073D02*
X793400Y471441D01*
G01X910581Y-50881D02*
X906282Y-46582D01*
G01X910187Y-51831D02*
X905888Y-47532D01*
G01X906282Y-46582D02*
X903509D01*
G01X905888Y-47532D02*
X903509D01*
G01X910187Y-51831D02*
X905888Y-47532D01*
G01X910581Y-50881D02*
X906282Y-46582D01*
G01X905888Y-47532D02*
X903509D01*
G01X906282Y-46582D02*
X903509D01*
G01X875578Y121935D02*
X887973Y124510D01*
G01X875578Y122906D02*
X887969Y125480D01*
G01X887973Y124510D02*
X932614Y115584D01*
G01X887969Y125480D02*
X932614Y116553D01*
G01X875578Y127093D02*
X886601Y129409D01*
G01X875578Y126121D02*
X886836Y128487D01*
G01X886601Y129409D02*
X887345Y129608D01*
G01X886836Y128487D02*
X887376Y128632D01*
G01X886601Y129409D02*
X887345Y129608D01*
G01D02*
X932583Y120560D01*
G01X887376Y128632D02*
X932583Y119591D01*
G01X875578Y122906D02*
X887969Y125480D01*
G01X875578Y121935D02*
X887973Y124510D01*
G01X887969Y125480D02*
X932614Y116553D01*
G01X887973Y124510D02*
X932614Y115584D01*
G01X875578Y126121D02*
X886836Y128487D01*
G01X875578Y127093D02*
X886601Y129409D01*
G01X886836Y128487D02*
X887376Y128632D01*
G01D02*
X932583Y119591D01*
G01X886601Y129409D02*
X887345Y129608D01*
G01X887376Y128632D02*
X932583Y119591D01*
G01X887345Y129608D02*
X932583Y120560D01*
G01X875578Y130215D02*
X886419Y132523D01*
G01X886197Y133448D02*
X887050Y133677D01*
G01X886419Y132523D02*
X887082Y132701D01*
G01X887050Y133677D02*
X932732Y124540D01*
G01X887082Y132701D02*
X932732Y123571D01*
G01X875578Y146797D02*
X887232Y149128D01*
G01D02*
X936487Y139277D01*
G01X887232Y150097D02*
X936858Y140172D01*
G01X875578Y142671D02*
X886085Y144858D01*
G01X886971Y146047D02*
X885877Y145786D01*
G01X886085Y144858D02*
X886984Y145073D01*
G01X932623Y136402D02*
X886971Y146047D01*
G01X886984Y145073D02*
X932577Y135440D01*
G01X875578Y139605D02*
X886803Y141984D01*
G01X875578Y138634D02*
X886805Y141013D01*
G01X886803Y141984D02*
X932475Y132484D01*
G01X886805Y141013D02*
X932430Y131522D01*
G01X875578Y134413D02*
X886540Y136779D01*
G01X875578Y135386D02*
X886312Y137702D01*
G01X886540Y136779D02*
X887305Y136992D01*
G01X886312Y137702D02*
X887273Y137970D01*
G01X887305Y136992D02*
X932261Y127557D01*
G01X887273Y137970D02*
X932288Y128523D01*
G01X875578Y130215D02*
X886419Y132523D01*
G01D02*
X887082Y132701D01*
G01X886197Y133448D02*
X887050Y133677D01*
G01X887082Y132701D02*
X932732Y123571D01*
G01X887050Y133677D02*
X932732Y124540D01*
G01X875578Y126121D02*
X886836Y128487D01*
G01X875578Y127093D02*
X886601Y129409D01*
G01X886836Y128487D02*
X887376Y128632D01*
G01D02*
X932583Y119591D01*
G01X886601Y129409D02*
X887345Y129608D01*
G01X887376Y128632D02*
X932583Y119591D01*
G01X887345Y129608D02*
X932583Y120560D01*
G01X875578Y146797D02*
X887232Y149128D01*
G01Y150097D02*
X936858Y140172D01*
G01X887232Y149128D02*
X936487Y139277D01*
G01X886984Y145073D02*
X932577Y135440D01*
G01X932623Y136402D02*
X886971Y146047D01*
G01X886085Y144858D02*
X886984Y145073D01*
G01X886971Y146047D02*
X885877Y145786D01*
G01X875578Y142671D02*
X886085Y144858D01*
G01D02*
X886984Y145073D01*
G01X875578Y138634D02*
X886805Y141013D01*
G01X875578Y139605D02*
X886803Y141984D01*
G01X886805Y141013D02*
X932430Y131522D01*
G01X886803Y141984D02*
X932475Y132484D01*
G01X875578Y135386D02*
X886312Y137702D01*
G01X875578Y134413D02*
X886540Y136779D01*
G01X886312Y137702D02*
X887273Y137970D01*
G01X886540Y136779D02*
X887305Y136992D01*
G01X887273Y137970D02*
X932288Y128523D01*
G01X887305Y136992D02*
X932261Y127557D01*
G01X888865Y157242D02*
X875578Y154584D01*
G01Y155553D02*
X888865Y158211D01*
G01X935720Y147872D02*
X888865Y157242D01*
G01Y158211D02*
X936069Y148772D01*
G01X888441Y154232D02*
X936359Y144647D01*
G01X935988Y143752D02*
X888441Y153263D01*
G01X875578Y151659D02*
X888441Y154232D01*
G01Y153263D02*
X875578Y150690D01*
G01X888865Y158211D02*
X936069Y148772D01*
G01X935720Y147872D02*
X888865Y157242D01*
G01X875578Y155553D02*
X888865Y158211D01*
G01Y157242D02*
X875578Y154584D01*
G01X888441Y153263D02*
X875578Y150690D01*
G01Y151659D02*
X888441Y154232D01*
G01X935988Y143752D02*
X888441Y153263D01*
G01Y154232D02*
X936359Y144647D01*
G01X875578Y142671D02*
X886085Y144858D01*
G01X886971Y146047D02*
X885877Y145786D01*
G01X886085Y144858D02*
X886984Y145073D01*
G01X932623Y136402D02*
X886971Y146047D01*
G01X886984Y145073D02*
X932577Y135440D01*
G01X875578Y130215D02*
X886419Y132523D01*
G01D02*
X887082Y132701D01*
G01X886197Y133448D02*
X887050Y133677D01*
G01X887082Y132701D02*
X932732Y123571D01*
G01X887050Y133677D02*
X932732Y124540D01*
G01X888865Y157242D02*
X875578Y154584D01*
G01Y155553D02*
X888865Y158211D01*
G01X935720Y147872D02*
X888865Y157242D01*
G01Y158211D02*
X936069Y148772D01*
G01X875578Y139605D02*
X886803Y141984D01*
G01X875578Y138634D02*
X886805Y141013D01*
G01X886803Y141984D02*
X932475Y132484D01*
G01X886805Y141013D02*
X932430Y131522D01*
G01X888441Y153263D02*
X875578Y150690D01*
G01Y151659D02*
X888441Y154232D01*
G01X935988Y143752D02*
X888441Y153263D01*
G01Y154232D02*
X936359Y144647D01*
G01X875578Y159438D02*
X889159Y162154D01*
G01X875578Y158469D02*
X889159Y161185D01*
G01Y162154D02*
X939556Y152077D01*
G01X889159Y161185D02*
X939185Y151182D01*
G01X891872Y181490D02*
X948529Y170158D01*
G01X891872Y182459D02*
X948529Y171127D01*
G01X875578Y175229D02*
X891222Y178357D01*
G01X875578Y174259D02*
X891222Y177388D01*
G01Y178357D02*
X945995Y167402D01*
G01X891222Y177388D02*
X945624Y166507D01*
G01X875578Y170269D02*
X890530Y173230D01*
G01X875578Y171238D02*
X890530Y174199D01*
G01Y173230D02*
X943666Y162607D01*
G01X890530Y174199D02*
X944037Y163502D01*
G01X875578Y166359D02*
X890354Y169314D01*
G01X875578Y167328D02*
X890354Y170283D01*
G01Y169314D02*
X941533Y159086D01*
G01X890354Y170283D02*
X941904Y159982D01*
G01X941210Y156000D02*
X890018Y166238D01*
G01X940839Y155105D02*
X890018Y165269D01*
G01Y166238D02*
X875578Y163350D01*
G01Y158469D02*
X889159Y161185D01*
G01X875578Y159438D02*
X889159Y162154D01*
G01Y161185D02*
X939185Y151182D01*
G01X889159Y162154D02*
X939556Y152077D01*
G01X875578Y183236D02*
X892669Y186656D01*
G01X875578Y182267D02*
X892669Y185687D01*
G01Y186656D02*
X948613Y175468D01*
G01X892669Y185687D02*
X948613Y174499D01*
G01X891872Y182459D02*
X948529Y171127D01*
G01X891872Y181490D02*
X948529Y170158D01*
G01X875578Y174259D02*
X891222Y177388D01*
G01X875578Y175229D02*
X891222Y178357D01*
G01Y177388D02*
X945624Y166507D01*
G01X891222Y178357D02*
X945995Y167402D01*
G01X875578Y171238D02*
X890530Y174199D01*
G01X875578Y170269D02*
X890530Y173230D01*
G01Y174199D02*
X944037Y163502D01*
G01X890530Y173230D02*
X943666Y162607D01*
G01X875578Y167328D02*
X890354Y170283D01*
G01X875578Y166359D02*
X890354Y169314D01*
G01Y170283D02*
X941904Y159982D01*
G01X890354Y169314D02*
X941533Y159086D01*
G01X940839Y155105D02*
X890018Y165269D01*
G01X941210Y156000D02*
X890018Y166238D01*
G01D02*
X875578Y163350D01*
G01Y187123D02*
X893134Y190635D01*
G01X875578Y186154D02*
X893134Y189666D01*
G01Y190635D02*
X948158Y179631D01*
G01X893134Y189666D02*
X948158Y178662D01*
G01X875578Y182267D02*
X892669Y185687D01*
G01X875578Y183236D02*
X892669Y186656D01*
G01Y185687D02*
X948613Y174499D01*
G01X892669Y186656D02*
X948613Y175468D01*
G01X875578Y191004D02*
X893480Y194585D01*
G01X875578Y190035D02*
X893480Y193616D01*
G01Y194585D02*
X950168Y183248D01*
G01X893480Y193616D02*
X950168Y182279D01*
G01X875578Y186154D02*
X893134Y189666D01*
G01X875578Y187123D02*
X893134Y190635D01*
G01Y189666D02*
X948158Y178662D01*
G01X893134Y190635D02*
X948158Y179631D01*
G01X897897Y203118D02*
X930994Y195584D01*
G01X930795Y194654D02*
X897785Y202169D01*
G01X897303Y203125D02*
X897897Y203118D01*
G01D02*
X930994Y195584D01*
G01X897785Y202169D02*
X897392Y202173D01*
G01X928744Y191430D02*
X895819Y198936D01*
G01X928744Y191430D02*
X895819Y198936D01*
G01X928533Y190503D02*
X895806Y197964D01*
G01X895819Y198936D02*
X875578Y194888D01*
G01X895806Y197964D02*
X875578Y193919D01*
G01Y190035D02*
X893480Y193616D01*
G01X875578Y191004D02*
X893480Y194585D01*
G01Y193616D02*
X950168Y182279D01*
G01X893480Y194585D02*
X950168Y183248D01*
G01X897785Y202169D02*
X897392Y202173D01*
G01X897785Y202169D02*
X897392Y202173D01*
G01X897303Y203125D02*
X897897Y203118D01*
G01X930795Y194654D02*
X897785Y202169D01*
G01D02*
X897392Y202173D01*
G01X897897Y203118D02*
X930994Y195584D01*
G01X928533Y190503D02*
X895806Y197964D01*
G01X928744Y191430D02*
X895819Y198936D01*
G01X895806Y197964D02*
X875578Y193919D01*
G01X895819Y198936D02*
X875578Y194888D01*
G01X941210Y156000D02*
X890018Y166238D01*
G01X940839Y155105D02*
X890018Y165269D01*
G01Y166238D02*
X875578Y163350D01*
G01X897897Y203118D02*
X930994Y195584D01*
G01X930795Y194654D02*
X897785Y202169D01*
G01X897303Y203125D02*
X897897Y203118D01*
G01D02*
X930994Y195584D01*
G01X897785Y202169D02*
X897392Y202173D01*
G01X875578Y187123D02*
X893134Y190635D01*
G01X875578Y186154D02*
X893134Y189666D01*
G01Y190635D02*
X948158Y179631D01*
G01X893134Y189666D02*
X948158Y178662D01*
G01X875578Y182267D02*
X892669Y185687D01*
G01X875578Y183236D02*
X892669Y186656D01*
G01Y185687D02*
X948613Y174499D01*
G01X892669Y186656D02*
X948613Y175468D01*
G01X875578Y174259D02*
X891222Y177388D01*
G01X875578Y175229D02*
X891222Y178357D01*
G01Y177388D02*
X945624Y166507D01*
G01X891222Y178357D02*
X945995Y167402D01*
G01X891872Y181490D02*
X948529Y170158D01*
G01X891872Y182459D02*
X948529Y171127D01*
G01X928533Y190503D02*
X895806Y197964D01*
G01X928744Y191430D02*
X895819Y198936D01*
G01X895806Y197964D02*
X875578Y193919D01*
G01X895819Y198936D02*
X875578Y194888D01*
G01X887319Y412561D02*
X897906Y413093D01*
G01X887248Y411606D02*
X897560Y412124D01*
G01X897906Y413093D02*
X898961Y412138D01*
G01X897560Y412124D02*
X898031Y411697D01*
G01X898961Y412138D02*
X899046Y410434D01*
G01X898031Y411697D02*
X898117Y409993D01*
G01X899046Y410434D02*
X899517Y410008D01*
G01X898117Y409993D02*
X899171Y409039D01*
G01X899517Y410008D02*
X902269Y410147D01*
G01X899171Y409039D02*
X902710Y409217D01*
G01X902269Y410147D02*
X902694Y410617D01*
G01X902710Y409217D02*
X903664Y410271D01*
G01X902694Y410617D02*
X902609Y412321D01*
G01X903664Y410271D02*
X903578Y411975D01*
G01X902609Y412321D02*
X903565Y413376D01*
G01X903578Y411975D02*
X904005Y412446D01*
G01X903565Y413376D02*
X907979Y413596D01*
G01X904005Y412446D02*
X907907Y412641D01*
G01X907979Y413596D02*
X938746Y407345D01*
G01X907907Y412641D02*
X938467Y406432D01*
G01X890310Y450859D02*
X980444Y455378D01*
G01X890239Y449904D02*
X980412Y454425D01*
G01X890548Y453735D02*
X980858Y458263D01*
G01X980891Y459216D02*
X890619Y454690D01*
G01X981012Y463036D02*
X890876Y458518D01*
G01X980980Y462083D02*
X890805Y457563D01*
G01X981110Y465904D02*
X891087Y461393D01*
G01X981142Y466857D02*
X891158Y462348D01*
G01X887605Y415440D02*
X908886Y416507D01*
G01X887676Y416395D02*
X908956Y417462D01*
G01X908886Y416507D02*
X948933Y408535D01*
G01X908956Y417462D02*
X949199Y409451D01*
G01X887965Y420224D02*
X925019Y422081D01*
G01X887894Y419269D02*
X906378Y420194D01*
G01X887965Y420224D02*
X925019Y422081D01*
G01X906378Y420195D02*
X916164Y420685D01*
G01X887965Y420224D02*
X925019Y422081D01*
G01X888180Y423098D02*
X925476Y424970D01*
G01X888251Y424053D02*
X925630Y425929D01*
G01X888457Y426927D02*
X926094Y428814D01*
G01X888528Y427882D02*
X926248Y429773D01*
G01X888738Y430756D02*
X926711Y432659D01*
G01X888809Y431711D02*
X926865Y433619D01*
G01X889178Y435544D02*
X927482Y437464D01*
G01X889107Y434589D02*
X927328Y436505D01*
G01X889460Y439373D02*
X928108Y441310D01*
G01X889389Y438418D02*
X927954Y440351D01*
G01X889672Y442248D02*
X928570Y444198D01*
G01X889743Y443203D02*
X928724Y445157D01*
G01X889961Y446077D02*
X979940Y450587D01*
G01X890032Y447032D02*
X979972Y451540D01*
G01X887248Y411606D02*
X897560Y412124D01*
G01X887319Y412561D02*
X897906Y413093D01*
G01X897560Y412124D02*
X898031Y411697D01*
G01X897906Y413093D02*
X898961Y412138D01*
G01X898031Y411697D02*
X898117Y409993D01*
G01X898961Y412138D02*
X899046Y410434D01*
G01X898117Y409993D02*
X899171Y409039D01*
G01X899046Y410434D02*
X899517Y410008D01*
G01X899171Y409039D02*
X902710Y409217D01*
G01X899517Y410008D02*
X902269Y410147D01*
G01X902710Y409217D02*
X903664Y410271D01*
G01X902269Y410147D02*
X902694Y410617D01*
G01X903664Y410271D02*
X903578Y411975D01*
G01X902694Y410617D02*
X902609Y412321D01*
G01X903578Y411975D02*
X904005Y412446D01*
G01X902609Y412321D02*
X903565Y413376D01*
G01X904005Y412446D02*
X907907Y412641D01*
G01X903565Y413376D02*
X907979Y413596D01*
G01X907907Y412641D02*
X938467Y406432D01*
G01X907979Y413596D02*
X938746Y407345D01*
G01X890239Y449904D02*
X980412Y454425D01*
G01X890310Y450859D02*
X980444Y455378D01*
G01X890239Y449904D02*
X980412Y454425D01*
G01X890310Y450859D02*
X980444Y455378D01*
G01X980891Y459216D02*
X890619Y454690D01*
G01X890548Y453735D02*
X980858Y458263D01*
G01X980980Y462083D02*
X890805Y457563D01*
G01X981012Y463036D02*
X890876Y458518D01*
G01X981142Y466857D02*
X891158Y462348D01*
G01X981110Y465904D02*
X891087Y461393D01*
G01X887676Y416395D02*
X908956Y417462D01*
G01X887605Y415440D02*
X908886Y416507D01*
G01X908956Y417462D02*
X949199Y409451D01*
G01X908886Y416507D02*
X948933Y408535D01*
G01X887676Y416395D02*
X908956Y417462D01*
G01X887605Y415440D02*
X908886Y416507D01*
G01X908956Y417462D02*
X949199Y409451D01*
G01X908886Y416507D02*
X948933Y408535D01*
G01X887894Y419269D02*
X906378Y420194D01*
G01Y420195D02*
X916164Y420685D01*
G01X887965Y420224D02*
X925019Y422081D01*
G01X888251Y424053D02*
X925630Y425929D01*
G01X888180Y423098D02*
X925476Y424970D01*
G01X888528Y427882D02*
X926248Y429773D01*
G01X888457Y426927D02*
X926094Y428814D01*
G01X888809Y431711D02*
X926865Y433619D01*
G01X888738Y430756D02*
X926711Y432659D01*
G01X889107Y434589D02*
X927328Y436505D01*
G01X889178Y435544D02*
X927482Y437464D01*
G01X889389Y438418D02*
X927954Y440351D01*
G01X889460Y439373D02*
X928108Y441310D01*
G01X889743Y443203D02*
X928724Y445157D01*
G01X889672Y442248D02*
X928570Y444198D01*
G01X890032Y447032D02*
X979972Y451540D01*
G01X889961Y446077D02*
X979940Y450587D01*
G01X890548Y453735D02*
X980858Y458263D01*
G01X980891Y459216D02*
X890619Y454690D01*
G01X981110Y465904D02*
X891087Y461393D01*
G01X981142Y466857D02*
X891158Y462348D01*
G01X980980Y462083D02*
X890805Y457563D01*
G01X981012Y463036D02*
X890876Y458518D01*
G01X889389Y438418D02*
X927954Y440351D01*
G01X889460Y439373D02*
X928108Y441310D01*
G01X889961Y446077D02*
X979940Y450587D01*
G01X890032Y447032D02*
X979972Y451540D01*
G01X887965Y420224D02*
X925019Y422081D01*
G01X887894Y419269D02*
X906378Y420194D01*
G01X887965Y420224D02*
X925019Y422081D01*
G01X906378Y420195D02*
X916164Y420685D01*
G01X887965Y420224D02*
X925019Y422081D01*
G01X888180Y423098D02*
X925476Y424970D01*
G01X888251Y424053D02*
X925630Y425929D01*
G01X889460Y439373D02*
X928108Y441310D01*
G01X889389Y438418D02*
X927954Y440351D01*
G01X888251Y424053D02*
X925630Y425929D01*
G01X888180Y423098D02*
X925476Y424970D01*
G01X889107Y434589D02*
X927328Y436505D01*
G01X889178Y435544D02*
X927482Y437464D01*
G01X889743Y443203D02*
X928724Y445157D01*
G01X889672Y442248D02*
X928570Y444198D01*
G01X888738Y430756D02*
X926711Y432659D01*
G01X888809Y431711D02*
X926865Y433619D01*
G01X887894Y419269D02*
X906378Y420194D01*
G01Y420195D02*
X916164Y420685D01*
G01X887965Y420224D02*
X925019Y422081D01*
G01X888528Y427882D02*
X926248Y429773D01*
G01X888457Y426927D02*
X926094Y428814D01*
G01X888809Y431711D02*
X926865Y433619D01*
G01X888738Y430756D02*
X926711Y432659D01*
G01X891458Y466176D02*
X981274Y470679D01*
G01X891387Y465221D02*
X981242Y469726D01*
G01X892055Y469069D02*
X981373Y473547D01*
G01X892126Y470024D02*
X981405Y474500D01*
G01X892441Y473856D02*
X856248Y481119D01*
G01X981878Y478340D02*
X892441Y473856D01*
G01X892370Y472901D02*
X981846Y477387D01*
G01X891387Y465221D02*
X981242Y469726D01*
G01X891458Y466176D02*
X981274Y470679D01*
G01X892126Y470024D02*
X981405Y474500D01*
G01X892055Y469069D02*
X981373Y473547D01*
G01X892370Y472901D02*
X981846Y477387D01*
G01X981878Y478340D02*
X892441Y473856D01*
G01D02*
X856248Y481119D01*
G01X892761Y477686D02*
X982008Y482161D01*
G01X892690Y476731D02*
X981976Y481208D01*
G01X892761Y477686D02*
X982008Y482161D01*
G01X892690Y476731D02*
X981976Y481208D01*
G01X892986Y480560D02*
X982450Y485045D01*
G01X893057Y481515D02*
X982483Y485998D01*
G01X888185Y485410D02*
X899639Y484706D01*
G01X888308Y486355D02*
X899644Y485658D01*
G01X899639Y484706D02*
X982536Y488865D01*
G01X899644Y485658D02*
X982568Y489818D01*
G01X891387Y465221D02*
X981242Y469726D01*
G01X891458Y466176D02*
X981274Y470679D01*
G01X892690Y476731D02*
X981976Y481208D01*
G01X892761Y477686D02*
X982008Y482161D01*
G01X893057Y481515D02*
X982483Y485998D01*
G01X892986Y480560D02*
X982450Y485045D01*
G01X888308Y486355D02*
X899644Y485658D01*
G01X888185Y485410D02*
X899639Y484706D01*
G01X899644Y485658D02*
X982568Y489818D01*
G01X899639Y484706D02*
X982536Y488865D01*
G01X892055Y469069D02*
X981373Y473547D01*
G01X892126Y470024D02*
X981405Y474500D01*
G01X892441Y473856D02*
X856248Y481119D01*
G01X981878Y478340D02*
X892441Y473856D01*
G01X892370Y472901D02*
X981846Y477387D01*
G01X1102000Y-41481D02*
X914200D01*
G01X1102000Y-42431D02*
X914200D01*
G01Y-41481D02*
G03Y-47131I0J-2825D01*
G01Y-42431D02*
G03Y-46181I0J-1875D01*
G01Y-47131D02*
X1103499D01*
G01X914200Y-46181D02*
X1103500D01*
G01X1103499Y-50881D02*
X910581D01*
G01X1103500Y-51831D02*
X910187D01*
G01X1102000Y-42431D02*
X914200D01*
G01X1102000Y-41481D02*
X914200D01*
G01Y-42431D02*
G03Y-46181I0J-1875D01*
G01Y-41481D02*
G03Y-47131I0J-2825D01*
G01Y-46181D02*
X1103500D01*
G01X914200Y-47131D02*
X1103499D01*
G01X1103500Y-51831D02*
X910187D01*
G01X1103499Y-50881D02*
X910581D01*
G01X932614Y115584D02*
X940705Y117203D01*
G01X932614Y116553D02*
X940705Y118172D01*
G01Y117203D02*
X959225Y113499D01*
G01X940705Y118172D02*
X964071Y113499D01*
G01X959225D02*
X982624Y108819D01*
G01X964071Y113499D02*
X982802Y109753D01*
G01X932583Y120560D02*
X940558Y122155D01*
G01X932583Y119591D02*
X940558Y121186D01*
G01Y122155D02*
X987330Y112801D01*
G01X940558Y121186D02*
X978991Y113499D01*
G01X940558Y122155D02*
X987330Y112801D01*
G01X932614Y116553D02*
X940705Y118172D01*
G01X932614Y115584D02*
X940705Y117203D01*
G01Y118172D02*
X964071Y113499D01*
G01X940705Y117203D02*
X959225Y113499D01*
G01X964071D02*
X982802Y109753D01*
G01X959225Y113499D02*
X982624Y108819D01*
G01X932583Y119591D02*
X940558Y121186D01*
G01X932583Y120560D02*
X940558Y122155D01*
G01Y121186D02*
X978991Y113499D01*
G01X940558Y122155D02*
X987330Y112801D01*
G01X932732Y124540D02*
X940167Y126028D01*
G01X932732Y123571D02*
X940167Y125059D01*
G01Y126028D02*
X987167Y116628D01*
G01X940167Y125059D02*
X987077Y115676D01*
G01X936487Y139277D02*
X936902Y139000D01*
G01D02*
X938641Y137840D01*
G01X936858Y140172D02*
X939012Y138735D01*
G01X938641Y137840D02*
X977475Y130073D01*
G01X939012Y138735D02*
X977511Y131035D01*
G01X934850Y136651D02*
X932623Y136402D01*
G01X932577Y135440D02*
X934780Y135687D01*
G01X939266Y135494D02*
X934850Y136651D01*
G01X934780Y135687D02*
X939052Y134567D01*
G01X977755Y127827D02*
X939266Y135494D01*
G01X939052Y134567D02*
X977697Y126869D01*
G01X932475Y132484D02*
X936522Y132938D01*
G01X932430Y131522D02*
X936481Y131977D01*
G01X936522Y132938D02*
X981543Y123933D01*
G01X936481Y131977D02*
X981470Y122978D01*
G01X932261Y127557D02*
X938414Y128487D01*
G01X932288Y128523D02*
X938437Y129452D01*
G01X938414Y128487D02*
X983899Y119384D01*
G01X938437Y129452D02*
X983982Y120337D01*
G01X932732Y123571D02*
X940167Y125059D01*
G01X932732Y124540D02*
X940167Y126028D01*
G01Y125059D02*
X987077Y115676D01*
G01X940167Y126028D02*
X987167Y116628D01*
G01X932583Y119591D02*
X940558Y121186D01*
G01X932583Y120560D02*
X940558Y122155D01*
G01Y121186D02*
X978991Y113499D01*
G01X940558Y122155D02*
X987330Y112801D01*
G01X936858Y140172D02*
X939012Y138735D01*
G01X936487Y139277D02*
X936902Y139000D01*
G01X936858Y140172D02*
X939012Y138735D01*
G01X936902Y139000D02*
X938641Y137840D01*
G01X939012Y138735D02*
X977511Y131035D01*
G01X938641Y137840D02*
X977475Y130073D01*
G01X939052Y134567D02*
X977697Y126869D01*
G01X977755Y127827D02*
X939266Y135494D01*
G01X934780Y135687D02*
X939052Y134567D01*
G01X939266Y135494D02*
X934850Y136651D01*
G01X932577Y135440D02*
X934780Y135687D01*
G01X934850Y136651D02*
X932623Y136402D01*
G01X932430Y131522D02*
X936481Y131977D01*
G01X932475Y132484D02*
X936522Y132938D01*
G01X936481Y131977D02*
X981470Y122978D01*
G01X936522Y132938D02*
X981543Y123933D01*
G01X932288Y128523D02*
X938437Y129452D01*
G01X932261Y127557D02*
X938414Y128487D01*
G01X938437Y129452D02*
X983982Y120337D01*
G01X938414Y128487D02*
X983899Y119384D01*
G01X939556Y152077D02*
X948348Y146214D01*
G01X939185Y151182D02*
X947977Y145319D01*
G01X948348Y146214D02*
X976372Y140610D01*
G01X947977Y145319D02*
X976372Y139641D01*
G01X943812Y142992D02*
X935720Y147872D01*
G01X936069Y148772D02*
X944161Y143892D01*
G01X974441Y136866D02*
X943812Y142992D01*
G01X944161Y143892D02*
X974613Y137801D01*
G01X941270Y141374D02*
X977249Y134178D01*
G01X977229Y133213D02*
X940899Y140479D01*
G01X936359Y144647D02*
X941270Y141374D01*
G01X940899Y140479D02*
X935988Y143752D01*
G01X945995Y167402D02*
X963943Y155438D01*
G01X945624Y166507D02*
X963572Y154543D01*
G01X963943Y155438D02*
X976392Y152950D01*
G01X963572Y154543D02*
X976392Y151981D01*
G01X943666Y162607D02*
X959143Y152288D01*
G01X944037Y163502D02*
X959514Y153183D01*
G01X959143Y152288D02*
X976410Y148835D01*
G01X959514Y153183D02*
X976410Y149804D01*
G01X941533Y159086D02*
X955123Y150029D01*
G01X941904Y159982D02*
X955494Y150924D01*
G01X955123Y150029D02*
X976402Y145771D01*
G01X955494Y150924D02*
X976402Y146740D01*
G01X976403Y143678D02*
X952526Y148455D01*
G01X976403Y142709D02*
X952155Y147560D01*
G01X952526Y148455D02*
X941210Y156000D01*
G01X952155Y147560D02*
X940839Y155105D01*
G01X939185Y151182D02*
X947977Y145319D01*
G01X939556Y152077D02*
X948348Y146214D01*
G01X947977Y145319D02*
X976372Y139641D01*
G01X948348Y146214D02*
X976372Y140610D01*
G01X944161Y143892D02*
X974613Y137801D01*
G01X974441Y136866D02*
X943812Y142992D01*
G01X936069Y148772D02*
X944161Y143892D01*
G01X943812Y142992D02*
X935720Y147872D01*
G01X940899Y140479D02*
X935988Y143752D01*
G01X936359Y144647D02*
X941270Y141374D01*
G01X977229Y133213D02*
X940899Y140479D01*
G01X941270Y141374D02*
X977249Y134178D01*
G01X945624Y166507D02*
X963572Y154543D01*
G01X945995Y167402D02*
X963943Y155438D01*
G01X963572Y154543D02*
X976392Y151981D01*
G01X963943Y155438D02*
X976392Y152950D01*
G01X944037Y163502D02*
X959514Y153183D01*
G01X943666Y162607D02*
X959143Y152288D01*
G01X959514Y153183D02*
X976410Y149804D01*
G01X959143Y152288D02*
X976410Y148835D01*
G01X941904Y159982D02*
X955494Y150924D01*
G01X941533Y159086D02*
X955123Y150029D01*
G01X955494Y150924D02*
X976402Y146740D01*
G01X955123Y150029D02*
X976402Y145771D01*
G01X976403Y142709D02*
X952155Y147560D01*
G01X976403Y143678D02*
X952526Y148455D01*
G01X952155Y147560D02*
X940839Y155105D01*
G01X952526Y148455D02*
X941210Y156000D01*
G01X934850Y136651D02*
X932623Y136402D01*
G01X932577Y135440D02*
X934780Y135687D01*
G01X939266Y135494D02*
X934850Y136651D01*
G01X934780Y135687D02*
X939052Y134567D01*
G01X977755Y127827D02*
X939266Y135494D01*
G01X939052Y134567D02*
X977697Y126869D01*
G01X932732Y123571D02*
X940167Y125059D01*
G01X932732Y124540D02*
X940167Y126028D01*
G01Y125059D02*
X987077Y115676D01*
G01X940167Y126028D02*
X987167Y116628D01*
G01X943812Y142992D02*
X935720Y147872D01*
G01X936069Y148772D02*
X944161Y143892D01*
G01X974441Y136866D02*
X943812Y142992D01*
G01X944161Y143892D02*
X974613Y137801D01*
G01X932475Y132484D02*
X936522Y132938D01*
G01X932430Y131522D02*
X936481Y131977D01*
G01X936522Y132938D02*
X981543Y123933D01*
G01X936481Y131977D02*
X981470Y122978D01*
G01X976403Y143678D02*
X952526Y148455D01*
G01X976403Y142709D02*
X952155Y147560D01*
G01X952526Y148455D02*
X941210Y156000D01*
G01X952155Y147560D02*
X940839Y155105D01*
G01X940899Y140479D02*
X935988Y143752D01*
G01X936359Y144647D02*
X941270Y141374D01*
G01X977229Y133213D02*
X940899Y140479D01*
G01X941270Y141374D02*
X977249Y134178D01*
G01X945624Y166507D02*
X963572Y154543D01*
G01X945995Y167402D02*
X963943Y155438D01*
G01X963572Y154543D02*
X976392Y151981D01*
G01X963943Y155438D02*
X976392Y152950D01*
G01X948529Y170158D02*
X976893Y175832D01*
G01X948529Y171127D02*
X976893Y176801D01*
G01X948613Y175468D02*
X976592Y181064D01*
G01X948613Y174499D02*
X976592Y180095D01*
G01X948529Y171127D02*
X976893Y176801D01*
G01X948529Y170158D02*
X976893Y175832D01*
G01X948158Y179631D02*
X978452Y185689D01*
G01X948158Y178662D02*
X978472Y184724D01*
G01X948613Y174499D02*
X976592Y180095D01*
G01X948613Y175468D02*
X976592Y181064D01*
G01X950168Y183248D02*
X979678Y189151D01*
G01X950168Y182279D02*
X979678Y188182D01*
G01X948158Y178662D02*
X978472Y184724D01*
G01X948158Y179631D02*
X978452Y185689D01*
G01X969971Y207398D02*
X973357Y207467D01*
G01X969971Y207398D02*
X973357Y207467D01*
G01X973251Y206514D02*
X970288Y206454D01*
G01X966954Y205208D02*
X969971Y207398D01*
G01X970288Y206454D02*
X967550Y204465D01*
G01X966811Y205081D02*
X966954Y205208D01*
G01X967538Y204455D02*
X967515Y204435D01*
G01X966811Y205081D02*
X966954Y205208D01*
G01X967515Y204435D02*
X967479Y204402D01*
G01X957847Y195318D02*
X966811Y205081D01*
G01X967479Y204402D02*
X958501Y194624D01*
G01X957742Y195232D02*
X957823Y195299D01*
G01D02*
X957830Y195305D01*
G01D02*
X957840Y195313D01*
G01X958501Y194624D02*
X958435Y194570D01*
G01X957840Y195313D02*
X957844Y195316D01*
G01X958435Y194570D02*
X958431Y194567D01*
G01X957742Y195232D02*
X957823Y195299D01*
G01D02*
X957830Y195305D01*
G01X958431Y194567D02*
X958417Y194555D01*
G01X957742Y195232D02*
X957823Y195299D01*
G01X957830Y195305D02*
X957840Y195313D01*
G01X958417Y194555D02*
X958286Y194449D01*
G01X953243Y192559D02*
X957742Y195232D01*
G01X958286Y194449D02*
X953594Y191662D01*
G01X948705Y191640D02*
X948913Y191638D01*
G01D02*
X953243Y192559D01*
G01X953594Y191662D02*
X949007Y190686D01*
G01X948705Y191640D02*
X948913Y191638D01*
G01X949007Y190686D02*
X948586Y190691D01*
G01X939042Y193975D02*
X939060Y193971D01*
G01D02*
X948705Y191640D01*
G01D02*
X948913Y191638D01*
G01X948586Y190691D02*
X938837Y193047D01*
G01X930994Y195584D02*
X939042Y193975D01*
G01D02*
X939060Y193971D01*
G01D02*
X948705Y191640D01*
G01X938837Y193047D02*
X938829Y193048D01*
G01X930994Y195584D02*
X939042Y193975D01*
G01D02*
X939060Y193971D01*
G01X938829Y193048D02*
X930795Y194654D01*
G01X977184Y192645D02*
X949621Y187255D01*
G01X977227Y191684D02*
X949622Y186285D01*
G01X949621Y187255D02*
X928744Y191430D01*
G01X949622Y186285D02*
X928557Y190497D01*
G01X949621Y187255D02*
X928744Y191430D01*
G01X928557Y190497D02*
X928533Y190503D01*
G01X950168Y182279D02*
X979678Y188182D01*
G01X950168Y183248D02*
X979678Y189151D01*
G01X938837Y193047D02*
X938829Y193048D01*
G01D02*
X930795Y194654D01*
G01X930994Y195584D02*
X939042Y193975D01*
G01X948586Y190691D02*
X938837Y193047D01*
G01D02*
X938829Y193048D01*
G01D02*
X930795Y194654D01*
G01X939042Y193975D02*
X939060Y193971D01*
G01X948586Y190691D02*
X938837Y193047D01*
G01D02*
X938829Y193048D01*
G01X939060Y193971D02*
X948705Y191640D01*
G01X953594Y191662D02*
X949007Y190686D01*
G01D02*
X948586Y190691D01*
G01D02*
X938837Y193047D01*
G01X948705Y191640D02*
X948913Y191638D01*
G01X953594Y191662D02*
X949007Y190686D01*
G01X948913Y191638D02*
X953243Y192559D01*
G01X958286Y194449D02*
X953594Y191662D01*
G01X953243Y192559D02*
X957742Y195232D01*
G01X958501Y194624D02*
X958435Y194570D01*
G01X958431Y194567D02*
X958417Y194555D01*
G01D02*
X958286Y194449D01*
G01X957742Y195232D02*
X957823Y195299D01*
G01X958501Y194624D02*
X958435Y194570D01*
G01X958431Y194567D02*
X958417Y194555D01*
G01X957823Y195299D02*
X957830Y195305D01*
G01X958501Y194624D02*
X958435Y194570D01*
G01X958417Y194555D02*
X958286Y194449D01*
G01X957830Y195305D02*
X957840Y195313D01*
G01X958435Y194570D02*
X958431Y194567D01*
G01X957840Y195313D02*
X957844Y195316D01*
G01X967479Y204402D02*
X958501Y194624D01*
G01X957847Y195318D02*
X966811Y205081D01*
G01X967538Y204455D02*
X967515Y204435D01*
G01D02*
X967479Y204402D01*
G01X966811Y205081D02*
X966954Y205208D01*
G01X970288Y206454D02*
X967550Y204465D01*
G01X966954Y205208D02*
X969971Y207398D01*
G01X973251Y206514D02*
X970288Y206454D01*
G01X969971Y207398D02*
X973357Y207467D01*
G01X977227Y191684D02*
X949622Y186285D01*
G01X977184Y192645D02*
X949621Y187255D01*
G01X949622Y186285D02*
X928557Y190497D01*
G01D02*
X928533Y190503D01*
G01X949621Y187255D02*
X928744Y191430D01*
G01X928557Y190497D02*
X928533Y190503D01*
G01X969971Y207398D02*
X973357Y207467D01*
G01X969971Y207398D02*
X973357Y207467D01*
G01X973251Y206514D02*
X970288Y206454D01*
G01X966954Y205208D02*
X969971Y207398D01*
G01X970288Y206454D02*
X967550Y204465D01*
G01X966811Y205081D02*
X966954Y205208D01*
G01X967538Y204455D02*
X967515Y204435D01*
G01X966811Y205081D02*
X966954Y205208D01*
G01X967515Y204435D02*
X967479Y204402D01*
G01X957847Y195318D02*
X966811Y205081D01*
G01X967479Y204402D02*
X958501Y194624D01*
G01X957742Y195232D02*
X957823Y195299D01*
G01D02*
X957830Y195305D01*
G01D02*
X957840Y195313D01*
G01X958501Y194624D02*
X958435Y194570D01*
G01X957840Y195313D02*
X957844Y195316D01*
G01X958435Y194570D02*
X958431Y194567D01*
G01X957742Y195232D02*
X957823Y195299D01*
G01D02*
X957830Y195305D01*
G01X958431Y194567D02*
X958417Y194555D01*
G01X957742Y195232D02*
X957823Y195299D01*
G01X957830Y195305D02*
X957840Y195313D01*
G01X958417Y194555D02*
X958286Y194449D01*
G01X953243Y192559D02*
X957742Y195232D01*
G01X958286Y194449D02*
X953594Y191662D01*
G01X948705Y191640D02*
X948913Y191638D01*
G01D02*
X953243Y192559D01*
G01X953594Y191662D02*
X949007Y190686D01*
G01X948705Y191640D02*
X948913Y191638D01*
G01X949007Y190686D02*
X948586Y190691D01*
G01X939042Y193975D02*
X939060Y193971D01*
G01D02*
X948705Y191640D01*
G01D02*
X948913Y191638D01*
G01X948586Y190691D02*
X938837Y193047D01*
G01X930994Y195584D02*
X939042Y193975D01*
G01D02*
X939060Y193971D01*
G01D02*
X948705Y191640D01*
G01X938837Y193047D02*
X938829Y193048D01*
G01X930994Y195584D02*
X939042Y193975D01*
G01D02*
X939060Y193971D01*
G01X938829Y193048D02*
X930795Y194654D01*
G01X948158Y179631D02*
X978452Y185689D01*
G01X948158Y178662D02*
X978472Y184724D01*
G01X948613Y174499D02*
X976592Y180095D01*
G01X948613Y175468D02*
X976592Y181064D01*
G01X948529Y170158D02*
X976893Y175832D01*
G01X948529Y171127D02*
X976893Y176801D01*
G01X977227Y191684D02*
X949622Y186285D01*
G01X977184Y192645D02*
X949621Y187255D01*
G01X949622Y186285D02*
X928557Y190497D01*
G01D02*
X928533Y190503D01*
G01X949621Y187255D02*
X928744Y191430D01*
G01X928557Y190497D02*
X928533Y190503D01*
G01X938467Y406432D02*
X946865Y402953D01*
G01X947404Y403759D02*
X949787Y401375D01*
G01X946865Y402953D02*
X949259Y400559D01*
G01X949787Y401375D02*
X954815Y399467D01*
G01X949259Y400559D02*
X954655Y398511D01*
G01X954815Y399467D02*
X967462Y399871D01*
G01X954655Y398511D02*
X967305Y398915D01*
G01X967462Y399871D02*
X974314Y397309D01*
G01X967305Y398915D02*
X974125Y396365D01*
G01X938467Y406432D02*
X946865Y402953D01*
G01D02*
X949259Y400559D01*
G01X947404Y403759D02*
X949787Y401375D01*
G01X949259Y400559D02*
X954655Y398511D01*
G01X949787Y401375D02*
X954815Y399467D01*
G01X954655Y398511D02*
X967305Y398915D01*
G01X954815Y399467D02*
X967462Y399871D01*
G01X967305Y398915D02*
X974125Y396365D01*
G01X967462Y399871D02*
X974314Y397309D01*
G01X938746Y407345D02*
X947404Y403759D01*
G01X948933Y408535D02*
X956114Y405759D01*
G01D02*
X958200Y404952D01*
G01X949199Y409451D02*
X958200Y405971D01*
G01X956114Y405759D02*
X958200Y404952D01*
G01D02*
X958320Y404906D01*
G01X958200Y405971D02*
X958514Y405850D01*
G01X958200Y404952D02*
X958320Y404906D01*
G01D02*
X993824Y403586D01*
G01X958514Y405850D02*
X993703Y404542D01*
G01X918043Y420780D02*
X924865Y421122D01*
G01X925019Y422081D02*
X959194Y408883D01*
G01X924865Y421122D02*
X935927Y416850D01*
G01X925019Y422081D02*
X959194Y408883D01*
G01X937682Y416172D02*
X938521Y415848D01*
G01X925019Y422081D02*
X959194Y408883D01*
G01X940276Y415170D02*
X959000Y407939D01*
G01X959194Y408883D02*
X990950Y407705D01*
G01X959000Y407939D02*
X991071Y406749D01*
G01X925476Y424970D02*
X961856Y410914D01*
G01X925630Y425929D02*
X962051Y411858D01*
G01X961856Y410914D02*
X988366Y409918D01*
G01X962051Y411858D02*
X988245Y410874D01*
G01X926094Y428814D02*
X964723Y413882D01*
G01X926248Y429773D02*
X964917Y414826D01*
G01X964723Y413882D02*
X985726Y413101D01*
G01X964917Y414826D02*
X985605Y414057D01*
G01X926711Y432659D02*
X967749Y416790D01*
G01X926865Y433619D02*
X967944Y417734D01*
G01X967749Y416790D02*
X982845Y416227D01*
G01X967944Y417734D02*
X982724Y417183D01*
G01X927482Y437464D02*
X970089Y421009D01*
G01X927328Y436505D02*
X969895Y420065D01*
G01X970089Y421009D02*
X980892Y420607D01*
G01X969895Y420065D02*
X981013Y419651D01*
G01X928108Y441310D02*
X972314Y424227D01*
G01X927954Y440351D02*
X972120Y423283D01*
G01X928570Y444198D02*
X974545Y426432D01*
G01X928724Y445157D02*
X974739Y427376D01*
G01X938746Y407345D02*
X947404Y403759D01*
G01X949199Y409451D02*
X958200Y405971D01*
G01X948933Y408535D02*
X956114Y405759D01*
G01X949199Y409451D02*
X958200Y405971D01*
G01D02*
X958514Y405850D01*
G01X956114Y405759D02*
X958200Y404952D01*
G01Y405971D02*
X958514Y405850D01*
G01D02*
X993703Y404542D01*
G01X958200Y404952D02*
X958320Y404906D01*
G01X958514Y405850D02*
X993703Y404542D01*
G01X958320Y404906D02*
X993824Y403586D01*
G01X949199Y409451D02*
X958200Y405971D01*
G01X948933Y408535D02*
X956114Y405759D01*
G01X949199Y409451D02*
X958200Y405971D01*
G01D02*
X958514Y405850D01*
G01X956114Y405759D02*
X958200Y404952D01*
G01Y405971D02*
X958514Y405850D01*
G01D02*
X993703Y404542D01*
G01X958200Y404952D02*
X958320Y404906D01*
G01X958514Y405850D02*
X993703Y404542D01*
G01X958320Y404906D02*
X993824Y403586D01*
G01X918043Y420780D02*
X924865Y421122D01*
G01D02*
X935927Y416850D01*
G01X937682Y416172D02*
X938521Y415848D01*
G01X940276Y415170D02*
X959000Y407939D01*
G01X925019Y422081D02*
X959194Y408883D01*
G01X959000Y407939D02*
X991071Y406749D01*
G01X959194Y408883D02*
X990950Y407705D01*
G01X925630Y425929D02*
X962051Y411858D01*
G01X925476Y424970D02*
X961856Y410914D01*
G01X962051Y411858D02*
X988245Y410874D01*
G01X961856Y410914D02*
X988366Y409918D01*
G01X926248Y429773D02*
X964917Y414826D01*
G01X926094Y428814D02*
X964723Y413882D01*
G01X964917Y414826D02*
X985605Y414057D01*
G01X964723Y413882D02*
X985726Y413101D01*
G01X926865Y433619D02*
X967944Y417734D01*
G01X926711Y432659D02*
X967749Y416790D01*
G01X967944Y417734D02*
X982724Y417183D01*
G01X967749Y416790D02*
X982845Y416227D01*
G01X927328Y436505D02*
X969895Y420065D01*
G01X927482Y437464D02*
X970089Y421009D01*
G01X969895Y420065D02*
X981013Y419651D01*
G01X970089Y421009D02*
X980892Y420607D01*
G01X927954Y440351D02*
X972120Y423283D01*
G01X928108Y441310D02*
X972314Y424227D01*
G01X928724Y445157D02*
X974739Y427376D01*
G01X928570Y444198D02*
X974545Y426432D01*
G01X927954Y440351D02*
X972120Y423283D01*
G01X928108Y441310D02*
X972314Y424227D01*
G01X918043Y420780D02*
X924865Y421122D01*
G01X925019Y422081D02*
X959194Y408883D01*
G01X924865Y421122D02*
X935927Y416850D01*
G01X925019Y422081D02*
X959194Y408883D01*
G01X937682Y416172D02*
X938521Y415848D01*
G01X925019Y422081D02*
X959194Y408883D01*
G01X940276Y415170D02*
X959000Y407939D01*
G01X959194Y408883D02*
X990950Y407705D01*
G01X959000Y407939D02*
X991071Y406749D01*
G01X925476Y424970D02*
X961856Y410914D01*
G01X925630Y425929D02*
X962051Y411858D01*
G01X961856Y410914D02*
X988366Y409918D01*
G01X962051Y411858D02*
X988245Y410874D01*
G01X928108Y441310D02*
X972314Y424227D01*
G01X927954Y440351D02*
X972120Y423283D01*
G01X925630Y425929D02*
X962051Y411858D01*
G01X925476Y424970D02*
X961856Y410914D01*
G01X962051Y411858D02*
X988245Y410874D01*
G01X961856Y410914D02*
X988366Y409918D01*
G01X927328Y436505D02*
X969895Y420065D01*
G01X927482Y437464D02*
X970089Y421009D01*
G01X969895Y420065D02*
X981013Y419651D01*
G01X970089Y421009D02*
X980892Y420607D01*
G01X928724Y445157D02*
X974739Y427376D01*
G01X928570Y444198D02*
X974545Y426432D01*
G01X926711Y432659D02*
X967749Y416790D01*
G01X926865Y433619D02*
X967944Y417734D01*
G01X967749Y416790D02*
X982845Y416227D01*
G01X967944Y417734D02*
X982724Y417183D01*
G01X918043Y420780D02*
X924865Y421122D01*
G01D02*
X935927Y416850D01*
G01X937682Y416172D02*
X938521Y415848D01*
G01X940276Y415170D02*
X959000Y407939D01*
G01X925019Y422081D02*
X959194Y408883D01*
G01X959000Y407939D02*
X991071Y406749D01*
G01X959194Y408883D02*
X990950Y407705D01*
G01X926248Y429773D02*
X964917Y414826D01*
G01X926094Y428814D02*
X964723Y413882D01*
G01X964917Y414826D02*
X985605Y414057D01*
G01X964723Y413882D02*
X985726Y413101D01*
G01X926865Y433619D02*
X967944Y417734D01*
G01X926711Y432659D02*
X967749Y416790D01*
G01X967944Y417734D02*
X982724Y417183D01*
G01X967749Y416790D02*
X982845Y416227D01*
G01X982624Y108819D02*
X1001345Y105443D01*
G01X982802Y109753D02*
X1001336Y106411D01*
G01X1001345Y105443D02*
X1103254Y125825D01*
G01X1001336Y106411D02*
X1036777Y113499D01*
G01X1001345Y105443D02*
X1103254Y125825D01*
G01X978991Y113499D02*
X987216Y111854D01*
G01X987330Y112801D02*
X994861Y112481D01*
G01X987216Y111854D02*
X994716Y111536D01*
G01X994861Y112481D02*
X1002099Y110531D01*
G01X994716Y111536D02*
X1002067Y109555D01*
G01X1002099Y110531D02*
X1016937Y113499D01*
G01X1002067Y109555D02*
X1021783Y113499D01*
G01X1016937D02*
X1103233Y130761D01*
G01X1021783Y113499D02*
X1103233Y129792D01*
G01X982802Y109753D02*
X1001336Y106411D01*
G01X982624Y108819D02*
X1001345Y105443D01*
G01X1001336Y106411D02*
X1036777Y113499D01*
G01X1001345Y105443D02*
X1103254Y125825D01*
G01X978991Y113499D02*
X987216Y111854D01*
G01D02*
X994716Y111536D01*
G01X987330Y112801D02*
X994861Y112481D01*
G01X994716Y111536D02*
X1002067Y109555D01*
G01X994861Y112481D02*
X1002099Y110531D01*
G01X1002067Y109555D02*
X1021783Y113499D01*
G01X1002099Y110531D02*
X1016937Y113499D01*
G01X1021783D02*
X1103233Y129792D01*
G01X1016937Y113499D02*
X1103233Y130761D01*
G01X987167Y116628D02*
X995204Y116705D01*
G01X987077Y115676D02*
X995097Y115753D01*
G01X995204Y116705D02*
X1003538Y114718D01*
G01X995097Y115753D02*
X1003520Y113745D01*
G01X1003538Y114718D02*
X1103436Y134699D01*
G01X1003520Y113745D02*
X1103436Y133730D01*
G01X977475Y130073D02*
X994623Y132174D01*
G01X977511Y131035D02*
X994605Y133129D01*
G01X994623Y132174D02*
X1009069Y130943D01*
G01X994605Y133129D02*
X1009015Y131902D01*
G01X1009069Y130943D02*
X1102116Y149555D01*
G01X1009015Y131902D02*
X1102116Y150524D01*
G01X993936Y129044D02*
X977755Y127827D01*
G01X977697Y126869D02*
X993940Y128091D01*
G01X1009075Y128034D02*
X993936Y129044D01*
G01X993940Y128091D02*
X1009138Y127077D01*
G01X1102114Y146644D02*
X1009075Y128034D01*
G01X1009138Y127077D02*
X1102114Y145675D01*
G01X981543Y123933D02*
X996373Y124598D01*
G01X981470Y122978D02*
X996328Y123645D01*
G01X996373Y124598D02*
X1006531Y123174D01*
G01X996328Y123645D02*
X1006559Y122210D01*
G01X1006531Y123174D02*
X1103281Y142525D01*
G01X1006559Y122210D02*
X1103281Y141556D01*
G01X983899Y119384D02*
X995081Y119647D01*
G01X983982Y120337D02*
X995143Y120599D01*
G01X995081Y119647D02*
X1005418Y118041D01*
G01X995143Y120599D02*
X1005397Y119006D01*
G01X1005418Y118041D02*
X1103421Y137642D01*
G01X1005397Y119006D02*
X1103421Y138611D01*
G01X987077Y115676D02*
X995097Y115753D01*
G01X987167Y116628D02*
X995204Y116705D01*
G01X995097Y115753D02*
X1003520Y113745D01*
G01X995204Y116705D02*
X1003538Y114718D01*
G01X1003520Y113745D02*
X1103436Y133730D01*
G01X1003538Y114718D02*
X1103436Y134699D01*
G01X978991Y113499D02*
X987216Y111854D01*
G01D02*
X994716Y111536D01*
G01X987330Y112801D02*
X994861Y112481D01*
G01X994716Y111536D02*
X1002067Y109555D01*
G01X994861Y112481D02*
X1002099Y110531D01*
G01X1002067Y109555D02*
X1021783Y113499D01*
G01X1002099Y110531D02*
X1016937Y113499D01*
G01X1021783D02*
X1103233Y129792D01*
G01X1016937Y113499D02*
X1103233Y130761D01*
G01X977511Y131035D02*
X994605Y133129D01*
G01X977475Y130073D02*
X994623Y132174D01*
G01X994605Y133129D02*
X1009015Y131902D01*
G01X994623Y132174D02*
X1009069Y130943D01*
G01X1009015Y131902D02*
X1102116Y150524D01*
G01X1009069Y130943D02*
X1102116Y149555D01*
G01X1009138Y127077D02*
X1102114Y145675D01*
G01Y146644D02*
X1009075Y128034D01*
G01X993940Y128091D02*
X1009138Y127077D01*
G01X1009075Y128034D02*
X993936Y129044D01*
G01X977697Y126869D02*
X993940Y128091D01*
G01X993936Y129044D02*
X977755Y127827D01*
G01X981470Y122978D02*
X996328Y123645D01*
G01X981543Y123933D02*
X996373Y124598D01*
G01X996328Y123645D02*
X1006559Y122210D01*
G01X996373Y124598D02*
X1006531Y123174D01*
G01X1006559Y122210D02*
X1103281Y141556D01*
G01X1006531Y123174D02*
X1103281Y142525D01*
G01X983982Y120337D02*
X995143Y120599D01*
G01X983899Y119384D02*
X995081Y119647D01*
G01X995143Y120599D02*
X1005397Y119006D01*
G01X995081Y119647D02*
X1005418Y118041D01*
G01X1005397Y119006D02*
X1103421Y138611D01*
G01X1005418Y118041D02*
X1103421Y137642D01*
G01X976372Y140610D02*
X990204Y143374D01*
G01X976372Y139641D02*
X990440Y142452D01*
G01X990204Y143374D02*
X997014Y145507D01*
G01X990440Y142452D02*
X997136Y144549D01*
G01X997014Y145507D02*
X1010340Y144848D01*
G01X997136Y144549D02*
X1010371Y143895D01*
G01X1010340Y144848D02*
X1020865Y146056D01*
G01X1010371Y143895D02*
X1021013Y145116D01*
G01X1020865Y146056D02*
X1102478Y162380D01*
G01X1021013Y145116D02*
X1102478Y161411D01*
G01X977200Y136403D02*
X974441Y136866D01*
G01X974613Y137801D02*
X977187Y137369D01*
G01X997978Y140486D02*
X977200Y136403D01*
G01X977187Y137369D02*
X997936Y141446D01*
G01X1009995Y139210D02*
X997978Y140486D01*
G01X997936Y141446D02*
X1009966Y140169D01*
G01X1019588Y140810D02*
X1009995Y139210D01*
G01X1009966Y140169D02*
X1019417Y141745D01*
G01X1102219Y157336D02*
X1019588Y140810D01*
G01X1019417Y141745D02*
X1102219Y158305D01*
G01X1009383Y135856D02*
X1102181Y154417D01*
G01Y153448D02*
X1009427Y134895D01*
G01X996605Y137215D02*
X1009383Y135856D01*
G01X1009427Y134895D02*
X996629Y136257D01*
G01X977249Y134178D02*
X996605Y137215D01*
G01X996629Y136257D02*
X977229Y133213D01*
G01X976392Y152950D02*
X980791Y153830D01*
G01X976392Y151981D02*
X981141Y152930D01*
G01X980791Y153830D02*
X994573Y162163D01*
G01X981141Y152930D02*
X994845Y161217D01*
G01X976410Y148835D02*
X983835Y150320D01*
G01X976410Y149804D02*
X983501Y151223D01*
G01X983835Y150320D02*
X994682Y156412D01*
G01X983504Y151224D02*
X994441Y157367D01*
G01X994682Y156412D02*
X1009467Y156149D01*
G01D02*
X1027516Y158282D01*
G01X1009467Y156149D02*
X1027516Y158282D01*
G01X976402Y145771D02*
X985521Y147595D01*
G01X976402Y146740D02*
X985225Y148505D01*
G01X985521Y147595D02*
X991598Y150400D01*
G01X985225Y148505D02*
X991218Y151271D01*
G01X991598Y150400D02*
X996582Y152454D01*
G01X991218Y151271D02*
X996412Y153412D01*
G01X996582Y152454D02*
X1010219Y151919D01*
G01X996412Y153412D02*
X1010176Y152872D01*
G01X1010219Y151919D02*
X1026212Y154011D01*
G01X1010176Y152872D02*
X1026057Y154949D01*
G01X1026212Y154011D02*
X1103339Y169435D01*
G01X1026057Y154949D02*
X1103269Y170390D01*
G01X1103053Y166438D02*
X1024820Y150791D01*
G01X1103126Y165483D02*
X1024976Y149853D01*
G01X1024820Y150791D02*
X1011021Y148959D01*
G01X1024976Y149853D02*
X1011068Y148006D01*
G01X1011021Y148959D02*
X1001895Y149264D01*
G01D02*
X1000945D01*
G01X1011068Y148006D02*
X1001879Y148314D01*
G01X1011021Y148959D02*
X1001895Y149264D01*
G01D02*
X1000945D01*
G01X1001879Y148314D02*
X1001864D01*
G01X1011021Y148959D02*
X1001895Y149264D01*
G01D02*
X1000945D01*
G01D02*
X996336Y149353D01*
G01X1001864Y148314D02*
X1000926Y148313D01*
G01X1001895Y149264D02*
X1000945D01*
G01D02*
X996336Y149353D01*
G01X1000926Y148313D02*
X996499Y148399D01*
G01X996336Y149353D02*
X986557Y145709D01*
G01X996499Y148399D02*
X986818Y144792D01*
G01X986557Y145709D02*
X976403Y143678D01*
G01X986818Y144792D02*
X976403Y142709D01*
G01X976372Y139641D02*
X990440Y142452D01*
G01X976372Y140610D02*
X990204Y143374D01*
G01X990440Y142452D02*
X997136Y144549D01*
G01X990204Y143374D02*
X997014Y145507D01*
G01X997136Y144549D02*
X1010371Y143895D01*
G01X997014Y145507D02*
X1010340Y144848D01*
G01X1010371Y143895D02*
X1021013Y145116D01*
G01X1010340Y144848D02*
X1020865Y146056D01*
G01X1021013Y145116D02*
X1102478Y161411D01*
G01X1020865Y146056D02*
X1102478Y162380D01*
G01X1019417Y141745D02*
X1102219Y158305D01*
G01Y157336D02*
X1019588Y140810D01*
G01X1009966Y140169D02*
X1019417Y141745D01*
G01X1019588Y140810D02*
X1009995Y139210D01*
G01X997936Y141446D02*
X1009966Y140169D01*
G01X1009995Y139210D02*
X997978Y140486D01*
G01X977187Y137369D02*
X997936Y141446D01*
G01X997978Y140486D02*
X977200Y136403D01*
G01X974613Y137801D02*
X977187Y137369D01*
G01X977200Y136403D02*
X974441Y136866D01*
G01X996629Y136257D02*
X977229Y133213D01*
G01X977249Y134178D02*
X996605Y137215D01*
G01X1009427Y134895D02*
X996629Y136257D01*
G01X996605Y137215D02*
X1009383Y135856D01*
G01X1102181Y153448D02*
X1009427Y134895D01*
G01X1009383Y135856D02*
X1102181Y154417D01*
G01X976392Y151981D02*
X981141Y152930D01*
G01X976392Y152950D02*
X980791Y153830D01*
G01X981141Y152930D02*
X994845Y161217D01*
G01X980791Y153830D02*
X994573Y162163D01*
G01X976410Y149804D02*
X983501Y151223D01*
G01X976410Y148835D02*
X983835Y150320D01*
G01X983504Y151224D02*
X994441Y157367D01*
G01X983835Y150320D02*
X994682Y156412D01*
G01D02*
X1009467Y156149D01*
G01D02*
X1027516Y158282D01*
G01X976402Y146740D02*
X985225Y148505D01*
G01X976402Y145771D02*
X985521Y147595D01*
G01X985225Y148505D02*
X991218Y151271D01*
G01X985521Y147595D02*
X991598Y150400D01*
G01X991218Y151271D02*
X996412Y153412D01*
G01X991598Y150400D02*
X996582Y152454D01*
G01X996412Y153412D02*
X1010176Y152872D01*
G01X996582Y152454D02*
X1010219Y151919D01*
G01X1010176Y152872D02*
X1026057Y154949D01*
G01X1010219Y151919D02*
X1026212Y154011D01*
G01X1026057Y154949D02*
X1103269Y170390D01*
G01X1026212Y154011D02*
X1103339Y169435D01*
G01X1103126Y165483D02*
X1024976Y149853D01*
G01X1103053Y166438D02*
X1024820Y150791D01*
G01X1024976Y149853D02*
X1011068Y148006D01*
G01X1024820Y150791D02*
X1011021Y148959D01*
G01X1011068Y148006D02*
X1001879Y148314D01*
G01D02*
X1001864D01*
G01D02*
X1000926Y148313D01*
G01X1011021Y148959D02*
X1001895Y149264D01*
G01X1011068Y148006D02*
X1001879Y148314D01*
G01D02*
X1001864D01*
G01D02*
X1000926Y148313D01*
G01D02*
X996499Y148399D01*
G01X1001895Y149264D02*
X1000945D01*
G01X1001864Y148314D02*
X1000926Y148313D01*
G01D02*
X996499Y148399D01*
G01X1000945Y149264D02*
X996336Y149353D01*
G01X996499Y148399D02*
X986818Y144792D01*
G01X996336Y149353D02*
X986557Y145709D01*
G01X986818Y144792D02*
X976403Y142709D01*
G01X986557Y145709D02*
X976403Y143678D01*
G01X993936Y129044D02*
X977755Y127827D01*
G01X977697Y126869D02*
X993940Y128091D01*
G01X1009075Y128034D02*
X993936Y129044D01*
G01X993940Y128091D02*
X1009138Y127077D01*
G01X1102114Y146644D02*
X1009075Y128034D01*
G01X1009138Y127077D02*
X1102114Y145675D01*
G01X987077Y115676D02*
X995097Y115753D01*
G01X987167Y116628D02*
X995204Y116705D01*
G01X995097Y115753D02*
X1003520Y113745D01*
G01X995204Y116705D02*
X1003538Y114718D01*
G01X1003520Y113745D02*
X1103436Y133730D01*
G01X1003538Y114718D02*
X1103436Y134699D01*
G01X977200Y136403D02*
X974441Y136866D01*
G01X974613Y137801D02*
X977187Y137369D01*
G01X997978Y140486D02*
X977200Y136403D01*
G01X977187Y137369D02*
X997936Y141446D01*
G01X1009995Y139210D02*
X997978Y140486D01*
G01X997936Y141446D02*
X1009966Y140169D01*
G01X1019588Y140810D02*
X1009995Y139210D01*
G01X1009966Y140169D02*
X1019417Y141745D01*
G01X1102219Y157336D02*
X1019588Y140810D01*
G01X1019417Y141745D02*
X1102219Y158305D01*
G01X981543Y123933D02*
X996373Y124598D01*
G01X981470Y122978D02*
X996328Y123645D01*
G01X996373Y124598D02*
X1006531Y123174D01*
G01X996328Y123645D02*
X1006559Y122210D01*
G01X1006531Y123174D02*
X1103281Y142525D01*
G01X1006559Y122210D02*
X1103281Y141556D01*
G01X1103053Y166438D02*
X1024820Y150791D01*
G01X1103126Y165483D02*
X1024976Y149853D01*
G01X1024820Y150791D02*
X1011021Y148959D01*
G01X1024976Y149853D02*
X1011068Y148006D01*
G01X1011021Y148959D02*
X1001895Y149264D01*
G01D02*
X1000945D01*
G01X1011068Y148006D02*
X1001879Y148314D01*
G01X1011021Y148959D02*
X1001895Y149264D01*
G01D02*
X1000945D01*
G01X1001879Y148314D02*
X1001864D01*
G01X1011021Y148959D02*
X1001895Y149264D01*
G01D02*
X1000945D01*
G01D02*
X996336Y149353D01*
G01X1001864Y148314D02*
X1000926Y148313D01*
G01X1001895Y149264D02*
X1000945D01*
G01D02*
X996336Y149353D01*
G01X1000926Y148313D02*
X996499Y148399D01*
G01X996336Y149353D02*
X986557Y145709D01*
G01X996499Y148399D02*
X986818Y144792D01*
G01X986557Y145709D02*
X976403Y143678D01*
G01X986818Y144792D02*
X976403Y142709D01*
G01X996629Y136257D02*
X977229Y133213D01*
G01X977249Y134178D02*
X996605Y137215D01*
G01X1009427Y134895D02*
X996629Y136257D01*
G01X996605Y137215D02*
X1009383Y135856D01*
G01X1102181Y153448D02*
X1009427Y134895D01*
G01X1009383Y135856D02*
X1102181Y154417D01*
G01X976392Y151981D02*
X981141Y152930D01*
G01X976392Y152950D02*
X980791Y153830D01*
G01X981141Y152930D02*
X994845Y161217D01*
G01X980791Y153830D02*
X994573Y162163D01*
G01X976893Y175832D02*
X989601Y173289D01*
G01X976893Y176801D02*
X990174Y174144D01*
G01X989601Y173289D02*
X989954Y172761D01*
G01X990174Y174144D02*
X990963Y172961D01*
G01X989954Y172761D02*
X989182Y168900D01*
G01X990963Y172961D02*
X990191Y169100D01*
G01X989182Y168900D02*
X989971Y167716D01*
G01X990191Y169100D02*
X990544Y168571D01*
G01X989971Y167716D02*
X993049Y167100D01*
G01X990544Y168571D02*
X992849Y168109D01*
G01X993049Y167100D02*
X994233Y167890D01*
G01X992849Y168109D02*
X993378Y168462D01*
G01X994233Y167890D02*
X995005Y171750D01*
G01X993378Y168462D02*
X994150Y172323D01*
G01X995005Y171750D02*
X995533Y172102D01*
G01X994150Y172323D02*
X995333Y173112D01*
G01X995533Y172102D02*
X997843Y171639D01*
G01X995333Y173112D02*
X998416Y172494D01*
G01X997843Y171639D02*
X998196Y171111D01*
G01X998416Y172494D02*
X999205Y171311D01*
G01X998196Y171111D02*
X997424Y167250D01*
G01X999205Y171311D02*
X998433Y167450D01*
G01X997424Y167250D02*
X998213Y166066D01*
G01X998433Y167450D02*
X998786Y166921D01*
G01X998213Y166066D02*
X1001291Y165450D01*
G01X998786Y166921D02*
X1001091Y166459D01*
G01X1001291Y165450D02*
X1002475Y166240D01*
G01X1001091Y166459D02*
X1001620Y166812D01*
G01X1002475Y166240D02*
X1003247Y170100D01*
G01X1001620Y166812D02*
X1002392Y170673D01*
G01X1003247Y170100D02*
X1003775Y170453D01*
G01X1002392Y170673D02*
X1003575Y171462D01*
G01X1003775Y170453D02*
X1025576Y166094D01*
G01X1003575Y171462D02*
X1025576Y167063D01*
G01Y166094D02*
X1102427Y181463D01*
G01X1025576Y167063D02*
X1102362Y182419D01*
G01X994573Y162163D02*
X1018981Y162574D01*
G01X994845Y161217D02*
X1018997Y161624D01*
G01X994573Y162163D02*
X1018981Y162574D01*
G01Y162575D02*
X1028742Y163332D01*
G01X1018997Y161624D02*
X1019026D01*
G01X1018981Y162575D02*
X1028742Y163332D01*
G01X1019026Y161624D02*
X1028872Y162389D01*
G01X1028742Y163332D02*
X1099460Y177476D01*
G01X1028872Y162389D02*
X1099663Y176547D01*
G01X994441Y157367D02*
X1009419Y157101D01*
G01X1027516Y158282D02*
X1028070Y158325D01*
G01X1009419Y157101D02*
X1027423Y159228D01*
G01X1027516Y158282D02*
X1028070Y158325D01*
G01D02*
X1100572Y172827D01*
G01X1027423Y159228D02*
X1027940Y159268D01*
G01X1028070Y158325D02*
X1100572Y172827D01*
G01X1027940Y159268D02*
X1100359Y173754D01*
G01X976592Y181064D02*
X1025973Y171189D01*
G01X976592Y180095D02*
X1025973Y170220D01*
G01Y171189D02*
X1102491Y186488D01*
G01X1025973Y170220D02*
X1102552Y185531D01*
G01X976893Y176801D02*
X990174Y174144D01*
G01X976893Y175832D02*
X989601Y173289D01*
G01X990174Y174144D02*
X990963Y172961D01*
G01X989601Y173289D02*
X989954Y172761D01*
G01X990963Y172961D02*
X990191Y169100D01*
G01X989954Y172761D02*
X989182Y168900D01*
G01X990191Y169100D02*
X990544Y168571D01*
G01X989182Y168900D02*
X989971Y167716D01*
G01X990544Y168571D02*
X992849Y168109D01*
G01X989971Y167716D02*
X993049Y167100D01*
G01X992849Y168109D02*
X993378Y168462D01*
G01X993049Y167100D02*
X994233Y167890D01*
G01X993378Y168462D02*
X994150Y172323D01*
G01X994233Y167890D02*
X995005Y171750D01*
G01X994150Y172323D02*
X995333Y173112D01*
G01X995005Y171750D02*
X995533Y172102D01*
G01X995333Y173112D02*
X998416Y172494D01*
G01X995533Y172102D02*
X997843Y171639D01*
G01X998416Y172494D02*
X999205Y171311D01*
G01X997843Y171639D02*
X998196Y171111D01*
G01X999205Y171311D02*
X998433Y167450D01*
G01X998196Y171111D02*
X997424Y167250D01*
G01X998433Y167450D02*
X998786Y166921D01*
G01X997424Y167250D02*
X998213Y166066D01*
G01X998786Y166921D02*
X1001091Y166459D01*
G01X998213Y166066D02*
X1001291Y165450D01*
G01X1001091Y166459D02*
X1001620Y166812D01*
G01X1001291Y165450D02*
X1002475Y166240D01*
G01X1001620Y166812D02*
X1002392Y170673D01*
G01X1002475Y166240D02*
X1003247Y170100D01*
G01X1002392Y170673D02*
X1003575Y171462D01*
G01X1003247Y170100D02*
X1003775Y170453D01*
G01X1003575Y171462D02*
X1025576Y167063D01*
G01X1003775Y170453D02*
X1025576Y166094D01*
G01Y167063D02*
X1102362Y182419D01*
G01X1025576Y166094D02*
X1102427Y181463D01*
G01X994845Y161217D02*
X1018997Y161624D01*
G01D02*
X1019026D01*
G01X994573Y162163D02*
X1018981Y162574D01*
G01X1018997Y161624D02*
X1019026D01*
G01D02*
X1028872Y162389D01*
G01X1018981Y162575D02*
X1028742Y163332D01*
G01X1028872Y162389D02*
X1099663Y176547D01*
G01X1028742Y163332D02*
X1099460Y177476D01*
G01X994441Y157367D02*
X1009419Y157101D01*
G01D02*
X1027423Y159228D01*
G01D02*
X1027940Y159268D01*
G01X1009419Y157101D02*
X1027423Y159228D01*
G01D02*
X1027940Y159268D01*
G01X1027516Y158282D02*
X1028070Y158325D01*
G01X1027423Y159228D02*
X1027940Y159268D01*
G01D02*
X1100359Y173754D01*
G01X1028070Y158325D02*
X1100572Y172827D01*
G01X978452Y185689D02*
X979950Y185452D01*
G01X978472Y184724D02*
X979748Y184523D01*
G01X979950Y185453D02*
X1009829Y178949D01*
G01X979748Y184523D02*
X1010011Y177937D01*
G01X1009829Y178949D02*
X1010362Y179291D01*
G01X1010011Y177937D02*
X1011207Y178703D01*
G01X1010362Y179291D02*
X1010594Y180355D01*
G01X1011207Y178703D02*
X1011439Y179769D01*
G01X1010594Y180355D02*
X1011790Y181126D01*
G01X1011439Y179769D02*
X1011973Y180113D01*
G01X1011790Y181126D02*
X1014858Y180456D01*
G01X1011973Y180113D02*
X1014271Y179611D01*
G01X1014858Y180456D02*
X1015628Y179260D01*
G01X1014271Y179611D02*
X1014615Y179077D01*
G01X1015628Y179260D02*
X1015396Y178197D01*
G01X1014615Y179077D02*
X1014383Y178014D01*
G01X1015396Y178197D02*
X1015740Y177662D01*
G01X1014383Y178014D02*
X1015153Y176817D01*
G01X1015740Y177662D02*
X1018043Y177161D01*
G01X1015153Y176817D02*
X1018225Y176149D01*
G01X1018043Y177161D02*
X1018576Y177503D01*
G01X1018225Y176149D02*
X1019421Y176915D01*
G01X1018576Y177503D02*
X1019124Y180015D01*
G01X1019421Y176915D02*
X1019969Y179429D01*
G01X1019124Y180015D02*
X1020320Y180786D01*
G01X1019969Y179429D02*
X1020503Y179773D01*
G01X1020320Y180786D02*
X1023388Y180116D01*
G01X1020503Y179773D02*
X1022801Y179271D01*
G01X1023388Y180116D02*
X1024158Y178920D01*
G01X1022801Y179271D02*
X1023145Y178737D01*
G01X1024158Y178920D02*
X1023610Y176408D01*
G01X1023145Y178737D02*
X1022597Y176225D01*
G01X1023610Y176408D02*
X1023954Y175873D01*
G01X1022597Y176225D02*
X1023063Y175500D01*
G01X1023610Y176408D02*
X1023954Y175873D01*
G01X1023063Y175500D02*
X1023367Y175028D01*
G01X1023954Y175873D02*
X1026320Y175358D01*
G01X1023367Y175028D02*
X1026306Y174388D01*
G01X1026320Y175358D02*
X1028340Y175736D01*
G01X1026306Y174388D02*
X1028902Y174874D01*
G01X1028340Y175736D02*
X1028698Y176259D01*
G01X1028902Y174874D02*
X1029331Y175500D01*
G01X1028340Y175736D02*
X1028698Y176259D01*
G01X1029331Y175500D02*
X1029705Y176047D01*
G01X1028698Y176259D02*
X1028433Y177673D01*
G01X1029705Y176047D02*
X1029440Y177460D01*
G01X1028433Y177673D02*
X1029239Y178846D01*
G01X1029440Y177460D02*
X1029800Y177984D01*
G01X1029239Y178846D02*
X1032323Y179425D01*
G01X1029800Y177984D02*
X1032111Y178418D01*
G01X1032323Y179425D02*
X1033497Y178621D01*
G01X1032111Y178418D02*
X1032635Y178059D01*
G01D02*
X1032888Y176702D01*
G01D02*
X1034073Y175903D01*
G01X976592Y180095D02*
X1025973Y170220D01*
G01X976592Y181064D02*
X1025973Y171189D01*
G01Y170220D02*
X1102552Y185531D01*
G01X1025973Y171189D02*
X1102491Y186488D01*
G01X979678Y189151D02*
X984820Y188122D01*
G01X979678Y188182D02*
X984827Y187151D01*
G01X984820Y188122D02*
X998492Y191076D01*
G01X984827Y187151D02*
X998577Y190122D01*
G01X998492Y191076D02*
X1002045Y190952D01*
G01X998577Y190122D02*
X1001619Y190016D01*
G01X1002045Y190952D02*
X1003016Y189912D01*
G01X1001619Y190016D02*
X1002052Y189551D01*
G01X1003016Y189912D02*
X1002899Y186586D01*
G01X1002052Y189551D02*
X1001935Y186225D01*
G01X1002899Y186586D02*
X1003333Y186122D01*
G01X1001935Y186225D02*
X1002907Y185186D01*
G01X1003333Y186122D02*
X1005684Y186038D01*
G01X1002907Y185186D02*
X1006045Y185074D01*
G01X1005684Y186038D02*
X1006148Y186472D01*
G01X1006045Y185074D02*
X1007084Y186046D01*
G01X1006148Y186472D02*
X1006264Y189798D01*
G01X1007084Y186046D02*
X1007200Y189372D01*
G01X1006264Y189798D02*
X1007304Y190769D01*
G01X1007200Y189372D02*
X1007665Y189805D01*
G01X1007304Y190769D02*
X1012294Y190595D01*
G01X1007665Y189805D02*
X1011867Y189658D01*
G01X1012294Y190595D02*
X1013264Y189555D01*
G01X1011867Y189658D02*
X1012300Y189195D01*
G01X1013264Y189555D02*
X1013112Y185237D01*
G01X1012300Y189195D02*
X1012148Y184876D01*
G01X1013112Y185237D02*
X1013546Y184772D01*
G01X1012148Y184876D02*
X1013119Y183836D01*
G01X1013546Y184772D02*
X1015896Y184688D01*
G01X1013119Y183836D02*
X1016257Y183724D01*
G01X1015896Y184688D02*
X1016360Y185122D01*
G01X1016257Y183724D02*
X1017296Y184696D01*
G01X1016360Y185122D02*
X1016582Y191439D01*
G01X1017296Y184696D02*
X1017519Y191012D01*
G01X1016582Y191439D02*
X1017622Y192409D01*
G01X1017519Y191012D02*
X1017982Y191445D01*
G01X1017622Y192409D02*
X1020764Y192298D01*
G01X1017982Y191445D02*
X1020337Y191362D01*
G01X1020764Y192298D02*
X1021734Y191258D01*
G01X1020337Y191362D02*
X1020770Y190898D01*
G01X1021734Y191258D02*
X1021512Y184941D01*
G01X1020770Y190898D02*
X1020548Y184581D01*
G01X1021512Y184941D02*
X1021946Y184476D01*
G01X1020548Y184581D02*
X1021519Y183540D01*
G01X1021946Y184476D02*
X1024296Y184392D01*
G01X1021519Y183540D02*
X1024657Y183428D01*
G01X1024296Y184392D02*
X1024760Y184826D01*
G01X1024657Y183428D02*
X1025696Y184400D01*
G01X1024760Y184826D02*
X1024949Y190160D01*
G01X1025696Y184400D02*
X1025885Y189734D01*
G01X1024949Y190160D02*
X1025987Y191131D01*
G01X1025885Y189734D02*
X1026348Y190167D01*
G01X1025987Y191131D02*
X1032989Y190884D01*
G01X1026348Y190167D02*
X1032778Y189940D01*
G01X1032989Y190884D02*
X1035385Y189857D01*
G01X1032778Y189940D02*
X1034648Y189138D01*
G01X978472Y184724D02*
X979748Y184523D01*
G01X978452Y185689D02*
X979950Y185452D01*
G01X979748Y184523D02*
X1010011Y177937D01*
G01X979950Y185453D02*
X1009829Y178949D01*
G01X1010011Y177937D02*
X1011207Y178703D01*
G01X1009829Y178949D02*
X1010362Y179291D01*
G01X1011207Y178703D02*
X1011439Y179769D01*
G01X1010362Y179291D02*
X1010594Y180355D01*
G01X1011439Y179769D02*
X1011973Y180113D01*
G01X1010594Y180355D02*
X1011790Y181126D01*
G01X1011973Y180113D02*
X1014271Y179611D01*
G01X1011790Y181126D02*
X1014858Y180456D01*
G01X1014271Y179611D02*
X1014615Y179077D01*
G01X1014858Y180456D02*
X1015628Y179260D01*
G01X1014615Y179077D02*
X1014383Y178014D01*
G01X1015628Y179260D02*
X1015396Y178197D01*
G01X1014383Y178014D02*
X1015153Y176817D01*
G01X1015396Y178197D02*
X1015740Y177662D01*
G01X1015153Y176817D02*
X1018225Y176149D01*
G01X1015740Y177662D02*
X1018043Y177161D01*
G01X1018225Y176149D02*
X1019421Y176915D01*
G01X1018043Y177161D02*
X1018576Y177503D01*
G01X1019421Y176915D02*
X1019969Y179429D01*
G01X1018576Y177503D02*
X1019124Y180015D01*
G01X1019969Y179429D02*
X1020503Y179773D01*
G01X1019124Y180015D02*
X1020320Y180786D01*
G01X1020503Y179773D02*
X1022801Y179271D01*
G01X1020320Y180786D02*
X1023388Y180116D01*
G01X1022801Y179271D02*
X1023145Y178737D01*
G01X1023388Y180116D02*
X1024158Y178920D01*
G01X1023145Y178737D02*
X1022597Y176225D01*
G01X1024158Y178920D02*
X1023610Y176408D01*
G01X1022597Y176225D02*
X1023063Y175500D01*
G01D02*
X1023367Y175028D01*
G01X1023610Y176408D02*
X1023954Y175873D01*
G01X1023367Y175028D02*
X1026306Y174388D01*
G01X1023954Y175873D02*
X1026320Y175358D01*
G01X1026306Y174388D02*
X1028902Y174874D01*
G01X1026320Y175358D02*
X1028340Y175736D01*
G01X1028902Y174874D02*
X1029331Y175500D01*
G01D02*
X1029705Y176047D01*
G01X1028340Y175736D02*
X1028698Y176259D01*
G01X1029705Y176047D02*
X1029440Y177460D01*
G01X1028698Y176259D02*
X1028433Y177673D01*
G01X1029440Y177460D02*
X1029800Y177984D01*
G01X1028433Y177673D02*
X1029239Y178846D01*
G01X1029800Y177984D02*
X1032111Y178418D01*
G01X1029239Y178846D02*
X1032323Y179425D01*
G01X1032111Y178418D02*
X1032635Y178059D01*
G01X1032323Y179425D02*
X1033497Y178621D01*
G01X1032635Y178059D02*
X1032888Y176702D01*
G01D02*
X1034073Y175903D01*
G01X1032339Y204806D02*
X1034487Y204376D01*
G01X1034116Y203481D02*
X1032339Y203837D01*
G01X1028672Y204072D02*
X1032339Y204806D01*
G01Y203837D02*
X1029042Y203177D01*
G01X1026996Y202956D02*
X1028672Y204072D01*
G01X1029042Y203177D02*
X1027366Y202061D01*
G01X1012700Y200096D02*
X1026996Y202956D01*
G01X1027366Y202061D02*
X1012700Y199127D01*
G01X1003297Y201978D02*
X1012700Y200096D01*
G01Y199127D02*
X1008011Y200064D01*
G01X1003297Y201978D02*
X1012700Y200096D01*
G01X1008011Y200065D02*
X1003320Y201004D01*
G01X993376Y199500D02*
X1003297Y201978D01*
G01X1003320Y201004D02*
X993493Y198550D01*
G01X988092Y199500D02*
X993376D01*
G01X993493Y198550D02*
X987633D01*
G01X987086Y200764D02*
X988092Y199500D01*
G01X987633Y198550D02*
X986376Y200130D01*
G01X985721Y202129D02*
X987086Y200764D01*
G01X986376Y200130D02*
X985117Y201389D01*
G01X980167Y205795D02*
X985721Y202129D01*
G01X985117Y201389D02*
X979780Y204911D01*
G01X973357Y207467D02*
X980167Y205795D01*
G01X979780Y204911D02*
X973252Y206514D01*
G01X973357Y207467D02*
X980167Y205795D01*
G01X973252Y206514D02*
X973251D01*
G01X1034053Y196603D02*
X1031888Y198341D01*
G01X1033765Y195615D02*
X1031417Y197500D01*
G01X1031888Y198341D02*
X1029122Y199335D01*
G01X1031417Y197500D02*
X1029048Y198352D01*
G01X1029122Y199335D02*
X1011174Y195799D01*
G01X1029048Y198352D02*
X1011086Y194813D01*
G01X1011174Y195799D02*
X1007817Y197113D01*
G01X1011086Y194813D02*
X1007642Y196161D01*
G01X1007817Y197113D02*
X1003989Y197077D01*
G01X1007642Y196161D02*
X1004137Y196128D01*
G01X1003989Y197077D02*
X986539Y191686D01*
G01X1004137Y196128D02*
X986634Y190721D01*
G01X986539Y191686D02*
X982119Y192139D01*
G01X980247Y192331D02*
X977184Y192645D01*
G01X986634Y190721D02*
X977227Y191685D01*
G01X979678Y188182D02*
X984827Y187151D01*
G01X979678Y189151D02*
X984820Y188122D01*
G01X984827Y187151D02*
X998577Y190122D01*
G01X984820Y188122D02*
X998492Y191076D01*
G01X998577Y190122D02*
X1001619Y190016D01*
G01X998492Y191076D02*
X1002045Y190952D01*
G01X1001619Y190016D02*
X1002052Y189551D01*
G01X1002045Y190952D02*
X1003016Y189912D01*
G01X1002052Y189551D02*
X1001935Y186225D01*
G01X1003016Y189912D02*
X1002899Y186586D01*
G01X1001935Y186225D02*
X1002907Y185186D01*
G01X1002899Y186586D02*
X1003333Y186122D01*
G01X1002907Y185186D02*
X1006045Y185074D01*
G01X1003333Y186122D02*
X1005684Y186038D01*
G01X1006045Y185074D02*
X1007084Y186046D01*
G01X1005684Y186038D02*
X1006148Y186472D01*
G01X1007084Y186046D02*
X1007200Y189372D01*
G01X1006148Y186472D02*
X1006264Y189798D01*
G01X1007200Y189372D02*
X1007665Y189805D01*
G01X1006264Y189798D02*
X1007304Y190769D01*
G01X1007665Y189805D02*
X1011867Y189658D01*
G01X1007304Y190769D02*
X1012294Y190595D01*
G01X1011867Y189658D02*
X1012300Y189195D01*
G01X1012294Y190595D02*
X1013264Y189555D01*
G01X1012300Y189195D02*
X1012148Y184876D01*
G01X1013264Y189555D02*
X1013112Y185237D01*
G01X1012148Y184876D02*
X1013119Y183836D01*
G01X1013112Y185237D02*
X1013546Y184772D01*
G01X1013119Y183836D02*
X1016257Y183724D01*
G01X1013546Y184772D02*
X1015896Y184688D01*
G01X1016257Y183724D02*
X1017296Y184696D01*
G01X1015896Y184688D02*
X1016360Y185122D01*
G01X1017296Y184696D02*
X1017519Y191012D01*
G01X1016360Y185122D02*
X1016582Y191439D01*
G01X1017519Y191012D02*
X1017982Y191445D01*
G01X1016582Y191439D02*
X1017622Y192409D01*
G01X1017982Y191445D02*
X1020337Y191362D01*
G01X1017622Y192409D02*
X1020764Y192298D01*
G01X1020337Y191362D02*
X1020770Y190898D01*
G01X1020764Y192298D02*
X1021734Y191258D01*
G01X1020770Y190898D02*
X1020548Y184581D01*
G01X1021734Y191258D02*
X1021512Y184941D01*
G01X1020548Y184581D02*
X1021519Y183540D01*
G01X1021512Y184941D02*
X1021946Y184476D01*
G01X1021519Y183540D02*
X1024657Y183428D01*
G01X1021946Y184476D02*
X1024296Y184392D01*
G01X1024657Y183428D02*
X1025696Y184400D01*
G01X1024296Y184392D02*
X1024760Y184826D01*
G01X1025696Y184400D02*
X1025885Y189734D01*
G01X1024760Y184826D02*
X1024949Y190160D01*
G01X1025885Y189734D02*
X1026348Y190167D01*
G01X1024949Y190160D02*
X1025987Y191131D01*
G01X1026348Y190167D02*
X1032778Y189940D01*
G01X1025987Y191131D02*
X1032989Y190884D01*
G01X1032778Y189940D02*
X1034648Y189138D01*
G01X1032989Y190884D02*
X1035385Y189857D01*
G01X973252Y206514D02*
X973251D01*
G01X979780Y204911D02*
X973252Y206514D01*
G01D02*
X973251D01*
G01X973357Y207467D02*
X980167Y205795D01*
G01X985117Y201389D02*
X979780Y204911D01*
G01X980167Y205795D02*
X985721Y202129D01*
G01X986376Y200130D02*
X985117Y201389D01*
G01X985721Y202129D02*
X987086Y200764D01*
G01X987633Y198550D02*
X986376Y200130D01*
G01X987086Y200764D02*
X988092Y199500D01*
G01X993493Y198550D02*
X987633D01*
G01X988092Y199500D02*
X993376D01*
G01X1003320Y201004D02*
X993493Y198550D01*
G01X993376Y199500D02*
X1003297Y201978D01*
G01X1012700Y199127D02*
X1008011Y200064D01*
G01Y200065D02*
X1003320Y201004D01*
G01X1003297Y201978D02*
X1012700Y200096D01*
G01X1027366Y202061D02*
X1012700Y199127D01*
G01Y200096D02*
X1026996Y202956D01*
G01X1029042Y203177D02*
X1027366Y202061D01*
G01X1026996Y202956D02*
X1028672Y204072D01*
G01X1032339Y203837D02*
X1029042Y203177D01*
G01X1028672Y204072D02*
X1032339Y204806D01*
G01X1034116Y203481D02*
X1032339Y203837D01*
G01Y204806D02*
X1034487Y204376D01*
G01X1033765Y195615D02*
X1031417Y197500D01*
G01X1033765Y195615D02*
X1031417Y197500D01*
G01X1034053Y196603D02*
X1031888Y198341D01*
G01X1031417Y197500D02*
X1029048Y198352D01*
G01X1031888Y198341D02*
X1029122Y199335D01*
G01X1029048Y198352D02*
X1011086Y194813D01*
G01X1029122Y199335D02*
X1011174Y195799D01*
G01X1011086Y194813D02*
X1007642Y196161D01*
G01X1011174Y195799D02*
X1007817Y197113D01*
G01X1007642Y196161D02*
X1004137Y196128D01*
G01X1007817Y197113D02*
X1003989Y197077D01*
G01X1004137Y196128D02*
X986634Y190721D01*
G01X1003989Y197077D02*
X986539Y191686D01*
G01X986634Y190721D02*
X977227Y191685D01*
G01X986539Y191686D02*
X982119Y192139D01*
G01X986634Y190721D02*
X977227Y191685D01*
G01X980247Y192331D02*
X977184Y192645D01*
G01X1032339Y204806D02*
X1034487Y204376D01*
G01X1034116Y203481D02*
X1032339Y203837D01*
G01X1028672Y204072D02*
X1032339Y204806D01*
G01Y203837D02*
X1029042Y203177D01*
G01X1026996Y202956D02*
X1028672Y204072D01*
G01X1029042Y203177D02*
X1027366Y202061D01*
G01X1012700Y200096D02*
X1026996Y202956D01*
G01X1027366Y202061D02*
X1012700Y199127D01*
G01X1003297Y201978D02*
X1012700Y200096D01*
G01Y199127D02*
X1008011Y200064D01*
G01X1003297Y201978D02*
X1012700Y200096D01*
G01X1008011Y200065D02*
X1003320Y201004D01*
G01X993376Y199500D02*
X1003297Y201978D01*
G01X1003320Y201004D02*
X993493Y198550D01*
G01X988092Y199500D02*
X993376D01*
G01X993493Y198550D02*
X987633D01*
G01X987086Y200764D02*
X988092Y199500D01*
G01X987633Y198550D02*
X986376Y200130D01*
G01X985721Y202129D02*
X987086Y200764D01*
G01X986376Y200130D02*
X985117Y201389D01*
G01X980167Y205795D02*
X985721Y202129D01*
G01X985117Y201389D02*
X979780Y204911D01*
G01X973357Y207467D02*
X980167Y205795D01*
G01X979780Y204911D02*
X973252Y206514D01*
G01X973357Y207467D02*
X980167Y205795D01*
G01X973252Y206514D02*
X973251D01*
G01X978452Y185689D02*
X979950Y185452D01*
G01X978472Y184724D02*
X979748Y184523D01*
G01X979950Y185453D02*
X1009829Y178949D01*
G01X979748Y184523D02*
X1010011Y177937D01*
G01X1009829Y178949D02*
X1010362Y179291D01*
G01X1010011Y177937D02*
X1011207Y178703D01*
G01X1010362Y179291D02*
X1010594Y180355D01*
G01X1011207Y178703D02*
X1011439Y179769D01*
G01X1010594Y180355D02*
X1011790Y181126D01*
G01X1011439Y179769D02*
X1011973Y180113D01*
G01X1011790Y181126D02*
X1014858Y180456D01*
G01X1011973Y180113D02*
X1014271Y179611D01*
G01X1014858Y180456D02*
X1015628Y179260D01*
G01X1014271Y179611D02*
X1014615Y179077D01*
G01X1015628Y179260D02*
X1015396Y178197D01*
G01X1014615Y179077D02*
X1014383Y178014D01*
G01X1015396Y178197D02*
X1015740Y177662D01*
G01X1014383Y178014D02*
X1015153Y176817D01*
G01X1015740Y177662D02*
X1018043Y177161D01*
G01X1015153Y176817D02*
X1018225Y176149D01*
G01X1018043Y177161D02*
X1018576Y177503D01*
G01X1018225Y176149D02*
X1019421Y176915D01*
G01X1018576Y177503D02*
X1019124Y180015D01*
G01X1019421Y176915D02*
X1019969Y179429D01*
G01X1019124Y180015D02*
X1020320Y180786D01*
G01X1019969Y179429D02*
X1020503Y179773D01*
G01X1020320Y180786D02*
X1023388Y180116D01*
G01X1020503Y179773D02*
X1022801Y179271D01*
G01X1023388Y180116D02*
X1024158Y178920D01*
G01X1022801Y179271D02*
X1023145Y178737D01*
G01X1024158Y178920D02*
X1023610Y176408D01*
G01X1023145Y178737D02*
X1022597Y176225D01*
G01X1023610Y176408D02*
X1023954Y175873D01*
G01X1022597Y176225D02*
X1023063Y175500D01*
G01X1023610Y176408D02*
X1023954Y175873D01*
G01X1023063Y175500D02*
X1023367Y175028D01*
G01X1023954Y175873D02*
X1026320Y175358D01*
G01X1023367Y175028D02*
X1026306Y174388D01*
G01X1026320Y175358D02*
X1028340Y175736D01*
G01X1026306Y174388D02*
X1028902Y174874D01*
G01X1028340Y175736D02*
X1028698Y176259D01*
G01X1028902Y174874D02*
X1029331Y175500D01*
G01X1028340Y175736D02*
X1028698Y176259D01*
G01X1029331Y175500D02*
X1029705Y176047D01*
G01X1028698Y176259D02*
X1028433Y177673D01*
G01X1029705Y176047D02*
X1029440Y177460D01*
G01X1028433Y177673D02*
X1029239Y178846D01*
G01X1029440Y177460D02*
X1029800Y177984D01*
G01X1029239Y178846D02*
X1032323Y179425D01*
G01X1029800Y177984D02*
X1032111Y178418D01*
G01X1032323Y179425D02*
X1033497Y178621D01*
G01X1032111Y178418D02*
X1032635Y178059D01*
G01D02*
X1032888Y176702D01*
G01D02*
X1034073Y175903D01*
G01X976592Y180095D02*
X1025973Y170220D01*
G01X976592Y181064D02*
X1025973Y171189D01*
G01Y170220D02*
X1102552Y185531D01*
G01X1025973Y171189D02*
X1102491Y186488D01*
G01X994845Y161217D02*
X1018997Y161624D01*
G01D02*
X1019026D01*
G01X994573Y162163D02*
X1018981Y162574D01*
G01X1018997Y161624D02*
X1019026D01*
G01D02*
X1028872Y162389D01*
G01X1018981Y162575D02*
X1028742Y163332D01*
G01X1028872Y162389D02*
X1099663Y176547D01*
G01X1028742Y163332D02*
X1099460Y177476D01*
G01X976893Y175832D02*
X989601Y173289D01*
G01X976893Y176801D02*
X990174Y174144D01*
G01X989601Y173289D02*
X989954Y172761D01*
G01X990174Y174144D02*
X990963Y172961D01*
G01X989954Y172761D02*
X989182Y168900D01*
G01X990963Y172961D02*
X990191Y169100D01*
G01X989182Y168900D02*
X989971Y167716D01*
G01X990191Y169100D02*
X990544Y168571D01*
G01X989971Y167716D02*
X993049Y167100D01*
G01X990544Y168571D02*
X992849Y168109D01*
G01X993049Y167100D02*
X994233Y167890D01*
G01X992849Y168109D02*
X993378Y168462D01*
G01X994233Y167890D02*
X995005Y171750D01*
G01X993378Y168462D02*
X994150Y172323D01*
G01X995005Y171750D02*
X995533Y172102D01*
G01X994150Y172323D02*
X995333Y173112D01*
G01X995533Y172102D02*
X997843Y171639D01*
G01X995333Y173112D02*
X998416Y172494D01*
G01X997843Y171639D02*
X998196Y171111D01*
G01X998416Y172494D02*
X999205Y171311D01*
G01X998196Y171111D02*
X997424Y167250D01*
G01X999205Y171311D02*
X998433Y167450D01*
G01X997424Y167250D02*
X998213Y166066D01*
G01X998433Y167450D02*
X998786Y166921D01*
G01X998213Y166066D02*
X1001291Y165450D01*
G01X998786Y166921D02*
X1001091Y166459D01*
G01X1001291Y165450D02*
X1002475Y166240D01*
G01X1001091Y166459D02*
X1001620Y166812D01*
G01X1002475Y166240D02*
X1003247Y170100D01*
G01X1001620Y166812D02*
X1002392Y170673D01*
G01X1003247Y170100D02*
X1003775Y170453D01*
G01X1002392Y170673D02*
X1003575Y171462D01*
G01X1003775Y170453D02*
X1025576Y166094D01*
G01X1003575Y171462D02*
X1025576Y167063D01*
G01Y166094D02*
X1102427Y181463D01*
G01X1025576Y167063D02*
X1102362Y182419D01*
G01X1033765Y195615D02*
X1031417Y197500D01*
G01X1033765Y195615D02*
X1031417Y197500D01*
G01X1034053Y196603D02*
X1031888Y198341D01*
G01X1031417Y197500D02*
X1029048Y198352D01*
G01X1031888Y198341D02*
X1029122Y199335D01*
G01X1029048Y198352D02*
X1011086Y194813D01*
G01X1029122Y199335D02*
X1011174Y195799D01*
G01X1011086Y194813D02*
X1007642Y196161D01*
G01X1011174Y195799D02*
X1007817Y197113D01*
G01X1007642Y196161D02*
X1004137Y196128D01*
G01X1007817Y197113D02*
X1003989Y197077D01*
G01X1004137Y196128D02*
X986634Y190721D01*
G01X1003989Y197077D02*
X986539Y191686D01*
G01X986634Y190721D02*
X977227Y191685D01*
G01X986539Y191686D02*
X982119Y192139D01*
G01X986634Y190721D02*
X977227Y191685D01*
G01X980247Y192331D02*
X977184Y192645D01*
G01X974314Y397309D02*
X982090Y397016D01*
G01X974125Y396365D02*
X982211Y396060D01*
G01X982090Y397016D02*
X993667Y400463D01*
G01X982211Y396060D02*
X993757Y399498D01*
G01X993667Y400463D02*
X1002835Y399504D01*
G01X993757Y399498D02*
X1002862Y398546D01*
G01X1002835Y399504D02*
X1009533Y400545D01*
G01X1002862Y398546D02*
X1009847Y399632D01*
G01X1009533Y400545D02*
X1011810Y401813D01*
G01X1009847Y399632D02*
X1012616Y401173D01*
G01X1011810Y401813D02*
X1011985Y402424D01*
G01X1012616Y401173D02*
X1013007Y402542D01*
G01X1011985Y402424D02*
X1011358Y403548D01*
G01X1013007Y402542D02*
X1012380Y403667D01*
G01X974125Y396365D02*
X982211Y396060D01*
G01X974314Y397309D02*
X982090Y397016D01*
G01X982211Y396060D02*
X993757Y399498D01*
G01X982090Y397016D02*
X993667Y400463D01*
G01X993757Y399498D02*
X1002862Y398546D01*
G01X993667Y400463D02*
X1002835Y399504D01*
G01X1002862Y398546D02*
X1009847Y399632D01*
G01X1002835Y399504D02*
X1009533Y400545D01*
G01X1009847Y399632D02*
X1012616Y401173D01*
G01X1009533Y400545D02*
X1011810Y401813D01*
G01X1012616Y401173D02*
X1013007Y402542D01*
G01X1011810Y401813D02*
X1011985Y402424D01*
G01X1013007Y402542D02*
X1012380Y403667D01*
G01X1011985Y402424D02*
X1011358Y403548D01*
G01D02*
X1011747Y404915D01*
G01X1012380Y403667D02*
X1012553Y404276D01*
G01X1011747Y404915D02*
X1013263Y405759D01*
G01D02*
X1014843Y406639D01*
G01X1012553Y404276D02*
X1014962Y405617D01*
G01X1014843Y406639D02*
X1016210Y406250D01*
G01X1014962Y405617D02*
X1015571Y405443D01*
G01X1016210Y406250D02*
X1016484Y405759D01*
G01D02*
X1016837Y405126D01*
G01X1015571Y405443D02*
X1016198Y404320D01*
G01X1016837Y405126D02*
X1017447Y404951D01*
G01X1016198Y404320D02*
X1017565Y403928D01*
G01X1017447Y404951D02*
X1018898Y405759D01*
G01D02*
X1022754Y407907D01*
G01X1017565Y403928D02*
X1020852Y405759D01*
G01X1018898D02*
X1022754Y407907D01*
G01X1020852Y405759D02*
X1023045Y406981D01*
G01X1022754Y407907D02*
X1097343Y415471D01*
G01X1023045Y406981D02*
X1097297Y414511D01*
G01X980444Y455378D02*
X1035040Y448916D01*
G01X980412Y454425D02*
X1035032Y447960D01*
G01X980858Y458263D02*
X1035040Y451790D01*
G01X1035048Y452746D02*
X980891Y459216D01*
G01X1035622Y456636D02*
X981012Y463036D01*
G01X1035615Y455680D02*
X980980Y462083D01*
G01X1035650Y459512D02*
X981110Y465904D01*
G01X1035657Y460468D02*
X981142Y466857D01*
G01X981274Y470679D02*
X1035686Y464301D01*
G01X981242Y469726D02*
X1035679Y463345D01*
G01X993824Y403586D02*
X1014162Y409642D01*
G01X993703Y404542D02*
X1013934Y410566D01*
G01X1014162Y409642D02*
X1023306Y411447D01*
G01X1013934Y410566D02*
X1023166Y412388D01*
G01X1023306Y411447D02*
X1098636Y419039D01*
G01X1023166Y412388D02*
X1056097Y415707D01*
G01X1023306Y411447D02*
X1098636Y419039D01*
G01X1023306Y411447D02*
X1098636Y419039D01*
G01X990950Y407705D02*
X1021333Y416752D01*
G01X991071Y406749D02*
X1021518Y415815D01*
G01X1021333Y416752D02*
X1108740Y425556D01*
G01X1021518Y415815D02*
X1093043Y423019D01*
G01X1021333Y416752D02*
X1108740Y425556D01*
G01X1021333Y416752D02*
X1108740Y425556D01*
G01X1021333Y416752D02*
X1108740Y425556D01*
G01X1021333Y416752D02*
X1108740Y425556D01*
G01X1021333Y416752D02*
X1108740Y425556D01*
G01X1021333Y416752D02*
X1108740Y425556D01*
G01X1021333Y416752D02*
X1108740Y425556D01*
G01X988366Y409918D02*
X1020915Y419609D01*
G01X988245Y410874D02*
X1020730Y420546D01*
G01X1020915Y419609D02*
X1109368Y428518D01*
G01X1020730Y420546D02*
X1109417Y429478D01*
G01X985726Y413101D02*
X1020337Y423410D01*
G01X985605Y414057D02*
X1020152Y424347D01*
G01X1020337Y423410D02*
X1109632Y432470D01*
G01X1020152Y424347D02*
X1109678Y433430D01*
G01X982845Y416227D02*
X1019563Y427160D01*
G01X982724Y417183D02*
X1019378Y428097D01*
G01X1019563Y427160D02*
X1110666Y436406D01*
G01X1019378Y428097D02*
X1110712Y437366D01*
G01X980892Y420607D02*
X1018678Y431859D01*
G01X981013Y419651D02*
X1018864Y430923D01*
G01X1018678Y431859D02*
X1112896Y441504D01*
G01X1018864Y430923D02*
X1112850Y440544D01*
G01X972314Y424227D02*
X978787Y423985D01*
G01X972120Y423283D02*
X978908Y423029D01*
G01X978787Y423985D02*
X1018155Y435713D01*
G01X978908Y423029D02*
X1018340Y434776D01*
G01X1018155Y435713D02*
X1113299Y445369D01*
G01X1018340Y434776D02*
X1113253Y444409D01*
G01X974545Y426432D02*
X976599Y426355D01*
G01X974739Y427376D02*
X976478Y427311D01*
G01X976599Y426355D02*
X1017418Y438512D01*
G01X976478Y427311D02*
X1017233Y439449D01*
G01X1017418Y438512D02*
X1113594Y448275D01*
G01X1017233Y439449D02*
X1113640Y449235D01*
G01X979940Y450587D02*
X987217Y449734D01*
G01X989105Y449512D02*
X993258Y449026D01*
G01X995146Y448804D02*
X996408Y448657D01*
G01X998296Y448434D02*
X1035027Y444130D01*
G01X979972Y451540D02*
X1035034Y445086D01*
G01X1012380Y403667D02*
X1012553Y404276D01*
G01X1011358Y403548D02*
X1011747Y404915D01*
G01X1012553Y404276D02*
X1014962Y405617D01*
G01X1011747Y404915D02*
X1013263Y405759D01*
G01X1012553Y404276D02*
X1014962Y405617D01*
G01X1013263Y405759D02*
X1014843Y406639D01*
G01X1014962Y405617D02*
X1015571Y405443D01*
G01X1014843Y406639D02*
X1016210Y406250D01*
G01X1015571Y405443D02*
X1016198Y404320D01*
G01X1016210Y406250D02*
X1016484Y405759D01*
G01X1015571Y405443D02*
X1016198Y404320D01*
G01X1016484Y405759D02*
X1016837Y405126D01*
G01X1016198Y404320D02*
X1017565Y403928D01*
G01X1016837Y405126D02*
X1017447Y404951D01*
G01X1017565Y403928D02*
X1020852Y405759D01*
G01X1017447Y404951D02*
X1018898Y405759D01*
G01X1017565Y403928D02*
X1020852Y405759D01*
G01D02*
X1023045Y406981D01*
G01X1018898Y405759D02*
X1022754Y407907D01*
G01X1023045Y406981D02*
X1097297Y414511D01*
G01X1022754Y407907D02*
X1097343Y415471D01*
G01X980412Y454425D02*
X1035032Y447960D01*
G01X980444Y455378D02*
X1035040Y448916D01*
G01X980412Y454425D02*
X1035032Y447960D01*
G01X980444Y455378D02*
X1035040Y448916D01*
G01X1035048Y452746D02*
X980891Y459216D01*
G01X980858Y458263D02*
X1035040Y451790D01*
G01X1035615Y455680D02*
X980980Y462083D01*
G01X1035622Y456636D02*
X981012Y463036D01*
G01X1035657Y460468D02*
X981142Y466857D01*
G01X1035650Y459512D02*
X981110Y465904D01*
G01X981242Y469726D02*
X1035679Y463345D01*
G01X981274Y470679D02*
X1035686Y464301D01*
G01X993703Y404542D02*
X1013934Y410566D01*
G01X993824Y403586D02*
X1014162Y409642D01*
G01X1013934Y410566D02*
X1023166Y412388D01*
G01X1014162Y409642D02*
X1023306Y411447D01*
G01X1023166Y412388D02*
X1056097Y415707D01*
G01X1023306Y411447D02*
X1098636Y419039D01*
G01X993703Y404542D02*
X1013934Y410566D01*
G01X993824Y403586D02*
X1014162Y409642D01*
G01X1013934Y410566D02*
X1023166Y412388D01*
G01X1014162Y409642D02*
X1023306Y411447D01*
G01X1023166Y412388D02*
X1056097Y415707D01*
G01X1023306Y411447D02*
X1098636Y419039D01*
G01X991071Y406749D02*
X1021518Y415815D01*
G01X990950Y407705D02*
X1021333Y416752D01*
G01X1021518Y415815D02*
X1093043Y423019D01*
G01X1021333Y416752D02*
X1108740Y425556D01*
G01X988245Y410874D02*
X1020730Y420546D01*
G01X988366Y409918D02*
X1020915Y419609D01*
G01X1020730Y420546D02*
X1109417Y429478D01*
G01X1020915Y419609D02*
X1109368Y428518D01*
G01X985605Y414057D02*
X1020152Y424347D01*
G01X985726Y413101D02*
X1020337Y423410D01*
G01X1020152Y424347D02*
X1109678Y433430D01*
G01X1020337Y423410D02*
X1109632Y432470D01*
G01X982724Y417183D02*
X1019378Y428097D01*
G01X982845Y416227D02*
X1019563Y427160D01*
G01X1019378Y428097D02*
X1110712Y437366D01*
G01X1019563Y427160D02*
X1110666Y436406D01*
G01X981013Y419651D02*
X1018864Y430923D01*
G01X980892Y420607D02*
X1018678Y431859D01*
G01X1018864Y430923D02*
X1112850Y440544D01*
G01X1018678Y431859D02*
X1112896Y441504D01*
G01X972120Y423283D02*
X978908Y423029D01*
G01X972314Y424227D02*
X978787Y423985D01*
G01X978908Y423029D02*
X1018340Y434776D01*
G01X978787Y423985D02*
X1018155Y435713D01*
G01X1018340Y434776D02*
X1113253Y444409D01*
G01X1018155Y435713D02*
X1113299Y445369D01*
G01X974739Y427376D02*
X976478Y427311D01*
G01X974545Y426432D02*
X976599Y426355D01*
G01X976478Y427311D02*
X1017233Y439449D01*
G01X976599Y426355D02*
X1017418Y438512D01*
G01X1017233Y439449D02*
X1113640Y449235D01*
G01X1017418Y438512D02*
X1113594Y448275D01*
G01X979972Y451540D02*
X1035034Y445086D01*
G01X979940Y450587D02*
X987217Y449734D01*
G01X979972Y451540D02*
X1035034Y445086D01*
G01X989105Y449512D02*
X993258Y449026D01*
G01X979972Y451540D02*
X1035034Y445086D01*
G01X995146Y448804D02*
X996408Y448657D01*
G01X979972Y451540D02*
X1035034Y445086D01*
G01X998296Y448434D02*
X1035027Y444130D01*
G01X981242Y469726D02*
X1035679Y463345D01*
G01X981274Y470679D02*
X1035686Y464301D01*
G01X980858Y458263D02*
X1035040Y451790D01*
G01X1035048Y452746D02*
X980891Y459216D01*
G01X1035650Y459512D02*
X981110Y465904D01*
G01X1035657Y460468D02*
X981142Y466857D01*
G01X1035615Y455680D02*
X980980Y462083D01*
G01X1035622Y456636D02*
X981012Y463036D01*
G01X972120Y423283D02*
X978908Y423029D01*
G01X972314Y424227D02*
X978787Y423985D01*
G01X978908Y423029D02*
X1018340Y434776D01*
G01X978787Y423985D02*
X1018155Y435713D01*
G01X1018340Y434776D02*
X1113253Y444409D01*
G01X1018155Y435713D02*
X1113299Y445369D01*
G01X979940Y450587D02*
X987217Y449734D01*
G01X989105Y449512D02*
X993258Y449026D01*
G01X995146Y448804D02*
X996408Y448657D01*
G01X998296Y448434D02*
X1035027Y444130D01*
G01X979972Y451540D02*
X1035034Y445086D01*
G01X990950Y407705D02*
X1021333Y416752D01*
G01X991071Y406749D02*
X1021518Y415815D01*
G01X1021333Y416752D02*
X1108740Y425556D01*
G01X1021518Y415815D02*
X1093043Y423019D01*
G01X1021333Y416752D02*
X1108740Y425556D01*
G01X1021333Y416752D02*
X1108740Y425556D01*
G01X1021333Y416752D02*
X1108740Y425556D01*
G01X1021333Y416752D02*
X1108740Y425556D01*
G01X1021333Y416752D02*
X1108740Y425556D01*
G01X1021333Y416752D02*
X1108740Y425556D01*
G01X1021333Y416752D02*
X1108740Y425556D01*
G01X988366Y409918D02*
X1020915Y419609D01*
G01X988245Y410874D02*
X1020730Y420546D01*
G01X1020915Y419609D02*
X1109368Y428518D01*
G01X1020730Y420546D02*
X1109417Y429478D01*
G01X972314Y424227D02*
X978787Y423985D01*
G01X972120Y423283D02*
X978908Y423029D01*
G01X978787Y423985D02*
X1018155Y435713D01*
G01X978908Y423029D02*
X1018340Y434776D01*
G01X1018155Y435713D02*
X1113299Y445369D01*
G01X1018340Y434776D02*
X1113253Y444409D01*
G01X988245Y410874D02*
X1020730Y420546D01*
G01X988366Y409918D02*
X1020915Y419609D01*
G01X1020730Y420546D02*
X1109417Y429478D01*
G01X1020915Y419609D02*
X1109368Y428518D01*
G01X981013Y419651D02*
X1018864Y430923D01*
G01X980892Y420607D02*
X1018678Y431859D01*
G01X1018864Y430923D02*
X1112850Y440544D01*
G01X1018678Y431859D02*
X1112896Y441504D01*
G01X974739Y427376D02*
X976478Y427311D01*
G01X974545Y426432D02*
X976599Y426355D01*
G01X976478Y427311D02*
X1017233Y439449D01*
G01X976599Y426355D02*
X1017418Y438512D01*
G01X1017233Y439449D02*
X1113640Y449235D01*
G01X1017418Y438512D02*
X1113594Y448275D01*
G01X982845Y416227D02*
X1019563Y427160D01*
G01X982724Y417183D02*
X1019378Y428097D01*
G01X1019563Y427160D02*
X1110666Y436406D01*
G01X1019378Y428097D02*
X1110712Y437366D01*
G01X991071Y406749D02*
X1021518Y415815D01*
G01X990950Y407705D02*
X1021333Y416752D01*
G01X1021518Y415815D02*
X1093043Y423019D01*
G01X1021333Y416752D02*
X1108740Y425556D01*
G01X985605Y414057D02*
X1020152Y424347D01*
G01X985726Y413101D02*
X1020337Y423410D01*
G01X1020152Y424347D02*
X1109678Y433430D01*
G01X1020337Y423410D02*
X1109632Y432470D01*
G01X982724Y417183D02*
X1019378Y428097D01*
G01X982845Y416227D02*
X1019563Y427160D01*
G01X1019378Y428097D02*
X1110712Y437366D01*
G01X1019563Y427160D02*
X1110666Y436406D01*
G01X981373Y473547D02*
X1035709Y467178D01*
G01X981405Y474500D02*
X1035716Y468134D01*
G01X1035715Y471965D02*
X981878Y478340D01*
G01X981846Y477387D02*
X1035707Y471009D01*
G01X981405Y474500D02*
X1035716Y468134D01*
G01X981373Y473547D02*
X1035709Y467178D01*
G01X981846Y477387D02*
X1035707Y471009D01*
G01X1035715Y471965D02*
X981878Y478340D01*
G01X982008Y482161D02*
X1035740Y475798D01*
G01X981976Y481208D02*
X1035732Y474842D01*
G01X982008Y482161D02*
X1035740Y475798D01*
G01X981976Y481208D02*
X1035732Y474842D01*
G01X982450Y485045D02*
X1035740Y478671D01*
G01X982483Y485998D02*
X1035748Y479627D01*
G01X982536Y488865D02*
X1036333Y482561D01*
G01X982568Y489818D02*
X1036340Y483517D01*
G01X981976Y481208D02*
X1035732Y474842D01*
G01X982008Y482161D02*
X1035740Y475798D01*
G01X982483Y485998D02*
X1035748Y479627D01*
G01X982450Y485045D02*
X1035740Y478671D01*
G01X982568Y489818D02*
X1036340Y483517D01*
G01X982536Y488865D02*
X1036333Y482561D01*
G01X981373Y473547D02*
X1035709Y467178D01*
G01X981405Y474500D02*
X1035716Y468134D01*
G01X1035715Y471965D02*
X981878Y478340D01*
G01X981846Y477387D02*
X1035707Y471009D01*
G01X1036777Y113499D02*
X1103254Y126794D01*
G01X1036777Y113499D02*
X1103254Y126794D01*
G01X1033497Y178621D02*
X1033750Y177268D01*
G01D02*
X1034276Y176913D01*
G01D02*
X1102084Y190401D01*
G01X1034073Y175903D02*
X1102145Y189444D01*
G01X1035385Y189857D02*
X1036409Y187291D01*
G01X1034648Y189138D02*
X1035380Y187304D01*
G01X1036409Y187291D02*
X1034751Y183423D01*
G01X1035380Y187304D02*
X1033722Y183436D01*
G01X1034751Y183423D02*
X1034987Y182833D01*
G01X1033722Y183436D02*
X1034250Y182114D01*
G01X1034987Y182833D02*
X1037149Y181906D01*
G01X1034250Y182114D02*
X1037136Y180877D01*
G01X1037149Y181906D02*
X1037739Y182142D01*
G01X1037136Y180877D02*
X1038458Y181405D01*
G01X1037739Y182142D02*
X1039397Y186010D01*
G01X1038458Y181405D02*
X1040116Y185273D01*
G01X1039397Y186010D02*
X1040717Y186538D01*
G01X1040116Y185273D02*
X1040704Y185509D01*
G01X1040717Y186538D02*
X1047380Y183682D01*
G01X1040704Y185509D02*
X1047277Y182692D01*
G01X1047380Y183682D02*
X1098337Y193875D01*
G01X1047277Y182692D02*
X1108512Y194940D01*
G01X1033497Y178621D02*
X1033750Y177268D01*
G01D02*
X1034276Y176913D01*
G01X1034073Y175903D02*
X1102145Y189444D01*
G01X1034276Y176913D02*
X1102084Y190401D01*
G01X1092927Y210310D02*
X1095452Y210816D01*
G01Y209847D02*
X1093500Y209455D01*
G01X1091374Y207982D02*
X1092927Y210310D01*
G01X1093500Y209455D02*
X1092383Y207782D01*
G01X1092175Y203975D02*
X1091374Y207982D01*
G01X1092383Y207782D02*
X1093184Y203776D01*
G01X1091823Y203445D02*
X1092175Y203975D01*
G01X1093184Y203776D02*
X1092397Y202590D01*
G01X1089519Y202983D02*
X1091823Y203445D01*
G01X1092397Y202590D02*
X1089321Y201974D01*
G01X1088989Y203335D02*
X1089519Y202983D01*
G01X1089321Y201974D02*
X1088134Y202761D01*
G01X1088242Y207069D02*
X1088989Y203335D01*
G01X1088134Y202761D02*
X1087387Y206496D01*
G01X1086448Y208266D02*
X1088242Y207069D01*
G01X1087387Y206496D02*
X1086062Y207381D01*
G01X1084169Y208810D02*
X1086448Y208266D01*
G01X1086062Y207381D02*
X1084332Y207794D01*
G01X1082958Y208065D02*
X1084169Y208810D01*
G01X1084332Y207794D02*
X1083791Y207462D01*
G01X1082125Y204568D02*
X1082958Y208065D01*
G01X1083791Y207462D02*
X1082958Y203965D01*
G01X1081584Y204235D02*
X1082125Y204568D01*
G01X1082958Y203965D02*
X1081747Y203219D01*
G01X1079296Y204781D02*
X1081584Y204235D01*
G01X1081747Y203219D02*
X1078693Y203948D01*
G01X1078963Y205322D02*
X1079296Y204781D01*
G01X1078693Y203948D02*
X1077947Y205159D01*
G01X1079796Y208819D02*
X1078963Y205322D01*
G01X1077947Y205159D02*
X1078780Y208656D01*
G01X1079051Y210029D02*
X1079796Y208819D01*
G01X1078780Y208656D02*
X1078448Y209196D01*
G01X1074768Y211049D02*
X1079051Y210029D01*
G01X1078448Y209196D02*
X1074942Y210030D01*
G01X1072991Y209906D02*
X1074768Y211049D01*
G01X1074942Y210030D02*
X1073686Y209222D01*
G01X1070689Y206204D02*
X1072991Y209906D01*
G01X1073686Y209222D02*
X1071457Y205638D01*
G01X1067785Y202852D02*
X1068397Y203558D01*
G01X1069806Y205184D02*
X1070689Y206204D01*
G01X1071457Y205638D02*
X1068401Y202110D01*
G01X1066526Y202116D02*
X1067785Y202852D01*
G01X1068401Y202110D02*
X1066868Y201215D01*
G01X1063566Y201524D02*
X1066526Y202116D01*
G01X1066868Y201215D02*
X1063566Y200555D01*
G01X1055970Y203042D02*
X1063566Y201524D01*
G01Y200555D02*
X1055970Y202073D01*
G01X1052536Y202356D02*
X1055970Y203042D01*
G01Y202073D02*
X1052907Y201461D01*
G01X1050319Y200878D02*
X1052536Y202356D01*
G01X1052907Y201461D02*
X1050690Y199983D01*
G01X1048588Y200532D02*
X1050319Y200878D01*
G01X1050690Y199983D02*
X1048588Y199563D01*
G01X1045791Y201091D02*
X1048588Y200532D01*
G01Y199563D02*
X1045791Y200122D01*
G01X1043122Y200593D02*
X1043305D01*
G01D02*
X1045791Y201091D01*
G01Y200122D02*
X1043400Y199643D01*
G01X1043122Y200593D02*
X1043305D01*
G01X1043400Y199643D02*
X1043027D01*
G01X1038891Y201440D02*
X1043122Y200593D01*
G01D02*
X1043305D01*
G01X1043027Y199643D02*
X1038520Y200545D01*
G01X1034487Y204376D02*
X1038891Y201440D01*
G01X1038520Y200545D02*
X1034116Y203481D01*
G01X1097541Y200133D02*
X1094254Y199476D01*
G01X1097341Y199124D02*
X1094827Y198621D01*
G01X1094254Y199476D02*
X1092832Y197343D01*
G01X1094827Y198621D02*
X1093405Y196488D01*
G01X1092832Y197343D02*
X1090846Y196946D01*
G01X1093405Y196488D02*
X1090645Y195937D01*
G01X1092832Y197343D02*
X1090846Y196946D01*
G01D02*
X1089875Y197597D01*
G01X1090645Y195937D02*
X1089674Y196587D01*
G01X1089875Y197597D02*
X1086407Y196903D01*
G01X1089674Y196587D02*
X1086980Y196048D01*
G01X1086407Y196903D02*
X1085800Y195993D01*
G01X1086980Y196048D02*
X1086373Y195138D01*
G01X1085800Y195993D02*
X1082050Y195242D01*
G01X1086373Y195138D02*
X1081850Y194233D01*
G01X1082050Y195242D02*
X1081523Y195594D01*
G01X1081850Y194233D02*
X1080668Y195022D01*
G01X1081523Y195594D02*
X1080649Y199966D01*
G01X1080668Y195022D02*
X1079794Y199394D01*
G01X1080649Y199966D02*
X1079465Y200756D01*
G01X1079794Y199394D02*
X1079265Y199747D01*
G01X1079465Y200756D02*
X1076388Y200141D01*
G01X1079265Y199747D02*
X1076960Y199286D01*
G01X1076388Y200141D02*
X1075598Y198957D01*
G01X1076960Y199286D02*
X1076607Y198757D01*
G01X1075598Y198957D02*
X1076471Y194585D01*
G01X1076607Y198757D02*
X1077480Y194385D01*
G01X1076471Y194585D02*
X1076118Y194057D01*
G01X1077480Y194385D02*
X1076691Y193202D01*
G01X1076118Y194057D02*
X1070776Y192992D01*
G01X1076690Y193201D02*
X1070576Y191983D01*
G01X1070776Y192992D02*
X1070247Y193345D01*
G01X1070576Y191983D02*
X1069392Y192773D01*
G01X1070247Y193345D02*
X1069408Y197542D01*
G01X1069392Y192773D02*
X1068553Y196970D01*
G01X1069408Y197542D02*
X1068226Y198331D01*
G01X1068553Y196970D02*
X1068026Y197322D01*
G01X1068226Y198331D02*
X1065142Y197714D01*
G01X1068026Y197322D02*
X1065715Y196859D01*
G01X1065142Y197714D02*
X1064353Y196531D01*
G01X1065715Y196859D02*
X1065362Y196331D01*
G01X1064353Y196531D02*
X1065191Y192334D01*
G01X1065362Y196331D02*
X1066200Y192134D01*
G01X1065191Y192334D02*
X1064838Y191805D01*
G01X1066200Y192134D02*
X1065410Y190950D01*
G01X1064838Y191805D02*
X1062532Y191344D01*
G01X1065410Y190950D02*
X1062332Y190335D01*
G01X1062532Y191344D02*
X1062003Y191697D01*
G01X1062332Y190335D02*
X1061148Y191125D01*
G01X1062003Y191697D02*
X1061119Y196119D01*
G01X1061148Y191125D02*
X1060311Y195311D01*
G01X1062003Y191697D02*
X1061119Y196119D01*
G01D02*
X1060877Y197327D01*
G01X1060311Y195311D02*
X1060022Y196755D01*
G01X1060877Y197327D02*
X1059696Y198116D01*
G01X1060022Y196755D02*
X1059496Y197107D01*
G01X1059696Y198116D02*
X1056612Y197499D01*
G01X1059496Y197107D02*
X1057185Y196644D01*
G01X1056612Y197499D02*
X1055823Y196316D01*
G01X1057185Y196644D02*
X1056832Y196116D01*
G01X1055823Y196316D02*
X1056737Y191737D01*
G01X1056832Y196116D02*
X1057545Y192545D01*
G01X1056737Y191737D02*
X1056947Y190686D01*
G01X1057545Y192545D02*
X1057956Y190486D01*
G01X1056947Y190686D02*
X1056594Y190157D01*
G01X1057956Y190486D02*
X1057166Y189302D01*
G01X1056594Y190157D02*
X1054288Y189696D01*
G01X1057166Y189302D02*
X1054088Y188687D01*
G01X1054288Y189696D02*
X1053759Y190049D01*
G01X1053847Y188847D02*
X1052904Y189477D01*
G01X1053759Y190049D02*
X1052515Y196274D01*
G01X1052904Y189477D02*
X1051660Y195702D01*
G01X1052515Y196274D02*
X1051333Y197063D01*
G01X1051660Y195702D02*
X1051133Y196054D01*
G01X1051333Y197063D02*
X1048249Y196446D01*
G01X1051133Y196054D02*
X1048822Y195591D01*
G01X1048249Y196446D02*
X1047460Y195263D01*
G01X1048822Y195591D02*
X1048469Y195063D01*
G01X1047460Y195263D02*
X1048703Y189038D01*
G01X1048469Y195063D02*
X1049712Y188838D01*
G01X1048703Y189038D02*
X1048350Y188509D01*
G01X1049712Y188838D02*
X1048922Y187654D01*
G01X1048350Y188509D02*
X1047063Y188252D01*
G01D02*
X1046639Y188242D01*
G01X1048922Y187654D02*
X1047168Y187304D01*
G01X1048350Y188509D02*
X1047063Y188252D01*
G01D02*
X1046639Y188242D01*
G01X1047168Y187304D02*
X1046437Y187286D01*
G01X1047063Y188252D02*
X1046639Y188242D01*
G01D02*
X1043825Y189566D01*
G01X1046437Y187286D02*
X1043318Y188754D01*
G01X1043825Y189566D02*
X1039654Y192914D01*
G01X1043318Y188754D02*
X1038752Y192419D01*
G01X1039654Y192914D02*
X1039585Y193544D01*
G01X1038752Y192419D02*
X1038597Y193834D01*
G01X1039585Y193544D02*
X1040131Y194222D01*
G01X1038597Y193834D02*
X1039143Y194511D01*
G01X1040131Y194222D02*
X1039911Y196232D01*
G01X1039143Y194511D02*
X1039009Y195737D01*
G01X1039911Y196232D02*
X1038123Y197668D01*
G01X1039009Y195737D02*
X1037835Y196680D01*
G01X1039911Y196232D02*
X1038123Y197668D01*
G01D02*
X1036114Y197448D01*
G01X1037835Y196680D02*
X1036608Y196546D01*
G01X1036114Y197448D02*
X1035567Y196769D01*
G01X1036608Y196546D02*
X1036063Y195867D01*
G01X1035567Y196769D02*
X1034053Y196603D01*
G01X1036063Y195867D02*
X1033765Y195615D01*
G01X1035567Y196769D02*
X1034053Y196603D01*
G01X1034648Y189138D02*
X1035380Y187304D01*
G01X1035385Y189857D02*
X1036409Y187291D01*
G01X1035380Y187304D02*
X1033722Y183436D01*
G01X1036409Y187291D02*
X1034751Y183423D01*
G01X1033722Y183436D02*
X1034250Y182114D01*
G01X1034751Y183423D02*
X1034987Y182833D01*
G01X1034250Y182114D02*
X1037136Y180877D01*
G01X1034987Y182833D02*
X1037149Y181906D01*
G01X1037136Y180877D02*
X1038458Y181405D01*
G01X1037149Y181906D02*
X1037739Y182142D01*
G01X1038458Y181405D02*
X1040116Y185273D01*
G01X1037739Y182142D02*
X1039397Y186010D01*
G01X1040116Y185273D02*
X1040704Y185509D01*
G01X1039397Y186010D02*
X1040717Y186538D01*
G01X1040704Y185509D02*
X1047277Y182692D01*
G01X1040717Y186538D02*
X1047380Y183682D01*
G01X1047277Y182692D02*
X1108512Y194940D01*
G01X1047380Y183682D02*
X1098337Y193875D01*
G01X1047277Y182692D02*
X1108512Y194940D01*
G01X1038520Y200545D02*
X1034116Y203481D01*
G01X1034487Y204376D02*
X1038891Y201440D01*
G01X1043027Y199643D02*
X1038520Y200545D01*
G01X1038891Y201440D02*
X1043122Y200593D01*
G01X1045791Y200122D02*
X1043400Y199643D01*
G01D02*
X1043027D01*
G01D02*
X1038520Y200545D01*
G01X1043122Y200593D02*
X1043305D01*
G01X1045791Y200122D02*
X1043400Y199643D01*
G01X1043305Y200593D02*
X1045791Y201091D01*
G01X1048588Y199563D02*
X1045791Y200122D01*
G01Y201091D02*
X1048588Y200532D01*
G01X1050690Y199983D02*
X1048588Y199563D01*
G01Y200532D02*
X1050319Y200878D01*
G01X1052907Y201461D02*
X1050690Y199983D01*
G01X1050319Y200878D02*
X1052536Y202356D01*
G01X1055970Y202073D02*
X1052907Y201461D01*
G01X1052536Y202356D02*
X1055970Y203042D01*
G01X1063566Y200555D02*
X1055970Y202073D01*
G01Y203042D02*
X1063566Y201524D01*
G01X1066868Y201215D02*
X1063566Y200555D01*
G01Y201524D02*
X1066526Y202116D01*
G01X1068401Y202110D02*
X1066868Y201215D01*
G01X1066526Y202116D02*
X1067785Y202852D01*
G01X1071457Y205638D02*
X1068401Y202110D01*
G01X1067785Y202852D02*
X1068397Y203558D01*
G01X1071457Y205638D02*
X1068401Y202110D01*
G01X1069806Y205184D02*
X1070689Y206204D01*
G01X1073686Y209222D02*
X1071457Y205638D01*
G01X1070689Y206204D02*
X1072991Y209906D01*
G01X1074942Y210030D02*
X1073686Y209222D01*
G01X1072991Y209906D02*
X1074768Y211049D01*
G01X1078448Y209196D02*
X1074942Y210030D01*
G01X1074768Y211049D02*
X1079051Y210029D01*
G01X1078780Y208656D02*
X1078448Y209196D01*
G01X1079051Y210029D02*
X1079796Y208819D01*
G01X1077947Y205159D02*
X1078780Y208656D01*
G01X1079796Y208819D02*
X1078963Y205322D01*
G01X1078693Y203948D02*
X1077947Y205159D01*
G01X1078963Y205322D02*
X1079296Y204781D01*
G01X1081747Y203219D02*
X1078693Y203948D01*
G01X1079296Y204781D02*
X1081584Y204235D01*
G01X1082958Y203965D02*
X1081747Y203219D01*
G01X1081584Y204235D02*
X1082125Y204568D01*
G01X1083791Y207462D02*
X1082958Y203965D01*
G01X1082125Y204568D02*
X1082958Y208065D01*
G01X1084332Y207794D02*
X1083791Y207462D01*
G01X1082958Y208065D02*
X1084169Y208810D01*
G01X1086062Y207381D02*
X1084332Y207794D01*
G01X1084169Y208810D02*
X1086448Y208266D01*
G01X1087387Y206496D02*
X1086062Y207381D01*
G01X1086448Y208266D02*
X1088242Y207069D01*
G01X1088134Y202761D02*
X1087387Y206496D01*
G01X1088242Y207069D02*
X1088989Y203335D01*
G01X1089321Y201974D02*
X1088134Y202761D01*
G01X1088989Y203335D02*
X1089519Y202983D01*
G01X1092397Y202590D02*
X1089321Y201974D01*
G01X1089519Y202983D02*
X1091823Y203445D01*
G01X1093184Y203776D02*
X1092397Y202590D01*
G01X1091823Y203445D02*
X1092175Y203975D01*
G01X1092383Y207782D02*
X1093184Y203776D01*
G01X1092175Y203975D02*
X1091374Y207982D01*
G01X1093500Y209455D02*
X1092383Y207782D01*
G01X1091374Y207982D02*
X1092927Y210310D01*
G01X1095452Y209847D02*
X1093500Y209455D01*
G01X1092927Y210310D02*
X1095452Y210816D01*
G01X1097341Y199124D02*
X1094827Y198621D01*
G01X1097541Y200133D02*
X1094254Y199476D01*
G01X1094827Y198621D02*
X1093405Y196488D01*
G01X1094254Y199476D02*
X1092832Y197343D01*
G01X1093405Y196488D02*
X1090645Y195937D01*
G01D02*
X1089674Y196587D01*
G01X1092832Y197343D02*
X1090846Y196946D01*
G01X1090645Y195937D02*
X1089674Y196587D01*
G01X1090846Y196946D02*
X1089875Y197597D01*
G01X1089674Y196587D02*
X1086980Y196048D01*
G01X1089875Y197597D02*
X1086407Y196903D01*
G01X1086980Y196048D02*
X1086373Y195138D01*
G01X1086407Y196903D02*
X1085800Y195993D01*
G01X1086373Y195138D02*
X1081850Y194233D01*
G01X1085800Y195993D02*
X1082050Y195242D01*
G01X1081850Y194233D02*
X1080668Y195022D01*
G01X1082050Y195242D02*
X1081523Y195594D01*
G01X1080668Y195022D02*
X1079794Y199394D01*
G01X1081523Y195594D02*
X1080649Y199966D01*
G01X1079794Y199394D02*
X1079265Y199747D01*
G01X1080649Y199966D02*
X1079465Y200756D01*
G01X1079265Y199747D02*
X1076960Y199286D01*
G01X1079465Y200756D02*
X1076388Y200141D01*
G01X1076960Y199286D02*
X1076607Y198757D01*
G01X1076388Y200141D02*
X1075598Y198957D01*
G01X1076607Y198757D02*
X1077480Y194385D01*
G01X1075598Y198957D02*
X1076471Y194585D01*
G01X1077480Y194385D02*
X1076691Y193202D01*
G01X1076471Y194585D02*
X1076118Y194057D01*
G01X1076690Y193201D02*
X1070576Y191983D01*
G01X1076118Y194057D02*
X1070776Y192992D01*
G01X1070576Y191983D02*
X1069392Y192773D01*
G01X1070776Y192992D02*
X1070247Y193345D01*
G01X1069392Y192773D02*
X1068553Y196970D01*
G01X1070247Y193345D02*
X1069408Y197542D01*
G01X1068553Y196970D02*
X1068026Y197322D01*
G01X1069408Y197542D02*
X1068226Y198331D01*
G01X1068026Y197322D02*
X1065715Y196859D01*
G01X1068226Y198331D02*
X1065142Y197714D01*
G01X1065715Y196859D02*
X1065362Y196331D01*
G01X1065142Y197714D02*
X1064353Y196531D01*
G01X1065362Y196331D02*
X1066200Y192134D01*
G01X1064353Y196531D02*
X1065191Y192334D01*
G01X1066200Y192134D02*
X1065410Y190950D01*
G01X1065191Y192334D02*
X1064838Y191805D01*
G01X1065410Y190950D02*
X1062332Y190335D01*
G01X1064838Y191805D02*
X1062532Y191344D01*
G01X1062332Y190335D02*
X1061148Y191125D01*
G01X1062532Y191344D02*
X1062003Y191697D01*
G01X1061148Y191125D02*
X1060311Y195311D01*
G01D02*
X1060022Y196755D01*
G01X1062003Y191697D02*
X1061119Y196119D01*
G01X1060311Y195311D02*
X1060022Y196755D01*
G01X1061119Y196119D02*
X1060877Y197327D01*
G01X1060022Y196755D02*
X1059496Y197107D01*
G01X1060877Y197327D02*
X1059696Y198116D01*
G01X1059496Y197107D02*
X1057185Y196644D01*
G01X1059696Y198116D02*
X1056612Y197499D01*
G01X1057185Y196644D02*
X1056832Y196116D01*
G01X1056612Y197499D02*
X1055823Y196316D01*
G01X1056832Y196116D02*
X1057545Y192545D01*
G01X1055823Y196316D02*
X1056737Y191737D01*
G01X1057545Y192545D02*
X1057956Y190486D01*
G01X1056737Y191737D02*
X1056947Y190686D01*
G01X1057956Y190486D02*
X1057166Y189302D01*
G01X1056947Y190686D02*
X1056594Y190157D01*
G01X1057166Y189302D02*
X1054088Y188687D01*
G01X1056594Y190157D02*
X1054288Y189696D01*
G01X1053847Y188847D02*
X1052904Y189477D01*
G01X1054288Y189696D02*
X1053759Y190049D01*
G01X1052904Y189477D02*
X1051660Y195702D01*
G01X1053759Y190049D02*
X1052515Y196274D01*
G01X1051660Y195702D02*
X1051133Y196054D01*
G01X1052515Y196274D02*
X1051333Y197063D01*
G01X1051133Y196054D02*
X1048822Y195591D01*
G01X1051333Y197063D02*
X1048249Y196446D01*
G01X1048822Y195591D02*
X1048469Y195063D01*
G01X1048249Y196446D02*
X1047460Y195263D01*
G01X1048469Y195063D02*
X1049712Y188838D01*
G01X1047460Y195263D02*
X1048703Y189038D01*
G01X1049712Y188838D02*
X1048922Y187654D01*
G01X1048703Y189038D02*
X1048350Y188509D01*
G01X1048922Y187654D02*
X1047168Y187304D01*
G01D02*
X1046437Y187286D01*
G01X1048350Y188509D02*
X1047063Y188252D01*
G01X1048922Y187654D02*
X1047168Y187304D01*
G01D02*
X1046437Y187286D01*
G01D02*
X1043318Y188754D01*
G01X1047063Y188252D02*
X1046639Y188242D01*
G01X1046437Y187286D02*
X1043318Y188754D01*
G01X1046639Y188242D02*
X1043825Y189566D01*
G01X1043318Y188754D02*
X1038752Y192419D01*
G01X1043825Y189566D02*
X1039654Y192914D01*
G01X1038752Y192419D02*
X1038597Y193834D01*
G01X1039654Y192914D02*
X1039585Y193544D01*
G01X1038597Y193834D02*
X1039143Y194511D01*
G01X1039585Y193544D02*
X1040131Y194222D01*
G01X1039143Y194511D02*
X1039009Y195737D01*
G01X1040131Y194222D02*
X1039911Y196232D01*
G01X1039009Y195737D02*
X1037835Y196680D01*
G01D02*
X1036608Y196546D01*
G01X1039911Y196232D02*
X1038123Y197668D01*
G01X1037835Y196680D02*
X1036608Y196546D01*
G01X1038123Y197668D02*
X1036114Y197448D01*
G01X1036608Y196546D02*
X1036063Y195867D01*
G01X1036114Y197448D02*
X1035567Y196769D01*
G01X1036063Y195867D02*
X1033765Y195615D01*
G01X1035567Y196769D02*
X1034053Y196603D01*
G01X1092927Y210310D02*
X1095452Y210816D01*
G01Y209847D02*
X1093500Y209455D01*
G01X1091374Y207982D02*
X1092927Y210310D01*
G01X1093500Y209455D02*
X1092383Y207782D01*
G01X1092175Y203975D02*
X1091374Y207982D01*
G01X1092383Y207782D02*
X1093184Y203776D01*
G01X1091823Y203445D02*
X1092175Y203975D01*
G01X1093184Y203776D02*
X1092397Y202590D01*
G01X1089519Y202983D02*
X1091823Y203445D01*
G01X1092397Y202590D02*
X1089321Y201974D01*
G01X1088989Y203335D02*
X1089519Y202983D01*
G01X1089321Y201974D02*
X1088134Y202761D01*
G01X1088242Y207069D02*
X1088989Y203335D01*
G01X1088134Y202761D02*
X1087387Y206496D01*
G01X1086448Y208266D02*
X1088242Y207069D01*
G01X1087387Y206496D02*
X1086062Y207381D01*
G01X1084169Y208810D02*
X1086448Y208266D01*
G01X1086062Y207381D02*
X1084332Y207794D01*
G01X1082958Y208065D02*
X1084169Y208810D01*
G01X1084332Y207794D02*
X1083791Y207462D01*
G01X1082125Y204568D02*
X1082958Y208065D01*
G01X1083791Y207462D02*
X1082958Y203965D01*
G01X1081584Y204235D02*
X1082125Y204568D01*
G01X1082958Y203965D02*
X1081747Y203219D01*
G01X1079296Y204781D02*
X1081584Y204235D01*
G01X1081747Y203219D02*
X1078693Y203948D01*
G01X1078963Y205322D02*
X1079296Y204781D01*
G01X1078693Y203948D02*
X1077947Y205159D01*
G01X1079796Y208819D02*
X1078963Y205322D01*
G01X1077947Y205159D02*
X1078780Y208656D01*
G01X1079051Y210029D02*
X1079796Y208819D01*
G01X1078780Y208656D02*
X1078448Y209196D01*
G01X1074768Y211049D02*
X1079051Y210029D01*
G01X1078448Y209196D02*
X1074942Y210030D01*
G01X1072991Y209906D02*
X1074768Y211049D01*
G01X1074942Y210030D02*
X1073686Y209222D01*
G01X1070689Y206204D02*
X1072991Y209906D01*
G01X1073686Y209222D02*
X1071457Y205638D01*
G01X1067785Y202852D02*
X1068397Y203558D01*
G01X1069806Y205184D02*
X1070689Y206204D01*
G01X1071457Y205638D02*
X1068401Y202110D01*
G01X1066526Y202116D02*
X1067785Y202852D01*
G01X1068401Y202110D02*
X1066868Y201215D01*
G01X1063566Y201524D02*
X1066526Y202116D01*
G01X1066868Y201215D02*
X1063566Y200555D01*
G01X1055970Y203042D02*
X1063566Y201524D01*
G01Y200555D02*
X1055970Y202073D01*
G01X1052536Y202356D02*
X1055970Y203042D01*
G01Y202073D02*
X1052907Y201461D01*
G01X1050319Y200878D02*
X1052536Y202356D01*
G01X1052907Y201461D02*
X1050690Y199983D01*
G01X1048588Y200532D02*
X1050319Y200878D01*
G01X1050690Y199983D02*
X1048588Y199563D01*
G01X1045791Y201091D02*
X1048588Y200532D01*
G01Y199563D02*
X1045791Y200122D01*
G01X1043122Y200593D02*
X1043305D01*
G01D02*
X1045791Y201091D01*
G01Y200122D02*
X1043400Y199643D01*
G01X1043122Y200593D02*
X1043305D01*
G01X1043400Y199643D02*
X1043027D01*
G01X1038891Y201440D02*
X1043122Y200593D01*
G01D02*
X1043305D01*
G01X1043027Y199643D02*
X1038520Y200545D01*
G01X1034487Y204376D02*
X1038891Y201440D01*
G01X1038520Y200545D02*
X1034116Y203481D01*
G01X1033497Y178621D02*
X1033750Y177268D01*
G01D02*
X1034276Y176913D01*
G01D02*
X1102084Y190401D01*
G01X1034073Y175903D02*
X1102145Y189444D01*
G01X1097341Y199124D02*
X1094827Y198621D01*
G01X1097541Y200133D02*
X1094254Y199476D01*
G01X1094827Y198621D02*
X1093405Y196488D01*
G01X1094254Y199476D02*
X1092832Y197343D01*
G01X1093405Y196488D02*
X1090645Y195937D01*
G01D02*
X1089674Y196587D01*
G01X1092832Y197343D02*
X1090846Y196946D01*
G01X1090645Y195937D02*
X1089674Y196587D01*
G01X1090846Y196946D02*
X1089875Y197597D01*
G01X1089674Y196587D02*
X1086980Y196048D01*
G01X1089875Y197597D02*
X1086407Y196903D01*
G01X1086980Y196048D02*
X1086373Y195138D01*
G01X1086407Y196903D02*
X1085800Y195993D01*
G01X1086373Y195138D02*
X1081850Y194233D01*
G01X1085800Y195993D02*
X1082050Y195242D01*
G01X1081850Y194233D02*
X1080668Y195022D01*
G01X1082050Y195242D02*
X1081523Y195594D01*
G01X1080668Y195022D02*
X1079794Y199394D01*
G01X1081523Y195594D02*
X1080649Y199966D01*
G01X1079794Y199394D02*
X1079265Y199747D01*
G01X1080649Y199966D02*
X1079465Y200756D01*
G01X1079265Y199747D02*
X1076960Y199286D01*
G01X1079465Y200756D02*
X1076388Y200141D01*
G01X1076960Y199286D02*
X1076607Y198757D01*
G01X1076388Y200141D02*
X1075598Y198957D01*
G01X1076607Y198757D02*
X1077480Y194385D01*
G01X1075598Y198957D02*
X1076471Y194585D01*
G01X1077480Y194385D02*
X1076691Y193202D01*
G01X1076471Y194585D02*
X1076118Y194057D01*
G01X1076690Y193201D02*
X1070576Y191983D01*
G01X1076118Y194057D02*
X1070776Y192992D01*
G01X1070576Y191983D02*
X1069392Y192773D01*
G01X1070776Y192992D02*
X1070247Y193345D01*
G01X1069392Y192773D02*
X1068553Y196970D01*
G01X1070247Y193345D02*
X1069408Y197542D01*
G01X1068553Y196970D02*
X1068026Y197322D01*
G01X1069408Y197542D02*
X1068226Y198331D01*
G01X1068026Y197322D02*
X1065715Y196859D01*
G01X1068226Y198331D02*
X1065142Y197714D01*
G01X1065715Y196859D02*
X1065362Y196331D01*
G01X1065142Y197714D02*
X1064353Y196531D01*
G01X1065362Y196331D02*
X1066200Y192134D01*
G01X1064353Y196531D02*
X1065191Y192334D01*
G01X1066200Y192134D02*
X1065410Y190950D01*
G01X1065191Y192334D02*
X1064838Y191805D01*
G01X1065410Y190950D02*
X1062332Y190335D01*
G01X1064838Y191805D02*
X1062532Y191344D01*
G01X1062332Y190335D02*
X1061148Y191125D01*
G01X1062532Y191344D02*
X1062003Y191697D01*
G01X1061148Y191125D02*
X1060311Y195311D01*
G01D02*
X1060022Y196755D01*
G01X1062003Y191697D02*
X1061119Y196119D01*
G01X1060311Y195311D02*
X1060022Y196755D01*
G01X1061119Y196119D02*
X1060877Y197327D01*
G01X1060022Y196755D02*
X1059496Y197107D01*
G01X1060877Y197327D02*
X1059696Y198116D01*
G01X1059496Y197107D02*
X1057185Y196644D01*
G01X1059696Y198116D02*
X1056612Y197499D01*
G01X1057185Y196644D02*
X1056832Y196116D01*
G01X1056612Y197499D02*
X1055823Y196316D01*
G01X1056832Y196116D02*
X1057545Y192545D01*
G01X1055823Y196316D02*
X1056737Y191737D01*
G01X1057545Y192545D02*
X1057956Y190486D01*
G01X1056737Y191737D02*
X1056947Y190686D01*
G01X1057956Y190486D02*
X1057166Y189302D01*
G01X1056947Y190686D02*
X1056594Y190157D01*
G01X1057166Y189302D02*
X1054088Y188687D01*
G01X1056594Y190157D02*
X1054288Y189696D01*
G01X1053847Y188847D02*
X1052904Y189477D01*
G01X1054288Y189696D02*
X1053759Y190049D01*
G01X1052904Y189477D02*
X1051660Y195702D01*
G01X1053759Y190049D02*
X1052515Y196274D01*
G01X1051660Y195702D02*
X1051133Y196054D01*
G01X1052515Y196274D02*
X1051333Y197063D01*
G01X1051133Y196054D02*
X1048822Y195591D01*
G01X1051333Y197063D02*
X1048249Y196446D01*
G01X1048822Y195591D02*
X1048469Y195063D01*
G01X1048249Y196446D02*
X1047460Y195263D01*
G01X1048469Y195063D02*
X1049712Y188838D01*
G01X1047460Y195263D02*
X1048703Y189038D01*
G01X1049712Y188838D02*
X1048922Y187654D01*
G01X1048703Y189038D02*
X1048350Y188509D01*
G01X1048922Y187654D02*
X1047168Y187304D01*
G01D02*
X1046437Y187286D01*
G01X1048350Y188509D02*
X1047063Y188252D01*
G01X1048922Y187654D02*
X1047168Y187304D01*
G01D02*
X1046437Y187286D01*
G01D02*
X1043318Y188754D01*
G01X1047063Y188252D02*
X1046639Y188242D01*
G01X1046437Y187286D02*
X1043318Y188754D01*
G01X1046639Y188242D02*
X1043825Y189566D01*
G01X1043318Y188754D02*
X1038752Y192419D01*
G01X1043825Y189566D02*
X1039654Y192914D01*
G01X1038752Y192419D02*
X1038597Y193834D01*
G01X1039654Y192914D02*
X1039585Y193544D01*
G01X1038597Y193834D02*
X1039143Y194511D01*
G01X1039585Y193544D02*
X1040131Y194222D01*
G01X1039143Y194511D02*
X1039009Y195737D01*
G01X1040131Y194222D02*
X1039911Y196232D01*
G01X1039009Y195737D02*
X1037835Y196680D01*
G01D02*
X1036608Y196546D01*
G01X1039911Y196232D02*
X1038123Y197668D01*
G01X1037835Y196680D02*
X1036608Y196546D01*
G01X1038123Y197668D02*
X1036114Y197448D01*
G01X1036608Y196546D02*
X1036063Y195867D01*
G01X1036114Y197448D02*
X1035567Y196769D01*
G01X1036063Y195867D02*
X1033765Y195615D01*
G01X1035567Y196769D02*
X1034053Y196603D01*
G01X1035040Y448916D02*
X1114911Y457025D01*
G01X1035032Y447960D02*
X1114865Y456065D01*
G01X1035040Y451790D02*
X1115182Y459929D01*
G01X1115228Y460889D02*
X1035048Y452746D01*
G01X1115806Y464776D02*
X1035622Y456636D01*
G01X1115760Y463816D02*
X1035615Y455680D01*
G01X1116128Y467685D02*
X1035650Y459512D01*
G01X1116174Y468645D02*
X1035657Y460468D01*
G01X1035686Y464301D02*
X1118164Y472680D01*
G01X1035679Y463345D02*
X1118118Y471720D01*
G01X1056097Y415707D02*
X1056100D01*
G01D02*
X1098672Y419998D01*
G01X1093043Y423019D02*
X1093044D01*
G01D02*
X1099540Y423673D01*
G01X1035027Y444130D02*
X1114546Y452200D01*
G01X1035034Y445086D02*
X1114592Y453160D01*
G01X1035032Y447960D02*
X1114865Y456065D01*
G01X1035040Y448916D02*
X1114911Y457025D01*
G01X1035032Y447960D02*
X1114865Y456065D01*
G01X1035040Y448916D02*
X1114911Y457025D01*
G01X1115228Y460889D02*
X1035048Y452746D01*
G01X1035040Y451790D02*
X1115182Y459929D01*
G01X1115760Y463816D02*
X1035615Y455680D01*
G01X1115806Y464776D02*
X1035622Y456636D01*
G01X1116174Y468645D02*
X1035657Y460468D01*
G01X1116128Y467685D02*
X1035650Y459512D01*
G01X1035679Y463345D02*
X1118118Y471720D01*
G01X1035686Y464301D02*
X1118164Y472680D01*
G01X1056097Y415707D02*
X1056100D01*
G01D02*
X1098672Y419998D01*
G01X1056097Y415707D02*
X1056100D01*
G01D02*
X1098672Y419998D01*
G01X1093043Y423019D02*
X1093044D01*
G01D02*
X1099540Y423673D01*
G01X1035034Y445086D02*
X1114592Y453160D01*
G01X1035027Y444130D02*
X1114546Y452200D01*
G01X1035679Y463345D02*
X1118118Y471720D01*
G01X1035686Y464301D02*
X1118164Y472680D01*
G01X1035040Y451790D02*
X1115182Y459929D01*
G01X1115228Y460889D02*
X1035048Y452746D01*
G01X1116128Y467685D02*
X1035650Y459512D01*
G01X1116174Y468645D02*
X1035657Y460468D01*
G01X1115760Y463816D02*
X1035615Y455680D01*
G01X1115806Y464776D02*
X1035622Y456636D01*
G01X1035027Y444130D02*
X1114546Y452200D01*
G01X1035034Y445086D02*
X1114592Y453160D01*
G01X1093043Y423019D02*
X1093044D01*
G01D02*
X1099540Y423673D01*
G01X1093043Y423019D02*
X1093044D01*
G01D02*
X1099540Y423673D01*
G01X1035709Y467178D02*
X1118685Y475606D01*
G01X1035716Y468134D02*
X1118731Y476566D01*
G01X1119354Y480462D02*
X1035715Y471965D01*
G01X1035707Y471009D02*
X1119308Y479502D01*
G01X1035716Y468134D02*
X1118731Y476566D01*
G01X1035709Y467178D02*
X1118685Y475606D01*
G01X1035707Y471009D02*
X1119308Y479502D01*
G01X1119354Y480462D02*
X1035715Y471965D01*
G01X1035740Y475798D02*
X1119581Y484315D01*
G01X1035732Y474842D02*
X1119535Y483355D01*
G01X1035740Y475798D02*
X1119581Y484315D01*
G01X1035732Y474842D02*
X1119535Y483355D01*
G01X1035740Y478671D02*
X1119920Y487226D01*
G01X1035748Y479627D02*
X1119966Y488186D01*
G01X1036333Y482561D02*
X1120528Y491119D01*
G01X1036340Y483517D02*
X1120574Y492080D01*
G01X1035732Y474842D02*
X1119535Y483355D01*
G01X1035740Y475798D02*
X1119581Y484315D01*
G01X1035748Y479627D02*
X1119966Y488186D01*
G01X1035740Y478671D02*
X1119920Y487226D01*
G01X1036340Y483517D02*
X1120574Y492080D01*
G01X1036333Y482561D02*
X1120528Y491119D01*
G01X1035709Y467178D02*
X1118685Y475606D01*
G01X1035716Y468134D02*
X1118731Y476566D01*
G01X1119354Y480462D02*
X1035715Y471965D01*
G01X1035707Y471009D02*
X1119308Y479502D01*
G01X1103499Y-47131D02*
G02Y-50881I0J-1875D01*
G01X1103500Y-46181D02*
G02Y-51831I0J-2825D01*
G01Y-46181D02*
G02Y-51831I0J-2825D01*
G01X1103499Y-47131D02*
G02Y-50881I0J-1875D01*
G01X1103254Y125825D02*
X1150542Y116370D01*
G01X1103254Y126794D02*
X1150542Y117339D01*
G01Y116370D02*
X1176273Y121514D01*
G01X1150542Y117339D02*
X1175868Y122402D01*
G01X1103233Y130761D02*
X1138138Y123780D01*
G01X1103233Y129792D02*
X1137941Y122850D01*
G01X1138138Y123780D02*
X1149470Y121250D01*
G01X1137941Y122850D02*
X1149470Y120276D01*
G01Y121250D02*
X1174469Y126811D01*
G01X1149470Y120276D02*
X1174891Y125931D01*
G01X1103254Y126794D02*
X1150542Y117339D01*
G01X1103254Y125825D02*
X1150542Y116370D01*
G01Y117339D02*
X1175868Y122402D01*
G01X1150542Y116370D02*
X1176273Y121514D01*
G01X1103233Y129792D02*
X1137941Y122850D01*
G01X1103233Y130761D02*
X1138138Y123780D01*
G01X1137941Y122850D02*
X1149470Y120276D01*
G01X1138138Y123780D02*
X1149470Y121250D01*
G01Y120276D02*
X1174891Y125931D01*
G01X1149470Y121250D02*
X1174469Y126811D01*
G01X1103436Y134699D02*
X1149461Y125494D01*
G01X1103436Y133730D02*
X1149478Y124521D01*
G01X1149461Y125494D02*
X1172796Y131032D01*
G01X1149478Y124521D02*
X1173227Y130157D01*
G01X1102116Y149555D02*
X1146759Y140624D01*
G01X1102116Y150524D02*
X1146715Y141602D01*
G01X1146759Y140624D02*
X1163958Y145689D01*
G01X1146715Y141602D02*
X1163482Y146540D01*
G01X1140906Y138884D02*
X1102114Y146644D01*
G01Y145675D02*
X1140740Y137948D01*
G01X1146439Y138025D02*
X1140906Y138884D01*
G01X1140740Y137948D02*
X1146496Y137054D01*
G01X1166781Y143702D02*
X1146439Y138025D01*
G01X1146496Y137054D02*
X1167245Y142845D01*
G01X1103281Y142525D02*
X1147632Y133654D01*
G01X1103281Y141556D02*
X1147665Y132678D01*
G01X1147632Y133654D02*
X1167348Y139000D01*
G01X1147665Y132678D02*
X1168823Y138415D01*
G01X1103421Y137642D02*
X1148936Y128539D01*
G01X1103421Y138611D02*
X1148910Y129514D01*
G01X1148936Y128539D02*
X1171431Y134286D01*
G01X1148910Y129514D02*
X1159950Y132335D01*
G01X1148936Y128539D02*
X1171431Y134286D01*
G01X1148936Y128539D02*
X1171431Y134286D01*
G01X1103436Y133730D02*
X1149478Y124521D01*
G01X1103436Y134699D02*
X1149461Y125494D01*
G01X1149478Y124521D02*
X1173227Y130157D01*
G01X1149461Y125494D02*
X1172796Y131032D01*
G01X1103233Y129792D02*
X1137941Y122850D01*
G01X1103233Y130761D02*
X1138138Y123780D01*
G01X1137941Y122850D02*
X1149470Y120276D01*
G01X1138138Y123780D02*
X1149470Y121250D01*
G01Y120276D02*
X1174891Y125931D01*
G01X1149470Y121250D02*
X1174469Y126811D01*
G01X1102116Y150524D02*
X1146715Y141602D01*
G01X1102116Y149555D02*
X1146759Y140624D01*
G01X1146715Y141602D02*
X1163482Y146540D01*
G01X1146759Y140624D02*
X1163958Y145689D01*
G01X1146496Y137054D02*
X1167245Y142845D01*
G01X1166781Y143702D02*
X1146439Y138025D01*
G01X1140740Y137948D02*
X1146496Y137054D01*
G01X1146439Y138025D02*
X1140906Y138884D01*
G01X1102114Y145675D02*
X1140740Y137948D01*
G01X1140906Y138884D02*
X1102114Y146644D01*
G01X1103281Y141556D02*
X1147665Y132678D01*
G01X1103281Y142525D02*
X1147632Y133654D01*
G01X1147665Y132678D02*
X1168823Y138415D01*
G01X1147632Y133654D02*
X1167348Y139000D01*
G01X1147665Y132678D02*
X1168823Y138415D01*
G01X1147665Y132678D02*
X1168823Y138415D01*
G01X1103421Y138611D02*
X1148910Y129514D01*
G01X1103421Y137642D02*
X1148936Y128539D01*
G01X1148910Y129514D02*
X1159950Y132335D01*
G01X1148936Y128539D02*
X1171431Y134286D01*
G01X1102478Y162380D02*
X1149821Y152911D01*
G01X1102478Y161411D02*
X1149821Y151942D01*
G01Y152911D02*
X1154054Y153758D01*
G01X1149821Y151942D02*
X1154425Y152862D01*
G01X1154054Y153758D02*
X1156921Y155667D01*
G01X1154425Y152862D02*
X1157608Y154983D01*
G01X1156921Y155667D02*
X1160740Y161461D01*
G01X1129327Y151913D02*
X1129297Y151920D01*
G01D02*
X1102219Y157336D01*
G01Y158305D02*
X1129498Y152849D01*
G01X1147242Y148329D02*
X1129327Y151913D01*
G01D02*
X1129297Y151920D01*
G01D02*
X1102219Y157336D01*
G01X1129498Y152849D02*
X1129528Y152842D01*
G01X1147242Y148329D02*
X1129327Y151913D01*
G01D02*
X1129297Y151920D01*
G01D02*
X1102219Y157336D01*
G01X1129528Y152842D02*
X1130400Y152668D01*
G01X1147242Y148329D02*
X1129327Y151913D01*
G01X1130400Y152668D02*
X1147242Y149298D01*
G01X1155635Y150008D02*
X1147242Y148329D01*
G01Y149298D02*
X1155264Y150903D01*
G01X1160479Y153236D02*
X1155635Y150008D01*
G01X1155264Y150903D02*
X1159831Y153946D01*
G01X1147611Y145331D02*
X1160688Y149268D01*
G01X1161209Y148432D02*
X1147658Y144352D01*
G01X1102181Y154417D02*
X1147611Y145331D01*
G01X1147658Y144352D02*
X1129506Y147983D01*
G01X1102181Y154417D02*
X1147611Y145331D01*
G01X1129506Y147983D02*
X1129500Y147984D01*
G01X1102181Y154417D02*
X1147611Y145331D01*
G01X1129500Y147984D02*
X1129491Y147986D01*
G01X1102181Y154417D02*
X1147611Y145331D01*
G01X1129491Y147986D02*
X1129485Y147987D01*
G01X1102181Y154417D02*
X1147611Y145331D01*
G01X1129485Y147987D02*
X1102181Y153448D01*
G01X1102478Y161411D02*
X1149821Y151942D01*
G01X1102478Y162380D02*
X1149821Y152911D01*
G01Y151942D02*
X1154425Y152862D01*
G01X1149821Y152911D02*
X1154054Y153758D01*
G01X1154425Y152862D02*
X1157608Y154983D01*
G01X1154054Y153758D02*
X1156921Y155667D01*
G01D02*
X1160740Y161461D01*
G01X1155264Y150903D02*
X1159831Y153946D01*
G01X1160479Y153236D02*
X1155635Y150008D01*
G01X1147242Y149298D02*
X1155264Y150903D01*
G01X1155635Y150008D02*
X1147242Y148329D01*
G01X1129498Y152849D02*
X1129528Y152842D01*
G01D02*
X1130400Y152668D01*
G01D02*
X1147242Y149298D01*
G01Y148329D02*
X1129327Y151913D01*
G01X1102219Y158305D02*
X1129498Y152849D01*
G01D02*
X1129528Y152842D01*
G01D02*
X1130400Y152668D01*
G01X1129327Y151913D02*
X1129297Y151920D01*
G01X1102219Y158305D02*
X1129498Y152849D01*
G01D02*
X1129528Y152842D01*
G01D02*
X1130400Y152668D01*
G01X1129297Y151920D02*
X1102219Y157336D01*
G01X1147658Y144352D02*
X1129506Y147983D01*
G01D02*
X1129500Y147984D01*
G01D02*
X1129491Y147986D01*
G01D02*
X1129485Y147987D01*
G01D02*
X1102181Y153448D01*
G01Y154417D02*
X1147611Y145331D01*
G01X1161209Y148432D02*
X1147658Y144352D01*
G01X1147611Y145331D02*
X1160688Y149268D01*
G01X1140906Y138884D02*
X1102114Y146644D01*
G01Y145675D02*
X1140740Y137948D01*
G01X1146439Y138025D02*
X1140906Y138884D01*
G01X1140740Y137948D02*
X1146496Y137054D01*
G01X1166781Y143702D02*
X1146439Y138025D01*
G01X1146496Y137054D02*
X1167245Y142845D01*
G01X1103436Y133730D02*
X1149478Y124521D01*
G01X1103436Y134699D02*
X1149461Y125494D01*
G01X1149478Y124521D02*
X1173227Y130157D01*
G01X1149461Y125494D02*
X1172796Y131032D01*
G01X1129327Y151913D02*
X1129297Y151920D01*
G01D02*
X1102219Y157336D01*
G01Y158305D02*
X1129498Y152849D01*
G01X1147242Y148329D02*
X1129327Y151913D01*
G01D02*
X1129297Y151920D01*
G01D02*
X1102219Y157336D01*
G01X1129498Y152849D02*
X1129528Y152842D01*
G01X1147242Y148329D02*
X1129327Y151913D01*
G01D02*
X1129297Y151920D01*
G01D02*
X1102219Y157336D01*
G01X1129528Y152842D02*
X1130400Y152668D01*
G01X1147242Y148329D02*
X1129327Y151913D01*
G01X1130400Y152668D02*
X1147242Y149298D01*
G01X1155635Y150008D02*
X1147242Y148329D01*
G01Y149298D02*
X1155264Y150903D01*
G01X1160479Y153236D02*
X1155635Y150008D01*
G01X1155264Y150903D02*
X1159831Y153946D01*
G01X1103281Y142525D02*
X1147632Y133654D01*
G01X1103281Y141556D02*
X1147665Y132678D01*
G01X1147632Y133654D02*
X1167348Y139000D01*
G01X1147665Y132678D02*
X1168823Y138415D01*
G01X1147658Y144352D02*
X1129506Y147983D01*
G01D02*
X1129500Y147984D01*
G01D02*
X1129491Y147986D01*
G01D02*
X1129485Y147987D01*
G01D02*
X1102181Y153448D01*
G01Y154417D02*
X1147611Y145331D01*
G01X1161209Y148432D02*
X1147658Y144352D01*
G01X1147611Y145331D02*
X1160688Y149268D01*
G01X1102427Y181463D02*
X1130060Y179753D01*
G01X1102362Y182419D02*
X1129821Y180720D01*
G01X1130060Y179753D02*
X1143036Y187552D01*
G01X1129821Y180720D02*
X1142351Y188250D01*
G01X1143036Y187552D02*
X1143798Y188776D01*
G01X1142351Y188250D02*
X1142992Y189279D01*
G01X1143798Y188776D02*
X1151654Y198782D01*
G01X1143018Y189323D02*
X1148745Y196616D01*
G01X1143798Y188776D02*
X1151654Y198782D01*
G01X1150074Y198308D02*
X1150907Y199369D01*
G01X1099460Y177476D02*
X1102387Y178173D01*
G01X1099663Y176547D02*
X1102476Y177217D01*
G01X1102387Y178173D02*
X1129990Y176865D01*
G01X1102476Y177217D02*
X1130246Y175901D01*
G01X1129990Y176865D02*
X1130400Y177126D01*
G01D02*
X1141221Y184003D01*
G01X1130246Y175901D02*
X1141604Y183120D01*
G01X1141221Y184003D02*
X1143393Y184565D01*
G01X1141604Y183120D02*
X1143830Y183696D01*
G01X1143393Y184565D02*
X1147892Y188198D01*
G01X1143830Y183696D02*
X1148574Y187527D01*
G01X1147892Y188198D02*
X1151608Y192958D01*
G01X1148574Y187527D02*
X1152351Y192365D01*
G01X1151608Y192958D02*
X1156120Y198482D01*
G01X1152351Y192365D02*
X1159041Y200555D01*
G01X1100572Y172827D02*
X1100599Y172834D01*
G01D02*
X1102636Y173301D01*
G01X1100359Y173754D02*
X1100373Y173758D01*
G01X1100572Y172827D02*
X1100599Y172834D01*
G01D02*
X1102636Y173301D01*
G01X1100373Y173758D02*
X1102552Y174257D01*
G01X1102636Y173301D02*
X1130483Y171937D01*
G01X1102552Y174257D02*
X1130220Y172902D01*
G01X1130483Y171937D02*
X1142054Y179537D01*
G01X1130220Y172902D02*
X1141669Y180422D01*
G01X1142054Y179537D02*
X1144303Y180083D01*
G01X1144304Y180085D02*
X1146930Y180723D01*
G01X1141669Y180422D02*
X1146490Y181594D01*
G01X1146930Y180723D02*
X1153641Y186352D01*
G01X1146490Y181594D02*
X1152925Y186993D01*
G01X1153641Y186352D02*
X1156021Y189926D01*
G01X1152925Y186993D02*
X1157536Y193913D01*
G01X1156021Y189925D02*
X1162973Y200354D01*
G01X1156021Y189925D02*
X1162973Y200354D01*
G01X1103339Y169435D02*
X1130572Y168049D01*
G01X1103269Y170390D02*
X1130325Y169013D01*
G01X1130572Y168049D02*
X1131647Y168710D01*
G01X1130325Y169013D02*
X1130400Y169059D01*
G01X1130572Y168049D02*
X1131647Y168710D01*
G01D02*
X1143465Y176574D01*
G01X1130400Y169059D02*
X1131134Y169511D01*
G01X1131647Y168710D02*
X1143465Y176574D01*
G01X1131134Y169511D02*
X1143072Y177455D01*
G01X1143465Y176574D02*
X1149586Y178148D01*
G01X1143072Y177455D02*
X1149188Y179027D01*
G01X1149586Y178148D02*
X1159183Y184701D01*
G01X1149188Y179027D02*
X1158493Y185381D01*
G01X1156971Y178411D02*
X1156417Y178521D01*
G01X1155182Y177217D02*
X1154054Y176465D01*
G01X1164686Y182411D02*
X1154425Y175570D01*
G01X1154054Y176465D02*
X1152731Y176201D01*
G01X1150621Y175778D02*
X1144246Y174503D01*
G01X1154425Y175570D02*
X1144641Y173612D01*
G01X1144246Y174503D02*
X1131587Y165136D01*
G01X1144641Y173612D02*
X1131881Y164171D01*
G01X1131587Y165136D02*
X1103053Y166438D01*
G01X1131881Y164171D02*
X1103126Y165483D01*
G01X1102491Y186488D02*
X1109397Y186002D01*
G01X1111542Y185850D02*
X1117672Y185419D01*
G01X1119817Y185267D02*
X1122655Y185067D01*
G01X1124801Y184914D02*
X1126147Y184820D01*
G01X1128293Y184668D02*
X1129639Y184573D01*
G01X1102552Y185531D02*
X1129883Y183603D01*
G01X1128293Y184668D02*
X1129639Y184573D01*
G01D02*
X1138586Y190230D01*
G01X1129883Y183603D02*
X1130400Y183930D01*
G01X1129639Y184573D02*
X1138586Y190230D01*
G01X1130400Y183930D02*
X1139267Y189535D01*
G01X1138586Y190230D02*
X1141974Y195352D01*
G01X1139267Y189535D02*
X1142737Y194781D01*
G01X1141974Y195352D02*
X1147555Y201974D01*
G01X1142737Y194781D02*
X1148189Y201250D01*
G01X1147555Y201974D02*
X1148776Y202753D01*
G01X1150590Y203910D02*
X1151728Y204635D01*
G01X1148189Y201250D02*
X1152416Y203947D01*
G01X1151728Y204635D02*
X1152401Y205692D01*
G01X1152416Y203947D02*
X1153204Y205181D01*
G01X1102362Y182419D02*
X1129821Y180720D01*
G01X1102427Y181463D02*
X1130060Y179753D01*
G01X1129821Y180720D02*
X1142351Y188250D01*
G01X1130060Y179753D02*
X1143036Y187552D01*
G01X1142351Y188250D02*
X1142992Y189279D01*
G01X1143036Y187552D02*
X1143798Y188776D01*
G01X1143018Y189323D02*
X1148745Y196616D01*
G01X1150074Y198308D02*
X1150907Y199369D01*
G01X1143798Y188776D02*
X1151654Y198782D01*
G01X1099663Y176547D02*
X1102476Y177217D01*
G01X1099460Y177476D02*
X1102387Y178173D01*
G01X1102476Y177217D02*
X1130246Y175901D01*
G01X1102387Y178173D02*
X1129990Y176865D01*
G01X1130246Y175901D02*
X1141604Y183120D01*
G01X1129990Y176865D02*
X1130400Y177126D01*
G01X1130246Y175901D02*
X1141604Y183120D01*
G01X1130400Y177126D02*
X1141221Y184003D01*
G01X1141604Y183120D02*
X1143830Y183696D01*
G01X1141221Y184003D02*
X1143393Y184565D01*
G01X1143830Y183696D02*
X1148574Y187527D01*
G01X1143393Y184565D02*
X1147892Y188198D01*
G01X1148574Y187527D02*
X1152351Y192365D01*
G01X1147892Y188198D02*
X1151608Y192958D01*
G01X1152351Y192365D02*
X1159041Y200555D01*
G01X1151608Y192958D02*
X1156120Y198482D01*
G01X1152351Y192365D02*
X1159041Y200555D01*
G01X1100359Y173754D02*
X1100373Y173758D01*
G01D02*
X1102552Y174257D01*
G01X1100572Y172827D02*
X1100599Y172834D01*
G01X1100359Y173754D02*
X1100373Y173758D01*
G01D02*
X1102552Y174257D01*
G01X1100599Y172834D02*
X1102636Y173301D01*
G01X1102552Y174257D02*
X1130220Y172902D01*
G01X1102636Y173301D02*
X1130483Y171937D01*
G01X1130220Y172902D02*
X1141669Y180422D01*
G01X1130483Y171937D02*
X1142054Y179537D01*
G01X1141669Y180422D02*
X1146490Y181594D01*
G01X1142054Y179537D02*
X1144303Y180083D01*
G01X1141669Y180422D02*
X1146490Y181594D01*
G01X1144304Y180085D02*
X1146930Y180723D01*
G01X1146490Y181594D02*
X1152925Y186993D01*
G01X1146930Y180723D02*
X1153641Y186352D01*
G01X1152925Y186993D02*
X1157536Y193913D01*
G01X1153641Y186352D02*
X1156021Y189926D01*
G01Y189925D02*
X1162973Y200354D01*
G01X1103269Y170390D02*
X1130325Y169013D01*
G01X1103339Y169435D02*
X1130572Y168049D01*
G01X1130325Y169013D02*
X1130400Y169059D01*
G01D02*
X1131134Y169511D01*
G01X1130572Y168049D02*
X1131647Y168710D01*
G01X1130400Y169059D02*
X1131134Y169511D01*
G01D02*
X1143072Y177455D01*
G01X1131647Y168710D02*
X1143465Y176574D01*
G01X1143072Y177455D02*
X1149188Y179027D01*
G01X1143465Y176574D02*
X1149586Y178148D01*
G01X1149188Y179027D02*
X1158493Y185381D01*
G01X1149586Y178148D02*
X1159183Y184701D01*
G01X1164686Y182411D02*
X1154425Y175570D01*
G01X1164686Y182411D02*
X1154425Y175570D01*
G01X1164686Y182411D02*
X1154425Y175570D01*
G01X1164686Y182411D02*
X1154425Y175570D01*
G01X1164686Y182411D02*
X1154425Y175570D01*
G01X1164686Y182411D02*
X1154425Y175570D01*
G01X1156971Y178411D02*
X1156417Y178521D01*
G01X1164686Y182411D02*
X1154425Y175570D01*
G01X1155182Y177217D02*
X1154054Y176465D01*
G01X1154425Y175570D02*
X1144641Y173612D01*
G01X1154054Y176465D02*
X1152731Y176201D01*
G01X1154425Y175570D02*
X1144641Y173612D01*
G01X1150621Y175778D02*
X1144246Y174503D01*
G01X1144641Y173612D02*
X1131881Y164171D01*
G01X1144246Y174503D02*
X1131587Y165136D01*
G01X1131881Y164171D02*
X1103126Y165483D01*
G01X1131587Y165136D02*
X1103053Y166438D01*
G01X1102084Y190401D02*
X1108005Y189993D01*
G01X1102145Y189444D02*
X1108334Y189017D01*
G01X1108005Y189993D02*
X1108483Y190411D01*
G01X1108334Y189017D02*
X1109404Y189953D01*
G01X1108483Y190411D02*
X1108530Y191081D01*
G01X1109404Y189953D02*
X1109451Y190623D01*
G01X1108530Y191081D02*
X1109600Y192017D01*
G01X1109451Y190623D02*
X1109929Y191041D01*
G01X1109600Y192017D02*
X1112733Y191801D01*
G01X1109929Y191041D02*
X1112275Y190879D01*
G01X1112733Y191801D02*
X1113669Y190727D01*
G01X1112275Y190879D02*
X1112694Y190399D01*
G01X1113669Y190727D02*
X1113623Y190058D01*
G01X1112694Y190399D02*
X1112648Y189730D01*
G01X1113623Y190058D02*
X1114040Y189580D01*
G01X1112648Y189730D02*
X1113582Y188659D01*
G01X1114040Y189580D02*
X1116391Y189418D01*
G01X1113582Y188659D02*
X1116719Y188443D01*
G01X1116391Y189418D02*
X1117904Y190738D01*
G01X1116719Y188443D02*
X1118232Y189763D01*
G01X1116391Y189418D02*
X1117904Y190738D01*
G01D02*
X1120433Y190564D01*
G01X1118232Y189763D02*
X1119976Y189643D01*
G01X1120433Y190564D02*
X1121785Y189017D01*
G01X1119976Y189643D02*
X1121328Y188096D01*
G01X1121785Y189017D02*
X1125239Y188781D01*
G01X1127136Y188650D02*
X1128696Y188544D01*
G01X1121328Y188096D02*
X1128889Y187578D01*
G01X1128696Y188544D02*
X1130400Y189392D01*
G01D02*
X1130731Y189557D01*
G01X1132434Y190404D02*
X1133610Y190989D01*
G01X1128889Y187578D02*
X1134218Y190230D01*
G01X1133610Y190989D02*
X1139295Y197995D01*
G01X1134218Y190230D02*
X1134819Y190971D01*
G01X1133610Y190989D02*
X1139295Y197995D01*
G01X1134819Y190971D02*
X1140009Y197367D01*
G01X1139295Y197995D02*
X1146940Y206001D01*
G01D02*
X1146948Y206009D01*
G01X1140009Y197367D02*
X1147628Y205344D01*
G01X1146940Y206001D02*
X1146948Y206009D01*
G01X1146956Y206016D02*
X1148399Y207459D01*
G01X1147628Y205344D02*
X1149071Y206787D01*
G01X1102552Y185531D02*
X1129883Y183603D01*
G01X1102491Y186488D02*
X1109397Y186002D01*
G01X1102552Y185531D02*
X1129883Y183603D01*
G01X1111542Y185850D02*
X1117672Y185419D01*
G01X1102552Y185531D02*
X1129883Y183603D01*
G01X1119817Y185267D02*
X1122655Y185067D01*
G01X1102552Y185531D02*
X1129883Y183603D01*
G01X1124801Y184914D02*
X1126147Y184820D01*
G01X1102552Y185531D02*
X1129883Y183603D01*
G01D02*
X1130400Y183930D01*
G01X1128293Y184668D02*
X1129639Y184573D01*
G01X1129883Y183603D02*
X1130400Y183930D01*
G01D02*
X1139267Y189535D01*
G01X1129639Y184573D02*
X1138586Y190230D01*
G01X1139267Y189535D02*
X1142737Y194781D01*
G01X1138586Y190230D02*
X1141974Y195352D01*
G01X1142737Y194781D02*
X1148189Y201250D01*
G01X1141974Y195352D02*
X1147555Y201974D01*
G01X1148189Y201250D02*
X1152416Y203947D01*
G01X1147555Y201974D02*
X1148776Y202753D01*
G01X1148189Y201250D02*
X1152416Y203947D01*
G01X1150590Y203910D02*
X1151728Y204635D01*
G01X1152416Y203947D02*
X1153204Y205181D01*
G01X1151728Y204635D02*
X1152401Y205692D01*
G01X1099855Y194179D02*
X1108432Y195893D01*
G01D02*
X1117149Y195637D01*
G01X1108512Y194940D02*
X1117013Y194690D01*
G01X1117149Y195637D02*
X1118363Y195322D01*
G01X1119977Y194901D02*
X1120940Y194648D01*
G01X1122527Y194234D02*
X1123349Y194018D01*
G01X1117013Y194690D02*
X1123196Y193076D01*
G01X1123349Y194018D02*
X1128090Y193700D01*
G01X1123196Y193076D02*
X1128230Y192738D01*
G01X1128090Y193700D02*
X1131725Y195049D01*
G01X1128230Y192738D02*
X1132251Y194230D01*
G01X1131725Y195049D02*
X1141285Y204609D01*
G01Y204610D02*
X1142584Y205909D01*
G01X1132251Y194230D02*
X1143257Y205237D01*
G01X1102145Y189444D02*
X1108334Y189017D01*
G01X1102084Y190401D02*
X1108005Y189993D01*
G01X1108334Y189017D02*
X1109404Y189953D01*
G01X1108005Y189993D02*
X1108483Y190411D01*
G01X1109404Y189953D02*
X1109451Y190623D01*
G01X1108483Y190411D02*
X1108530Y191081D01*
G01X1109451Y190623D02*
X1109929Y191041D01*
G01X1108530Y191081D02*
X1109600Y192017D01*
G01X1109929Y191041D02*
X1112275Y190879D01*
G01X1109600Y192017D02*
X1112733Y191801D01*
G01X1112275Y190879D02*
X1112694Y190399D01*
G01X1112733Y191801D02*
X1113669Y190727D01*
G01X1112694Y190399D02*
X1112648Y189730D01*
G01X1113669Y190727D02*
X1113623Y190058D01*
G01X1112648Y189730D02*
X1113582Y188659D01*
G01X1113623Y190058D02*
X1114040Y189580D01*
G01X1113582Y188659D02*
X1116719Y188443D01*
G01X1114040Y189580D02*
X1116391Y189418D01*
G01X1116719Y188443D02*
X1118232Y189763D01*
G01D02*
X1119976Y189643D01*
G01X1116391Y189418D02*
X1117904Y190738D01*
G01X1118232Y189763D02*
X1119976Y189643D01*
G01X1117904Y190738D02*
X1120433Y190564D01*
G01X1119976Y189643D02*
X1121328Y188096D01*
G01X1120433Y190564D02*
X1121785Y189017D01*
G01X1121328Y188096D02*
X1128889Y187578D01*
G01X1121785Y189017D02*
X1125239Y188781D01*
G01X1121328Y188096D02*
X1128889Y187578D01*
G01X1127136Y188650D02*
X1128696Y188544D01*
G01X1128889Y187578D02*
X1134218Y190230D01*
G01X1128696Y188544D02*
X1130400Y189392D01*
G01X1128889Y187578D02*
X1134218Y190230D01*
G01X1130400Y189392D02*
X1130731Y189557D01*
G01X1128889Y187578D02*
X1134218Y190230D01*
G01X1132434Y190404D02*
X1133610Y190989D01*
G01X1134218Y190230D02*
X1134819Y190971D01*
G01D02*
X1140009Y197367D01*
G01X1133610Y190989D02*
X1139295Y197995D01*
G01X1140009Y197367D02*
X1147628Y205344D01*
G01X1139295Y197995D02*
X1146940Y206001D01*
G01X1140009Y197367D02*
X1147628Y205344D01*
G01D02*
X1149071Y206787D01*
G01X1146940Y206001D02*
X1146948Y206009D01*
G01X1147628Y205344D02*
X1149071Y206787D01*
G01X1146956Y206016D02*
X1148399Y207459D01*
G01X1127171Y208900D02*
X1128694D01*
G01X1128650Y207950D02*
X1127118D01*
G01X1123887Y208256D02*
X1124997Y209144D01*
G01D02*
X1127171Y208900D01*
G01X1127118Y207950D02*
X1125283Y208155D01*
G01X1123887Y208256D02*
X1124997Y209144D01*
G01X1125283Y208155D02*
X1124788Y207760D01*
G01X1123594Y205631D02*
X1123887Y208256D01*
G01X1124788Y207760D02*
X1124495Y205135D01*
G01X1123098Y205233D02*
X1123594Y205631D01*
G01X1124495Y205135D02*
X1123385Y204244D01*
G01X1120761Y205495D02*
X1123098Y205233D01*
G01X1123385Y204244D02*
X1120265Y204594D01*
G01X1120363Y205991D02*
X1120761Y205495D01*
G01X1120265Y204594D02*
X1119375Y205704D01*
G01X1120656Y208616D02*
X1120363Y205991D01*
G01X1119375Y205704D02*
X1119668Y208330D01*
G01X1119768Y209726D02*
X1120656Y208616D01*
G01X1119668Y208330D02*
X1119269Y208825D01*
G01X1111924Y210598D02*
X1116289Y210113D01*
G01X1118427Y209875D02*
X1119768Y209726D01*
G01X1119269Y208825D02*
X1111966Y209637D01*
G01X1104234Y209060D02*
X1108491Y209911D01*
G01X1110601Y210334D02*
X1111924Y210598D01*
G01X1111966Y209637D02*
X1104605Y208165D01*
G01X1103050Y208271D02*
X1104234Y209060D01*
G01X1104605Y208165D02*
X1103905Y207698D01*
G01X1102488Y205468D02*
X1103050Y208271D01*
G01X1103905Y207698D02*
X1103343Y204895D01*
G01X1101797Y205008D02*
X1102488Y205468D01*
G01X1103343Y204895D02*
X1101997Y203998D01*
G01X1099627Y205442D02*
X1101797Y205008D01*
G01X1101997Y203998D02*
X1099054Y204587D01*
G01X1099274Y205970D02*
X1099627Y205442D01*
G01X1099054Y204587D02*
X1098265Y205771D01*
G01X1099864Y208909D02*
X1099274Y205970D01*
G01X1098265Y205771D02*
X1098854Y208709D01*
G01X1099073Y210092D02*
X1099864Y208909D01*
G01X1098854Y208709D02*
X1098501Y209237D01*
G01X1095452Y210816D02*
X1099073Y210092D01*
G01X1098501Y209237D02*
X1095452Y209847D01*
G01X1135357Y204482D02*
X1130410Y199536D01*
G01X1136029Y203810D02*
X1130997Y198778D01*
G01X1130410Y199536D02*
X1130400Y199530D01*
G01D02*
X1127318Y197713D01*
G01X1130997Y198778D02*
X1127641Y196800D01*
G01X1127318Y197713D02*
X1125171Y197396D01*
G01X1127641Y196800D02*
X1125093Y196424D01*
G01X1125171Y197396D02*
X1123299Y197990D01*
G01X1125093Y196424D02*
X1122858Y197133D01*
G01X1123299Y197990D02*
X1122579Y198529D01*
G01X1121758Y199770D02*
X1121058Y199670D01*
G01D02*
X1120135Y200362D01*
G01X1119314Y201603D02*
X1118614Y201503D01*
G01D02*
X1116639Y202983D01*
G01X1122858Y197133D02*
X1116241Y202093D01*
G01X1116639Y202983D02*
X1109595Y204389D01*
G01X1116241Y202093D02*
X1109595Y203420D01*
G01Y204389D02*
X1107134Y203898D01*
G01X1109595Y203420D02*
X1107505Y203002D01*
G01X1107134Y203898D02*
X1100316Y199355D01*
G01X1107505Y203002D02*
X1100688Y198460D01*
G01X1100316Y199355D02*
X1099080Y199105D01*
G01X1100688Y198460D02*
X1098881Y198095D01*
G01X1099080Y199105D02*
X1097541Y200133D01*
G01X1098881Y198095D02*
X1097341Y199124D01*
G01X1099855Y194179D02*
X1108432Y195893D01*
G01X1108512Y194940D02*
X1117013Y194690D01*
G01X1108432Y195893D02*
X1117149Y195637D01*
G01X1117013Y194690D02*
X1123196Y193076D01*
G01X1117149Y195637D02*
X1118363Y195322D01*
G01X1117013Y194690D02*
X1123196Y193076D01*
G01X1119977Y194901D02*
X1120940Y194648D01*
G01X1117013Y194690D02*
X1123196Y193076D01*
G01X1122527Y194234D02*
X1123349Y194018D01*
G01X1123196Y193076D02*
X1128230Y192738D01*
G01X1123349Y194018D02*
X1128090Y193700D01*
G01X1128230Y192738D02*
X1132251Y194230D01*
G01X1128090Y193700D02*
X1131725Y195049D01*
G01X1132251Y194230D02*
X1143257Y205237D01*
G01X1131725Y195049D02*
X1141285Y204609D01*
G01X1132251Y194230D02*
X1143257Y205237D01*
G01X1141285Y204610D02*
X1142584Y205909D01*
G01X1098501Y209237D02*
X1095452Y209847D01*
G01Y210816D02*
X1099073Y210092D01*
G01X1098854Y208709D02*
X1098501Y209237D01*
G01X1099073Y210092D02*
X1099864Y208909D01*
G01X1098265Y205771D02*
X1098854Y208709D01*
G01X1099864Y208909D02*
X1099274Y205970D01*
G01X1099054Y204587D02*
X1098265Y205771D01*
G01X1099274Y205970D02*
X1099627Y205442D01*
G01X1101997Y203998D02*
X1099054Y204587D01*
G01X1099627Y205442D02*
X1101797Y205008D01*
G01X1103343Y204895D02*
X1101997Y203998D01*
G01X1101797Y205008D02*
X1102488Y205468D01*
G01X1103905Y207698D02*
X1103343Y204895D01*
G01X1102488Y205468D02*
X1103050Y208271D01*
G01X1104605Y208165D02*
X1103905Y207698D01*
G01X1103050Y208271D02*
X1104234Y209060D01*
G01X1111966Y209637D02*
X1104605Y208165D01*
G01X1104234Y209060D02*
X1108491Y209911D01*
G01X1111966Y209637D02*
X1104605Y208165D01*
G01X1110601Y210334D02*
X1111924Y210598D01*
G01X1119269Y208825D02*
X1111966Y209637D01*
G01X1111924Y210598D02*
X1116289Y210113D01*
G01X1119269Y208825D02*
X1111966Y209637D01*
G01X1118427Y209875D02*
X1119768Y209726D01*
G01X1119668Y208330D02*
X1119269Y208825D01*
G01X1119768Y209726D02*
X1120656Y208616D01*
G01X1119375Y205704D02*
X1119668Y208330D01*
G01X1120656Y208616D02*
X1120363Y205991D01*
G01X1120265Y204594D02*
X1119375Y205704D01*
G01X1120363Y205991D02*
X1120761Y205495D01*
G01X1123385Y204244D02*
X1120265Y204594D01*
G01X1120761Y205495D02*
X1123098Y205233D01*
G01X1124495Y205135D02*
X1123385Y204244D01*
G01X1123098Y205233D02*
X1123594Y205631D01*
G01X1124788Y207760D02*
X1124495Y205135D01*
G01X1123594Y205631D02*
X1123887Y208256D01*
G01X1127118Y207950D02*
X1125283Y208155D01*
G01D02*
X1124788Y207760D01*
G01X1123887Y208256D02*
X1124997Y209144D01*
G01X1127118Y207950D02*
X1125283Y208155D01*
G01X1124997Y209144D02*
X1127171Y208900D01*
G01X1128650Y207950D02*
X1127118D01*
G01X1127171Y208900D02*
X1128694D01*
G01X1136029Y203810D02*
X1130997Y198778D01*
G01X1135357Y204482D02*
X1130410Y199536D01*
G01X1130997Y198778D02*
X1127641Y196800D01*
G01X1130410Y199536D02*
X1130400Y199530D01*
G01X1130997Y198778D02*
X1127641Y196800D01*
G01X1130400Y199530D02*
X1127318Y197713D01*
G01X1127641Y196800D02*
X1125093Y196424D01*
G01X1127318Y197713D02*
X1125171Y197396D01*
G01X1125093Y196424D02*
X1122858Y197133D01*
G01X1125171Y197396D02*
X1123299Y197990D01*
G01X1122858Y197133D02*
X1116241Y202093D01*
G01X1123299Y197990D02*
X1122579Y198529D01*
G01X1122858Y197133D02*
X1116241Y202093D01*
G01X1121758Y199770D02*
X1121058Y199670D01*
G01X1122858Y197133D02*
X1116241Y202093D01*
G01X1121058Y199670D02*
X1120135Y200362D01*
G01X1122858Y197133D02*
X1116241Y202093D01*
G01X1119314Y201603D02*
X1118614Y201503D01*
G01X1122858Y197133D02*
X1116241Y202093D01*
G01X1118614Y201503D02*
X1116639Y202983D01*
G01X1116241Y202093D02*
X1109595Y203420D01*
G01X1116639Y202983D02*
X1109595Y204389D01*
G01Y203420D02*
X1107505Y203002D01*
G01X1109595Y204389D02*
X1107134Y203898D01*
G01X1107505Y203002D02*
X1100688Y198460D01*
G01X1107134Y203898D02*
X1100316Y199355D01*
G01X1100688Y198460D02*
X1098881Y198095D01*
G01X1100316Y199355D02*
X1099080Y199105D01*
G01X1098881Y198095D02*
X1097341Y199124D01*
G01X1099080Y199105D02*
X1097541Y200133D01*
G01X1156971Y178411D02*
X1156417Y178521D01*
G01X1155182Y177217D02*
X1154054Y176465D01*
G01X1164686Y182411D02*
X1154425Y175570D01*
G01X1154054Y176465D02*
X1152731Y176201D01*
G01X1150621Y175778D02*
X1144246Y174503D01*
G01X1154425Y175570D02*
X1144641Y173612D01*
G01X1144246Y174503D02*
X1131587Y165136D01*
G01X1144641Y173612D02*
X1131881Y164171D01*
G01X1131587Y165136D02*
X1103053Y166438D01*
G01X1131881Y164171D02*
X1103126Y165483D01*
G01X1127171Y208900D02*
X1128694D01*
G01X1128650Y207950D02*
X1127118D01*
G01X1123887Y208256D02*
X1124997Y209144D01*
G01D02*
X1127171Y208900D01*
G01X1127118Y207950D02*
X1125283Y208155D01*
G01X1123887Y208256D02*
X1124997Y209144D01*
G01X1125283Y208155D02*
X1124788Y207760D01*
G01X1123594Y205631D02*
X1123887Y208256D01*
G01X1124788Y207760D02*
X1124495Y205135D01*
G01X1123098Y205233D02*
X1123594Y205631D01*
G01X1124495Y205135D02*
X1123385Y204244D01*
G01X1120761Y205495D02*
X1123098Y205233D01*
G01X1123385Y204244D02*
X1120265Y204594D01*
G01X1120363Y205991D02*
X1120761Y205495D01*
G01X1120265Y204594D02*
X1119375Y205704D01*
G01X1120656Y208616D02*
X1120363Y205991D01*
G01X1119375Y205704D02*
X1119668Y208330D01*
G01X1119768Y209726D02*
X1120656Y208616D01*
G01X1119668Y208330D02*
X1119269Y208825D01*
G01X1111924Y210598D02*
X1116289Y210113D01*
G01X1118427Y209875D02*
X1119768Y209726D01*
G01X1119269Y208825D02*
X1111966Y209637D01*
G01X1104234Y209060D02*
X1108491Y209911D01*
G01X1110601Y210334D02*
X1111924Y210598D01*
G01X1111966Y209637D02*
X1104605Y208165D01*
G01X1103050Y208271D02*
X1104234Y209060D01*
G01X1104605Y208165D02*
X1103905Y207698D01*
G01X1102488Y205468D02*
X1103050Y208271D01*
G01X1103905Y207698D02*
X1103343Y204895D01*
G01X1101797Y205008D02*
X1102488Y205468D01*
G01X1103343Y204895D02*
X1101997Y203998D01*
G01X1099627Y205442D02*
X1101797Y205008D01*
G01X1101997Y203998D02*
X1099054Y204587D01*
G01X1099274Y205970D02*
X1099627Y205442D01*
G01X1099054Y204587D02*
X1098265Y205771D01*
G01X1099864Y208909D02*
X1099274Y205970D01*
G01X1098265Y205771D02*
X1098854Y208709D01*
G01X1099073Y210092D02*
X1099864Y208909D01*
G01X1098854Y208709D02*
X1098501Y209237D01*
G01X1095452Y210816D02*
X1099073Y210092D01*
G01X1098501Y209237D02*
X1095452Y209847D01*
G01X1102084Y190401D02*
X1108005Y189993D01*
G01X1102145Y189444D02*
X1108334Y189017D01*
G01X1108005Y189993D02*
X1108483Y190411D01*
G01X1108334Y189017D02*
X1109404Y189953D01*
G01X1108483Y190411D02*
X1108530Y191081D01*
G01X1109404Y189953D02*
X1109451Y190623D01*
G01X1108530Y191081D02*
X1109600Y192017D01*
G01X1109451Y190623D02*
X1109929Y191041D01*
G01X1109600Y192017D02*
X1112733Y191801D01*
G01X1109929Y191041D02*
X1112275Y190879D01*
G01X1112733Y191801D02*
X1113669Y190727D01*
G01X1112275Y190879D02*
X1112694Y190399D01*
G01X1113669Y190727D02*
X1113623Y190058D01*
G01X1112694Y190399D02*
X1112648Y189730D01*
G01X1113623Y190058D02*
X1114040Y189580D01*
G01X1112648Y189730D02*
X1113582Y188659D01*
G01X1114040Y189580D02*
X1116391Y189418D01*
G01X1113582Y188659D02*
X1116719Y188443D01*
G01X1116391Y189418D02*
X1117904Y190738D01*
G01X1116719Y188443D02*
X1118232Y189763D01*
G01X1116391Y189418D02*
X1117904Y190738D01*
G01D02*
X1120433Y190564D01*
G01X1118232Y189763D02*
X1119976Y189643D01*
G01X1120433Y190564D02*
X1121785Y189017D01*
G01X1119976Y189643D02*
X1121328Y188096D01*
G01X1121785Y189017D02*
X1125239Y188781D01*
G01X1127136Y188650D02*
X1128696Y188544D01*
G01X1121328Y188096D02*
X1128889Y187578D01*
G01X1128696Y188544D02*
X1130400Y189392D01*
G01D02*
X1130731Y189557D01*
G01X1132434Y190404D02*
X1133610Y190989D01*
G01X1128889Y187578D02*
X1134218Y190230D01*
G01X1133610Y190989D02*
X1139295Y197995D01*
G01X1134218Y190230D02*
X1134819Y190971D01*
G01X1133610Y190989D02*
X1139295Y197995D01*
G01X1134819Y190971D02*
X1140009Y197367D01*
G01X1139295Y197995D02*
X1146940Y206001D01*
G01D02*
X1146948Y206009D01*
G01X1140009Y197367D02*
X1147628Y205344D01*
G01X1146940Y206001D02*
X1146948Y206009D01*
G01X1146956Y206016D02*
X1148399Y207459D01*
G01X1147628Y205344D02*
X1149071Y206787D01*
G01X1102552Y185531D02*
X1129883Y183603D01*
G01X1102491Y186488D02*
X1109397Y186002D01*
G01X1102552Y185531D02*
X1129883Y183603D01*
G01X1111542Y185850D02*
X1117672Y185419D01*
G01X1102552Y185531D02*
X1129883Y183603D01*
G01X1119817Y185267D02*
X1122655Y185067D01*
G01X1102552Y185531D02*
X1129883Y183603D01*
G01X1124801Y184914D02*
X1126147Y184820D01*
G01X1102552Y185531D02*
X1129883Y183603D01*
G01D02*
X1130400Y183930D01*
G01X1128293Y184668D02*
X1129639Y184573D01*
G01X1129883Y183603D02*
X1130400Y183930D01*
G01D02*
X1139267Y189535D01*
G01X1129639Y184573D02*
X1138586Y190230D01*
G01X1139267Y189535D02*
X1142737Y194781D01*
G01X1138586Y190230D02*
X1141974Y195352D01*
G01X1142737Y194781D02*
X1148189Y201250D01*
G01X1141974Y195352D02*
X1147555Y201974D01*
G01X1148189Y201250D02*
X1152416Y203947D01*
G01X1147555Y201974D02*
X1148776Y202753D01*
G01X1148189Y201250D02*
X1152416Y203947D01*
G01X1150590Y203910D02*
X1151728Y204635D01*
G01X1152416Y203947D02*
X1153204Y205181D01*
G01X1151728Y204635D02*
X1152401Y205692D01*
G01X1099663Y176547D02*
X1102476Y177217D01*
G01X1099460Y177476D02*
X1102387Y178173D01*
G01X1102476Y177217D02*
X1130246Y175901D01*
G01X1102387Y178173D02*
X1129990Y176865D01*
G01X1130246Y175901D02*
X1141604Y183120D01*
G01X1129990Y176865D02*
X1130400Y177126D01*
G01X1130246Y175901D02*
X1141604Y183120D01*
G01X1130400Y177126D02*
X1141221Y184003D01*
G01X1141604Y183120D02*
X1143830Y183696D01*
G01X1141221Y184003D02*
X1143393Y184565D01*
G01X1143830Y183696D02*
X1148574Y187527D01*
G01X1143393Y184565D02*
X1147892Y188198D01*
G01X1148574Y187527D02*
X1152351Y192365D01*
G01X1147892Y188198D02*
X1151608Y192958D01*
G01X1152351Y192365D02*
X1159041Y200555D01*
G01X1151608Y192958D02*
X1156120Y198482D01*
G01X1152351Y192365D02*
X1159041Y200555D01*
G01X1102427Y181463D02*
X1130060Y179753D01*
G01X1102362Y182419D02*
X1129821Y180720D01*
G01X1130060Y179753D02*
X1143036Y187552D01*
G01X1129821Y180720D02*
X1142351Y188250D01*
G01X1143036Y187552D02*
X1143798Y188776D01*
G01X1142351Y188250D02*
X1142992Y189279D01*
G01X1143798Y188776D02*
X1151654Y198782D01*
G01X1143018Y189323D02*
X1148745Y196616D01*
G01X1143798Y188776D02*
X1151654Y198782D01*
G01X1150074Y198308D02*
X1150907Y199369D01*
G01X1136029Y203810D02*
X1130997Y198778D01*
G01X1135357Y204482D02*
X1130410Y199536D01*
G01X1130997Y198778D02*
X1127641Y196800D01*
G01X1130410Y199536D02*
X1130400Y199530D01*
G01X1130997Y198778D02*
X1127641Y196800D01*
G01X1130400Y199530D02*
X1127318Y197713D01*
G01X1127641Y196800D02*
X1125093Y196424D01*
G01X1127318Y197713D02*
X1125171Y197396D01*
G01X1125093Y196424D02*
X1122858Y197133D01*
G01X1125171Y197396D02*
X1123299Y197990D01*
G01X1122858Y197133D02*
X1116241Y202093D01*
G01X1123299Y197990D02*
X1122579Y198529D01*
G01X1122858Y197133D02*
X1116241Y202093D01*
G01X1121758Y199770D02*
X1121058Y199670D01*
G01X1122858Y197133D02*
X1116241Y202093D01*
G01X1121058Y199670D02*
X1120135Y200362D01*
G01X1122858Y197133D02*
X1116241Y202093D01*
G01X1119314Y201603D02*
X1118614Y201503D01*
G01X1122858Y197133D02*
X1116241Y202093D01*
G01X1118614Y201503D02*
X1116639Y202983D01*
G01X1116241Y202093D02*
X1109595Y203420D01*
G01X1116639Y202983D02*
X1109595Y204389D01*
G01Y203420D02*
X1107505Y203002D01*
G01X1109595Y204389D02*
X1107134Y203898D01*
G01X1107505Y203002D02*
X1100688Y198460D01*
G01X1107134Y203898D02*
X1100316Y199355D01*
G01X1100688Y198460D02*
X1098881Y198095D01*
G01X1100316Y199355D02*
X1099080Y199105D01*
G01X1098881Y198095D02*
X1097341Y199124D01*
G01X1099080Y199105D02*
X1097541Y200133D01*
G01X1097343Y415471D02*
X1115423Y411858D01*
G01X1097297Y414511D02*
X1108236Y412325D01*
G01X1097343Y415471D02*
X1115423Y411858D01*
G01X1110100Y411952D02*
X1115422Y410889D01*
G01X1115423Y411858D02*
X1118178Y412403D01*
G01X1115422Y410889D02*
X1118177Y411434D01*
G01X1118178Y412403D02*
X1146163Y406810D01*
G01X1118177Y411434D02*
X1123116Y410447D01*
G01X1118178Y412403D02*
X1146163Y406810D01*
G01X1125120Y410046D02*
X1146163Y405841D01*
G01Y406810D02*
X1150159Y406011D01*
G01X1146163Y405841D02*
X1150159Y405042D01*
G01Y406011D02*
X1189310Y413841D01*
G01X1150159Y405042D02*
X1174364Y409882D01*
G01X1150159Y406011D02*
X1189310Y413841D01*
G01X1150159Y406011D02*
X1189310Y413841D01*
G01X1114911Y457025D02*
X1126111Y454786D01*
G01X1114865Y456065D02*
X1126111Y453817D01*
G01Y454786D02*
X1146163Y458796D01*
G01X1126111Y453817D02*
X1146163Y457827D01*
G01Y458796D02*
X1148887Y459341D01*
G01X1146163Y457827D02*
X1148887Y458372D01*
G01Y459341D02*
X1200906Y448942D01*
G01X1148887Y458372D02*
X1200651Y448024D01*
G01X1148981Y461531D02*
X1206590Y450016D01*
G01X1206845Y450934D02*
X1148981Y462500D01*
G01X1146163Y460969D02*
X1148981Y461531D01*
G01Y462500D02*
X1146163Y461938D01*
G01X1128053Y457355D02*
X1146163Y460969D01*
G01Y461938D02*
X1128053Y458324D01*
G01X1115182Y459929D02*
X1128053Y457355D01*
G01Y458324D02*
X1115228Y460889D01*
G01X1216356Y452297D02*
X1149417Y465679D01*
G01X1216031Y451392D02*
X1149417Y464710D01*
G01D02*
X1146163Y464059D01*
G01Y465028D02*
X1130400Y461875D01*
G01D02*
X1130360Y461867D01*
G01D02*
X1130353Y461866D01*
G01X1146163Y464059D02*
X1130400Y460906D01*
G01X1130360Y461867D02*
X1130353Y461866D01*
G01D02*
X1115806Y464776D01*
G01X1130353Y460897D02*
X1115760Y463816D01*
G01X1146163Y467174D02*
X1132420Y464427D01*
G01D02*
X1116128Y467685D01*
G01X1098636Y419039D02*
X1102416Y418365D01*
G01D02*
X1102535Y418340D01*
G01X1098672Y419998D02*
X1102593Y419299D01*
G01X1098636Y419039D02*
X1102416Y418365D01*
G01D02*
X1102535Y418340D01*
G01D02*
X1102551Y418336D01*
G01D02*
X1102557Y418335D01*
G01D02*
X1102951Y418252D01*
G01X1102593Y419299D02*
X1102733Y419270D01*
G01X1098636Y419039D02*
X1102416Y418365D01*
G01X1102733Y419270D02*
X1102736Y419269D01*
G01X1098636Y419039D02*
X1102416Y418365D01*
G01D02*
X1102535Y418340D01*
G01D02*
X1102551Y418336D01*
G01D02*
X1102557Y418335D01*
G01D02*
X1102951Y418252D01*
G01X1102736Y419269D02*
X1102743Y419268D01*
G01X1102416Y418365D02*
X1102535Y418340D01*
G01D02*
X1102551Y418336D01*
G01D02*
X1102557Y418335D01*
G01D02*
X1102951Y418252D01*
G01X1102743Y419268D02*
X1102753Y419266D01*
G01X1102416Y418365D02*
X1102535Y418340D01*
G01D02*
X1102551Y418336D01*
G01D02*
X1102557Y418335D01*
G01D02*
X1102951Y418252D01*
G01D02*
X1104996Y419599D01*
G01X1102753Y419266D02*
X1102759Y419265D01*
G01X1102951Y418252D02*
X1104996Y419599D01*
G01X1102759Y419264D02*
X1104802Y420609D01*
G01X1104996Y419599D02*
X1106424Y419304D01*
G01X1104802Y420609D02*
X1107002Y420155D01*
G01X1106424Y419304D02*
X1107470Y417712D01*
G01X1107002Y420155D02*
X1108049Y418563D01*
G01X1107470Y417712D02*
X1108082Y417585D01*
G01X1108089Y417574D02*
X1111230Y417012D01*
G01X1108049Y418563D02*
X1108635Y418441D01*
G01X1108089Y417574D02*
X1111230Y417012D01*
G01X1108635Y418441D02*
X1111009Y418017D01*
G01X1111230Y417012D02*
X1112593Y417963D01*
G01X1111009Y418017D02*
X1111728Y418518D01*
G01X1112593Y417963D02*
X1112802Y419115D01*
G01X1111728Y418518D02*
X1111734Y418557D01*
G01X1112593Y417963D02*
X1112802Y419115D01*
G01X1111734Y418557D02*
X1111938Y419673D01*
G01X1112802Y419115D02*
X1113505Y419601D01*
G01X1111938Y419673D02*
X1113287Y420606D01*
G01X1113505Y419601D02*
X1115914Y419170D01*
G01X1113287Y420606D02*
X1116472Y420036D01*
G01X1115914Y419170D02*
X1116398Y418468D01*
G01X1116472Y420036D02*
X1117404Y418684D01*
G01X1116398Y418468D02*
X1116189Y417323D01*
G01X1117404Y418684D02*
X1117280Y418008D01*
G01X1116398Y418468D02*
X1116189Y417323D01*
G01X1117280Y418007D02*
X1117195Y417541D01*
G01X1116189Y417323D02*
X1117004Y416153D01*
G01X1117195Y417541D02*
X1117559Y417019D01*
G01X1117004Y416153D02*
X1120629Y415506D01*
G01X1117559Y417019D02*
X1118587Y416835D01*
G01X1117004Y416153D02*
X1120629Y415506D01*
G01X1118587Y416835D02*
X1118588D01*
G01X1117004Y416153D02*
X1120629Y415506D01*
G01X1118588Y416835D02*
X1121067Y416393D01*
G01X1120630Y415505D02*
X1122716Y413607D01*
G01X1121067Y416393D02*
X1123161Y414487D01*
G01X1122716Y413607D02*
X1146163Y408919D01*
G01X1123161Y414487D02*
X1146163Y409888D01*
G01Y408919D02*
X1150009Y408150D01*
G01X1146163Y409888D02*
X1150009Y409119D01*
G01Y408150D02*
X1190601Y416272D01*
G01X1150009Y409119D02*
X1190632Y417248D01*
G01X1099540Y423673D02*
X1099541D01*
G01D02*
X1100221Y423742D01*
G01X1102093Y423931D02*
X1102988Y424021D01*
G01X1104860Y424210D02*
X1105755Y424300D01*
G01X1108740Y425556D02*
X1118690Y423699D01*
G01X1107626Y424489D02*
X1108700Y424597D01*
G01X1108740Y425556D02*
X1118690Y423699D01*
G01X1108700Y424597D02*
X1111090Y424151D01*
G01X1108740Y425556D02*
X1118690Y423699D01*
G01X1112939Y423805D02*
X1113457Y423708D01*
G01X1108740Y425556D02*
X1118690Y423699D01*
G01X1113457Y423708D02*
X1118261Y422812D01*
G01X1118690Y423699D02*
X1125972Y417362D01*
G01X1118261Y422812D02*
X1125530Y416487D01*
G01X1125972Y417362D02*
X1138033Y414669D01*
G01X1125530Y416487D02*
X1137836Y413739D01*
G01X1138033Y414669D02*
X1146163Y413044D01*
G01X1137836Y413739D02*
X1146163Y412075D01*
G01Y413044D02*
X1150174Y412242D01*
G01X1146163Y412075D02*
X1150174Y411273D01*
G01Y412242D02*
X1191163Y420443D01*
G01X1150174Y411273D02*
X1191141Y419469D01*
G01X1109368Y428518D02*
X1120301Y426283D01*
G01X1109417Y429478D02*
X1120743Y427163D01*
G01X1120301Y426283D02*
X1128400Y419055D01*
G01X1120743Y427163D02*
X1128846Y419931D01*
G01X1128400Y419055D02*
X1150136Y414349D01*
G01X1128846Y419931D02*
X1150144Y415320D01*
G01X1150136Y414349D02*
X1192191Y422758D01*
G01X1150144Y415320D02*
X1192227Y423735D01*
G01X1109632Y432470D02*
X1122139Y429968D01*
G01X1109678Y433430D02*
X1122569Y430852D01*
G01X1122139Y429968D02*
X1132124Y421433D01*
G01X1122569Y430852D02*
X1132553Y422317D01*
G01X1132124Y421433D02*
X1146163Y418627D01*
G01X1132553Y422317D02*
X1146163Y419596D01*
G01Y418627D02*
X1150907Y417679D01*
G01X1146163Y419596D02*
X1150907Y418648D01*
G01Y417679D02*
X1193537Y426208D01*
G01X1150907Y418648D02*
X1193572Y427184D01*
G01X1110666Y436406D02*
X1123782Y433785D01*
G01X1110712Y437366D02*
X1124209Y434669D01*
G01X1123782Y433785D02*
X1135535Y423839D01*
G01X1124209Y434669D02*
X1135962Y424723D01*
G01X1135535Y423839D02*
X1150202Y420909D01*
G01X1135962Y424723D02*
X1146163Y422685D01*
G01X1135535Y423839D02*
X1150202Y420909D01*
G01X1146163Y422685D02*
X1150202Y421878D01*
G01Y420909D02*
X1194645Y429798D01*
G01X1150202Y421878D02*
X1194630Y430764D01*
G01X1112896Y441504D02*
X1124860Y439110D01*
G01X1112850Y440544D02*
X1124446Y438224D01*
G01X1124860Y439110D02*
X1132397Y433067D01*
G01Y433068D02*
X1139576Y427311D01*
G01X1124446Y438224D02*
X1139159Y426426D01*
G01X1139576Y427311D02*
X1150437Y425062D01*
G01X1139159Y426426D02*
X1150437Y424091D01*
G01Y425062D02*
X1196300Y434534D01*
G01X1150437Y424091D02*
X1196267Y433556D01*
G01X1113299Y445369D02*
X1126621Y442707D01*
G01X1113253Y444409D02*
X1126220Y441817D01*
G01X1126621Y442707D02*
X1143627Y429796D01*
G01X1126220Y441817D02*
X1143216Y428915D01*
G01X1143627Y429796D02*
X1146163Y429218D01*
G01X1143216Y428915D02*
X1146163Y428243D01*
G01Y429218D02*
X1150172Y428304D01*
G01X1146163Y428243D02*
X1150171Y427329D01*
G01X1150172Y428304D02*
X1195408Y438523D01*
G01X1150171Y427329D02*
X1195368Y437540D01*
G01X1113594Y448275D02*
X1123062Y446383D01*
G01X1113640Y449235D02*
X1123060Y447353D01*
G01X1123062Y446383D02*
X1146163Y451088D01*
G01X1123060Y447353D02*
X1146163Y452058D01*
G01Y451088D02*
X1150294Y451929D01*
G01X1146163Y452058D02*
X1150295Y452899D01*
G01X1150294Y451929D02*
X1190732Y443581D01*
G01X1150295Y452899D02*
X1190989Y444498D01*
G01X1114546Y452200D02*
X1125341Y450041D01*
G01X1114592Y453160D02*
X1125340Y451011D01*
G01X1125341Y450041D02*
X1146163Y454265D01*
G01X1125340Y451011D02*
X1146163Y455235D01*
G01Y454265D02*
X1150106Y455065D01*
G01X1146163Y455235D02*
X1150107Y456035D01*
G01X1150106Y455065D02*
X1194482Y445981D01*
G01X1150107Y456035D02*
X1194630Y446920D01*
G01X1150106Y455065D02*
X1194482Y445981D01*
G01X1097297Y414511D02*
X1108236Y412325D01*
G01X1110100Y411952D02*
X1115422Y410889D01*
G01X1097343Y415471D02*
X1115423Y411858D01*
G01X1115422Y410889D02*
X1118177Y411434D01*
G01X1115423Y411858D02*
X1118178Y412403D01*
G01X1118177Y411434D02*
X1123116Y410447D01*
G01X1125120Y410046D02*
X1146163Y405841D01*
G01X1118178Y412403D02*
X1146163Y406810D01*
G01Y405841D02*
X1150159Y405042D01*
G01X1146163Y406810D02*
X1150159Y406011D01*
G01Y405042D02*
X1174364Y409882D01*
G01X1150159Y406011D02*
X1189310Y413841D01*
G01X1114865Y456065D02*
X1126111Y453817D01*
G01X1114911Y457025D02*
X1126111Y454786D01*
G01Y453817D02*
X1146163Y457827D01*
G01X1126111Y454786D02*
X1146163Y458796D01*
G01Y457827D02*
X1148887Y458372D01*
G01X1146163Y458796D02*
X1148887Y459341D01*
G01Y458372D02*
X1200651Y448024D01*
G01X1148887Y459341D02*
X1200906Y448942D01*
G01X1114865Y456065D02*
X1126111Y453817D01*
G01X1114911Y457025D02*
X1126111Y454786D01*
G01Y453817D02*
X1146163Y457827D01*
G01X1126111Y454786D02*
X1146163Y458796D01*
G01Y457827D02*
X1148887Y458372D01*
G01X1146163Y458796D02*
X1148887Y459341D01*
G01Y458372D02*
X1200651Y448024D01*
G01X1148887Y459341D02*
X1200906Y448942D01*
G01X1128053Y458324D02*
X1115228Y460889D01*
G01X1115182Y459929D02*
X1128053Y457355D01*
G01X1146163Y461938D02*
X1128053Y458324D01*
G01Y457355D02*
X1146163Y460969D01*
G01X1148981Y462500D02*
X1146163Y461938D01*
G01Y460969D02*
X1148981Y461531D01*
G01X1206845Y450934D02*
X1148981Y462500D01*
G01Y461531D02*
X1206590Y450016D01*
G01X1216031Y451392D02*
X1149417Y464710D01*
G01X1216356Y452297D02*
X1149417Y465679D01*
G01Y464710D02*
X1146163Y464059D01*
G01D02*
X1130400Y460906D01*
G01X1146163Y465028D02*
X1130400Y461875D01*
G01X1146163Y464059D02*
X1130400Y460906D01*
G01Y461875D02*
X1130360Y461867D01*
G01X1146163Y464059D02*
X1130400Y460906D01*
G01X1130353Y460897D02*
X1115760Y463816D01*
G01X1130360Y461867D02*
X1130353Y461866D01*
G01Y460897D02*
X1115760Y463816D01*
G01X1130353Y461866D02*
X1115806Y464776D01*
G01X1146163Y467174D02*
X1132420Y464427D01*
G01D02*
X1116128Y467685D01*
G01X1098672Y419998D02*
X1102593Y419299D01*
G01D02*
X1102733Y419270D01*
G01D02*
X1102736Y419269D01*
G01D02*
X1102743Y419268D01*
G01X1098636Y419039D02*
X1102416Y418365D01*
G01X1098672Y419998D02*
X1102593Y419299D01*
G01D02*
X1102733Y419270D01*
G01X1102736Y419269D02*
X1102743Y419268D01*
G01D02*
X1102753Y419266D01*
G01D02*
X1102759Y419265D01*
G01X1102416Y418365D02*
X1102535Y418340D01*
G01X1102593Y419299D02*
X1102733Y419270D01*
G01X1102736Y419269D02*
X1102743Y419268D01*
G01D02*
X1102753Y419266D01*
G01D02*
X1102759Y419265D01*
G01X1102535Y418340D02*
X1102551Y418336D01*
G01X1102593Y419299D02*
X1102733Y419270D01*
G01X1102736Y419269D02*
X1102743Y419268D01*
G01D02*
X1102753Y419266D01*
G01D02*
X1102759Y419265D01*
G01X1102551Y418336D02*
X1102557Y418335D01*
G01X1102593Y419299D02*
X1102733Y419270D01*
G01X1102736Y419269D02*
X1102743Y419268D01*
G01D02*
X1102753Y419266D01*
G01D02*
X1102759Y419265D01*
G01X1102557Y418335D02*
X1102951Y418252D01*
G01X1102753Y419266D02*
X1102759Y419265D01*
G01Y419264D02*
X1104802Y420609D01*
G01X1102951Y418252D02*
X1104996Y419599D01*
G01X1104802Y420609D02*
X1107002Y420155D01*
G01X1104996Y419599D02*
X1106424Y419304D01*
G01X1107002Y420155D02*
X1108049Y418563D01*
G01X1106424Y419304D02*
X1107470Y417712D01*
G01X1108049Y418563D02*
X1108635Y418441D01*
G01X1107470Y417712D02*
X1108082Y417585D01*
G01X1108049Y418563D02*
X1108635Y418441D01*
G01D02*
X1111009Y418017D01*
G01X1108089Y417574D02*
X1111230Y417012D01*
G01X1111009Y418017D02*
X1111728Y418518D01*
G01X1111230Y417012D02*
X1112593Y417963D01*
G01X1111728Y418518D02*
X1111734Y418557D01*
G01D02*
X1111938Y419673D01*
G01X1112593Y417963D02*
X1112802Y419115D01*
G01X1111938Y419673D02*
X1113287Y420606D01*
G01X1112802Y419115D02*
X1113505Y419601D01*
G01X1113287Y420606D02*
X1116472Y420036D01*
G01X1113505Y419601D02*
X1115914Y419170D01*
G01X1116472Y420036D02*
X1117404Y418684D01*
G01X1115914Y419170D02*
X1116398Y418468D01*
G01X1117404Y418684D02*
X1117280Y418008D01*
G01Y418007D02*
X1117195Y417541D01*
G01X1116398Y418468D02*
X1116189Y417323D01*
G01X1117195Y417541D02*
X1117559Y417019D01*
G01X1116189Y417323D02*
X1117004Y416153D01*
G01X1117559Y417019D02*
X1118587Y416835D01*
G01D02*
X1118588D01*
G01D02*
X1121067Y416393D01*
G01X1117004Y416153D02*
X1120629Y415506D01*
G01X1121067Y416393D02*
X1123161Y414487D01*
G01X1120630Y415505D02*
X1122716Y413607D01*
G01X1123161Y414487D02*
X1146163Y409888D01*
G01X1122716Y413607D02*
X1146163Y408919D01*
G01Y409888D02*
X1150009Y409119D01*
G01X1146163Y408919D02*
X1150009Y408150D01*
G01Y409119D02*
X1190632Y417248D01*
G01X1150009Y408150D02*
X1190601Y416272D01*
G01X1098672Y419998D02*
X1102593Y419299D01*
G01D02*
X1102733Y419270D01*
G01D02*
X1102736Y419269D01*
G01D02*
X1102743Y419268D01*
G01X1098636Y419039D02*
X1102416Y418365D01*
G01X1098672Y419998D02*
X1102593Y419299D01*
G01D02*
X1102733Y419270D01*
G01X1102736Y419269D02*
X1102743Y419268D01*
G01D02*
X1102753Y419266D01*
G01D02*
X1102759Y419265D01*
G01X1102416Y418365D02*
X1102535Y418340D01*
G01X1102593Y419299D02*
X1102733Y419270D01*
G01X1102736Y419269D02*
X1102743Y419268D01*
G01D02*
X1102753Y419266D01*
G01D02*
X1102759Y419265D01*
G01X1102535Y418340D02*
X1102551Y418336D01*
G01X1102593Y419299D02*
X1102733Y419270D01*
G01X1102736Y419269D02*
X1102743Y419268D01*
G01D02*
X1102753Y419266D01*
G01D02*
X1102759Y419265D01*
G01X1102551Y418336D02*
X1102557Y418335D01*
G01X1102593Y419299D02*
X1102733Y419270D01*
G01X1102736Y419269D02*
X1102743Y419268D01*
G01D02*
X1102753Y419266D01*
G01D02*
X1102759Y419265D01*
G01X1102557Y418335D02*
X1102951Y418252D01*
G01X1102753Y419266D02*
X1102759Y419265D01*
G01Y419264D02*
X1104802Y420609D01*
G01X1102951Y418252D02*
X1104996Y419599D01*
G01X1104802Y420609D02*
X1107002Y420155D01*
G01X1104996Y419599D02*
X1106424Y419304D01*
G01X1107002Y420155D02*
X1108049Y418563D01*
G01X1106424Y419304D02*
X1107470Y417712D01*
G01X1108049Y418563D02*
X1108635Y418441D01*
G01X1107470Y417712D02*
X1108082Y417585D01*
G01X1108049Y418563D02*
X1108635Y418441D01*
G01D02*
X1111009Y418017D01*
G01X1108089Y417574D02*
X1111230Y417012D01*
G01X1111009Y418017D02*
X1111728Y418518D01*
G01X1111230Y417012D02*
X1112593Y417963D01*
G01X1111728Y418518D02*
X1111734Y418557D01*
G01D02*
X1111938Y419673D01*
G01X1112593Y417963D02*
X1112802Y419115D01*
G01X1111938Y419673D02*
X1113287Y420606D01*
G01X1112802Y419115D02*
X1113505Y419601D01*
G01X1113287Y420606D02*
X1116472Y420036D01*
G01X1113505Y419601D02*
X1115914Y419170D01*
G01X1116472Y420036D02*
X1117404Y418684D01*
G01X1115914Y419170D02*
X1116398Y418468D01*
G01X1117404Y418684D02*
X1117280Y418008D01*
G01Y418007D02*
X1117195Y417541D01*
G01X1116398Y418468D02*
X1116189Y417323D01*
G01X1117195Y417541D02*
X1117559Y417019D01*
G01X1116189Y417323D02*
X1117004Y416153D01*
G01X1117559Y417019D02*
X1118587Y416835D01*
G01D02*
X1118588D01*
G01D02*
X1121067Y416393D01*
G01X1117004Y416153D02*
X1120629Y415506D01*
G01X1121067Y416393D02*
X1123161Y414487D01*
G01X1120630Y415505D02*
X1122716Y413607D01*
G01X1123161Y414487D02*
X1146163Y409888D01*
G01X1122716Y413607D02*
X1146163Y408919D01*
G01Y409888D02*
X1150009Y409119D01*
G01X1146163Y408919D02*
X1150009Y408150D01*
G01Y409119D02*
X1190632Y417248D01*
G01X1150009Y408150D02*
X1190601Y416272D01*
G01X1099540Y423673D02*
X1099541D01*
G01D02*
X1100221Y423742D01*
G01X1102093Y423931D02*
X1102988Y424021D01*
G01X1104860Y424210D02*
X1105755Y424300D01*
G01X1107626Y424489D02*
X1108700Y424597D01*
G01X1107626Y424489D02*
X1108700Y424597D01*
G01D02*
X1111090Y424151D01*
G01X1112939Y423805D02*
X1113457Y423708D01*
G01D02*
X1118261Y422812D01*
G01X1108740Y425556D02*
X1118690Y423699D01*
G01X1118261Y422812D02*
X1125530Y416487D01*
G01X1118690Y423699D02*
X1125972Y417362D01*
G01X1125530Y416487D02*
X1137836Y413739D01*
G01X1125972Y417362D02*
X1138033Y414669D01*
G01X1137836Y413739D02*
X1146163Y412075D01*
G01X1138033Y414669D02*
X1146163Y413044D01*
G01Y412075D02*
X1150174Y411273D01*
G01X1146163Y413044D02*
X1150174Y412242D01*
G01Y411273D02*
X1191141Y419469D01*
G01X1150174Y412242D02*
X1191163Y420443D01*
G01X1109417Y429478D02*
X1120743Y427163D01*
G01X1109368Y428518D02*
X1120301Y426283D01*
G01X1120743Y427163D02*
X1128846Y419931D01*
G01X1120301Y426283D02*
X1128400Y419055D01*
G01X1128846Y419931D02*
X1150144Y415320D01*
G01X1128400Y419055D02*
X1150136Y414349D01*
G01X1150144Y415320D02*
X1192227Y423735D01*
G01X1150136Y414349D02*
X1192191Y422758D01*
G01X1109678Y433430D02*
X1122569Y430852D01*
G01X1109632Y432470D02*
X1122139Y429968D01*
G01X1122569Y430852D02*
X1132553Y422317D01*
G01X1122139Y429968D02*
X1132124Y421433D01*
G01X1132553Y422317D02*
X1146163Y419596D01*
G01X1132124Y421433D02*
X1146163Y418627D01*
G01Y419596D02*
X1150907Y418648D01*
G01X1146163Y418627D02*
X1150907Y417679D01*
G01Y418648D02*
X1193572Y427184D01*
G01X1150907Y417679D02*
X1193537Y426208D01*
G01X1110712Y437366D02*
X1124209Y434669D01*
G01X1110666Y436406D02*
X1123782Y433785D01*
G01X1124209Y434669D02*
X1135962Y424723D01*
G01X1123782Y433785D02*
X1135535Y423839D01*
G01X1135962Y424723D02*
X1146163Y422685D01*
G01D02*
X1150202Y421878D01*
G01X1135535Y423839D02*
X1150202Y420909D01*
G01Y421878D02*
X1194630Y430764D01*
G01X1150202Y420909D02*
X1194645Y429798D01*
G01X1112850Y440544D02*
X1124446Y438224D01*
G01X1112896Y441504D02*
X1124860Y439110D01*
G01X1124446Y438224D02*
X1139159Y426426D01*
G01X1124860Y439110D02*
X1132397Y433067D01*
G01X1124446Y438224D02*
X1139159Y426426D01*
G01X1132397Y433068D02*
X1139576Y427311D01*
G01X1139159Y426426D02*
X1150437Y424091D01*
G01X1139576Y427311D02*
X1150437Y425062D01*
G01Y424091D02*
X1196267Y433556D01*
G01X1150437Y425062D02*
X1196300Y434534D01*
G01X1113253Y444409D02*
X1126220Y441817D01*
G01X1113299Y445369D02*
X1126621Y442707D01*
G01X1126220Y441817D02*
X1143216Y428915D01*
G01X1126621Y442707D02*
X1143627Y429796D01*
G01X1143216Y428915D02*
X1146163Y428243D01*
G01X1143627Y429796D02*
X1146163Y429218D01*
G01Y428243D02*
X1150171Y427329D01*
G01X1146163Y429218D02*
X1150172Y428304D01*
G01X1150171Y427329D02*
X1195368Y437540D01*
G01X1150172Y428304D02*
X1195408Y438523D01*
G01X1113640Y449235D02*
X1123060Y447353D01*
G01X1113594Y448275D02*
X1123062Y446383D01*
G01X1123060Y447353D02*
X1146163Y452058D01*
G01X1123062Y446383D02*
X1146163Y451088D01*
G01Y452058D02*
X1150295Y452899D01*
G01X1146163Y451088D02*
X1150294Y451929D01*
G01X1150295Y452899D02*
X1190989Y444498D01*
G01X1150294Y451929D02*
X1190732Y443581D01*
G01X1114592Y453160D02*
X1125340Y451011D01*
G01X1114546Y452200D02*
X1125341Y450041D01*
G01X1125340Y451011D02*
X1146163Y455235D01*
G01X1125341Y450041D02*
X1146163Y454265D01*
G01Y455235D02*
X1150107Y456035D01*
G01X1146163Y454265D02*
X1150106Y455065D01*
G01X1150107Y456035D02*
X1194630Y446920D01*
G01X1150106Y455065D02*
X1194482Y445981D01*
G01X1148981Y461531D02*
X1206590Y450016D01*
G01X1206845Y450934D02*
X1148981Y462500D01*
G01X1146163Y460969D02*
X1148981Y461531D01*
G01Y462500D02*
X1146163Y461938D01*
G01X1128053Y457355D02*
X1146163Y460969D01*
G01Y461938D02*
X1128053Y458324D01*
G01X1115182Y459929D02*
X1128053Y457355D01*
G01Y458324D02*
X1115228Y460889D01*
G01X1146163Y467174D02*
X1132420Y464427D01*
G01D02*
X1116128Y467685D01*
G01X1216031Y451392D02*
X1149417Y464710D01*
G01X1216356Y452297D02*
X1149417Y465679D01*
G01Y464710D02*
X1146163Y464059D01*
G01D02*
X1130400Y460906D01*
G01X1146163Y465028D02*
X1130400Y461875D01*
G01X1146163Y464059D02*
X1130400Y460906D01*
G01Y461875D02*
X1130360Y461867D01*
G01X1146163Y464059D02*
X1130400Y460906D01*
G01X1130353Y460897D02*
X1115760Y463816D01*
G01X1130360Y461867D02*
X1130353Y461866D01*
G01Y460897D02*
X1115760Y463816D01*
G01X1130353Y461866D02*
X1115806Y464776D01*
G01X1113253Y444409D02*
X1126220Y441817D01*
G01X1113299Y445369D02*
X1126621Y442707D01*
G01X1126220Y441817D02*
X1143216Y428915D01*
G01X1126621Y442707D02*
X1143627Y429796D01*
G01X1143216Y428915D02*
X1146163Y428243D01*
G01X1143627Y429796D02*
X1146163Y429218D01*
G01Y428243D02*
X1150171Y427329D01*
G01X1146163Y429218D02*
X1150172Y428304D01*
G01X1150171Y427329D02*
X1195368Y437540D01*
G01X1150172Y428304D02*
X1195408Y438523D01*
G01X1114546Y452200D02*
X1125341Y450041D01*
G01X1114592Y453160D02*
X1125340Y451011D01*
G01X1125341Y450041D02*
X1146163Y454265D01*
G01X1125340Y451011D02*
X1146163Y455235D01*
G01Y454265D02*
X1150106Y455065D01*
G01X1146163Y455235D02*
X1150107Y456035D01*
G01X1150106Y455065D02*
X1194482Y445981D01*
G01X1150107Y456035D02*
X1194630Y446920D01*
G01X1150106Y455065D02*
X1194482Y445981D01*
G01X1099540Y423673D02*
X1099541D01*
G01D02*
X1100221Y423742D01*
G01X1102093Y423931D02*
X1102988Y424021D01*
G01X1104860Y424210D02*
X1105755Y424300D01*
G01X1108740Y425556D02*
X1118690Y423699D01*
G01X1107626Y424489D02*
X1108700Y424597D01*
G01X1108740Y425556D02*
X1118690Y423699D01*
G01X1108700Y424597D02*
X1111090Y424151D01*
G01X1108740Y425556D02*
X1118690Y423699D01*
G01X1112939Y423805D02*
X1113457Y423708D01*
G01X1108740Y425556D02*
X1118690Y423699D01*
G01X1113457Y423708D02*
X1118261Y422812D01*
G01X1118690Y423699D02*
X1125972Y417362D01*
G01X1118261Y422812D02*
X1125530Y416487D01*
G01X1125972Y417362D02*
X1138033Y414669D01*
G01X1125530Y416487D02*
X1137836Y413739D01*
G01X1138033Y414669D02*
X1146163Y413044D01*
G01X1137836Y413739D02*
X1146163Y412075D01*
G01Y413044D02*
X1150174Y412242D01*
G01X1146163Y412075D02*
X1150174Y411273D01*
G01Y412242D02*
X1191163Y420443D01*
G01X1150174Y411273D02*
X1191141Y419469D01*
G01X1109368Y428518D02*
X1120301Y426283D01*
G01X1109417Y429478D02*
X1120743Y427163D01*
G01X1120301Y426283D02*
X1128400Y419055D01*
G01X1120743Y427163D02*
X1128846Y419931D01*
G01X1128400Y419055D02*
X1150136Y414349D01*
G01X1128846Y419931D02*
X1150144Y415320D01*
G01X1150136Y414349D02*
X1192191Y422758D01*
G01X1150144Y415320D02*
X1192227Y423735D01*
G01X1113299Y445369D02*
X1126621Y442707D01*
G01X1113253Y444409D02*
X1126220Y441817D01*
G01X1126621Y442707D02*
X1143627Y429796D01*
G01X1126220Y441817D02*
X1143216Y428915D01*
G01X1143627Y429796D02*
X1146163Y429218D01*
G01X1143216Y428915D02*
X1146163Y428243D01*
G01Y429218D02*
X1150172Y428304D01*
G01X1146163Y428243D02*
X1150171Y427329D01*
G01X1150172Y428304D02*
X1195408Y438523D01*
G01X1150171Y427329D02*
X1195368Y437540D01*
G01X1109417Y429478D02*
X1120743Y427163D01*
G01X1109368Y428518D02*
X1120301Y426283D01*
G01X1120743Y427163D02*
X1128846Y419931D01*
G01X1120301Y426283D02*
X1128400Y419055D01*
G01X1128846Y419931D02*
X1150144Y415320D01*
G01X1128400Y419055D02*
X1150136Y414349D01*
G01X1150144Y415320D02*
X1192227Y423735D01*
G01X1150136Y414349D02*
X1192191Y422758D01*
G01X1112850Y440544D02*
X1124446Y438224D01*
G01X1112896Y441504D02*
X1124860Y439110D01*
G01X1124446Y438224D02*
X1139159Y426426D01*
G01X1124860Y439110D02*
X1132397Y433067D01*
G01X1124446Y438224D02*
X1139159Y426426D01*
G01X1132397Y433068D02*
X1139576Y427311D01*
G01X1139159Y426426D02*
X1150437Y424091D01*
G01X1139576Y427311D02*
X1150437Y425062D01*
G01Y424091D02*
X1196267Y433556D01*
G01X1150437Y425062D02*
X1196300Y434534D01*
G01X1113640Y449235D02*
X1123060Y447353D01*
G01X1113594Y448275D02*
X1123062Y446383D01*
G01X1123060Y447353D02*
X1146163Y452058D01*
G01X1123062Y446383D02*
X1146163Y451088D01*
G01Y452058D02*
X1150295Y452899D01*
G01X1146163Y451088D02*
X1150294Y451929D01*
G01X1150295Y452899D02*
X1190989Y444498D01*
G01X1150294Y451929D02*
X1190732Y443581D01*
G01X1110666Y436406D02*
X1123782Y433785D01*
G01X1110712Y437366D02*
X1124209Y434669D01*
G01X1123782Y433785D02*
X1135535Y423839D01*
G01X1124209Y434669D02*
X1135962Y424723D01*
G01X1135535Y423839D02*
X1150202Y420909D01*
G01X1135962Y424723D02*
X1146163Y422685D01*
G01X1135535Y423839D02*
X1150202Y420909D01*
G01X1146163Y422685D02*
X1150202Y421878D01*
G01Y420909D02*
X1194645Y429798D01*
G01X1150202Y421878D02*
X1194630Y430764D01*
G01X1099540Y423673D02*
X1099541D01*
G01D02*
X1100221Y423742D01*
G01X1102093Y423931D02*
X1102988Y424021D01*
G01X1104860Y424210D02*
X1105755Y424300D01*
G01X1107626Y424489D02*
X1108700Y424597D01*
G01X1107626Y424489D02*
X1108700Y424597D01*
G01D02*
X1111090Y424151D01*
G01X1112939Y423805D02*
X1113457Y423708D01*
G01D02*
X1118261Y422812D01*
G01X1108740Y425556D02*
X1118690Y423699D01*
G01X1118261Y422812D02*
X1125530Y416487D01*
G01X1118690Y423699D02*
X1125972Y417362D01*
G01X1125530Y416487D02*
X1137836Y413739D01*
G01X1125972Y417362D02*
X1138033Y414669D01*
G01X1137836Y413739D02*
X1146163Y412075D01*
G01X1138033Y414669D02*
X1146163Y413044D01*
G01Y412075D02*
X1150174Y411273D01*
G01X1146163Y413044D02*
X1150174Y412242D01*
G01Y411273D02*
X1191141Y419469D01*
G01X1150174Y412242D02*
X1191163Y420443D01*
G01X1109678Y433430D02*
X1122569Y430852D01*
G01X1109632Y432470D02*
X1122139Y429968D01*
G01X1122569Y430852D02*
X1132553Y422317D01*
G01X1122139Y429968D02*
X1132124Y421433D01*
G01X1132553Y422317D02*
X1146163Y419596D01*
G01X1132124Y421433D02*
X1146163Y418627D01*
G01Y419596D02*
X1150907Y418648D01*
G01X1146163Y418627D02*
X1150907Y417679D01*
G01Y418648D02*
X1193572Y427184D01*
G01X1150907Y417679D02*
X1193537Y426208D01*
G01X1110712Y437366D02*
X1124209Y434669D01*
G01X1110666Y436406D02*
X1123782Y433785D01*
G01X1124209Y434669D02*
X1135962Y424723D01*
G01X1123782Y433785D02*
X1135535Y423839D01*
G01X1135962Y424723D02*
X1146163Y422685D01*
G01D02*
X1150202Y421878D01*
G01X1135535Y423839D02*
X1150202Y420909D01*
G01Y421878D02*
X1194630Y430764D01*
G01X1150202Y420909D02*
X1194645Y429798D01*
G01X1149417Y465679D02*
X1146163Y465028D01*
G01X1178913Y461892D02*
X1149330Y467807D01*
G01X1178915Y462861D02*
X1149330Y468776D01*
G01Y467807D02*
X1146163Y467174D01*
G01X1149330Y468776D02*
X1146163Y468143D01*
G01D02*
X1132420Y465396D01*
G01D02*
X1116174Y468645D01*
G01X1118164Y472680D02*
X1134819Y469349D01*
G01D02*
X1135722Y469168D01*
G01X1118118Y471720D02*
X1134819Y468380D01*
G01Y469349D02*
X1135722Y469168D01*
G01X1134819Y468380D02*
X1135722Y468199D01*
G01Y469168D02*
X1146163Y471256D01*
G01X1135722Y468199D02*
X1146163Y470287D01*
G01Y471256D02*
X1151267Y472277D01*
G01X1146163Y470287D02*
X1151267Y471308D01*
G01Y472277D02*
X1177227Y467084D01*
G01X1151267Y471308D02*
X1177225Y466115D01*
G01X1118685Y475606D02*
X1138052Y471733D01*
G01X1118731Y476566D02*
X1138052Y472702D01*
G01Y471733D02*
X1146163Y473358D01*
G01X1138052Y472702D02*
X1146163Y474327D01*
G01Y473358D02*
X1151416Y474410D01*
G01X1146163Y474327D02*
X1151416Y475379D01*
G01Y474410D02*
X1176448Y469400D01*
G01X1151416Y475379D02*
X1176448Y470369D01*
G01X1140378Y476257D02*
X1119354Y480462D01*
G01X1119308Y479502D02*
X1140378Y475288D01*
G01X1146163Y477414D02*
X1140378Y476257D01*
G01Y475288D02*
X1146163Y476445D01*
G01X1153796Y478940D02*
X1146163Y477414D01*
G01Y476445D02*
X1153796Y477971D01*
G01X1173039Y475089D02*
X1153796Y478940D01*
G01Y477971D02*
X1173039Y474120D01*
G01X1149417Y465679D02*
X1146163Y465028D01*
G01X1178915Y462861D02*
X1149330Y468776D01*
G01X1178913Y461892D02*
X1149330Y467807D01*
G01Y468776D02*
X1146163Y468143D01*
G01X1149330Y467807D02*
X1146163Y467174D01*
G01Y468143D02*
X1132420Y465396D01*
G01D02*
X1116174Y468645D01*
G01X1118118Y471720D02*
X1134819Y468380D01*
G01X1118164Y472680D02*
X1134819Y469349D01*
G01X1118118Y471720D02*
X1134819Y468380D01*
G01D02*
X1135722Y468199D01*
G01X1134819Y469349D02*
X1135722Y469168D01*
G01Y468199D02*
X1146163Y470287D01*
G01X1135722Y469168D02*
X1146163Y471256D01*
G01Y470287D02*
X1151267Y471308D01*
G01X1146163Y471256D02*
X1151267Y472277D01*
G01Y471308D02*
X1177225Y466115D01*
G01X1151267Y472277D02*
X1177227Y467084D01*
G01X1118731Y476566D02*
X1138052Y472702D01*
G01X1118685Y475606D02*
X1138052Y471733D01*
G01Y472702D02*
X1146163Y474327D01*
G01X1138052Y471733D02*
X1146163Y473358D01*
G01Y474327D02*
X1151416Y475379D01*
G01X1146163Y473358D02*
X1151416Y474410D01*
G01Y475379D02*
X1176448Y470369D01*
G01X1151416Y474410D02*
X1176448Y469400D01*
G01X1153796Y477971D02*
X1173039Y474120D01*
G01Y475089D02*
X1153796Y478940D01*
G01X1146163Y476445D02*
X1153796Y477971D01*
G01Y478940D02*
X1146163Y477414D01*
G01X1140378Y475288D02*
X1146163Y476445D01*
G01Y477414D02*
X1140378Y476257D01*
G01X1119308Y479502D02*
X1140378Y475288D01*
G01Y476257D02*
X1119354Y480462D01*
G01X1119581Y484315D02*
X1141972Y479837D01*
G01X1119535Y483355D02*
X1141972Y478868D01*
G01Y479837D02*
X1154167Y482271D01*
G01X1141972Y478868D02*
X1146163Y479704D01*
G01X1141972Y479837D02*
X1154167Y482271D01*
G01X1146163Y479704D02*
X1154167Y481302D01*
G01Y482271D02*
X1171661Y478772D01*
G01X1154167Y481302D02*
X1171661Y477803D01*
G01X1119581Y484315D02*
X1141972Y479837D01*
G01X1119535Y483355D02*
X1141972Y478868D01*
G01Y479837D02*
X1154167Y482271D01*
G01X1141972Y478868D02*
X1146163Y479704D01*
G01X1141972Y479837D02*
X1154167Y482271D01*
G01X1146163Y479704D02*
X1154167Y481302D01*
G01Y482271D02*
X1171661Y478772D01*
G01X1154167Y481302D02*
X1171661Y477803D01*
G01X1119920Y487226D02*
X1143980Y482414D01*
G01X1119966Y488186D02*
X1143981Y483383D01*
G01X1143980Y482414D02*
X1146163Y482847D01*
G01X1143981Y483383D02*
X1146163Y483815D01*
G01Y482847D02*
X1154001Y484400D01*
G01X1146163Y483815D02*
X1154002Y485369D01*
G01X1154001Y484400D02*
X1167858Y481629D01*
G01X1154002Y485369D02*
X1167858Y482598D01*
G01X1120528Y491120D02*
X1145516Y486120D01*
G01X1120574Y492080D02*
X1145516Y487089D01*
G01X1120528Y491120D02*
X1145516Y486120D01*
G01D02*
X1146163Y486249D01*
G01D02*
X1153609Y487739D01*
G01X1145516Y487089D02*
X1146163Y487218D01*
G01Y486249D02*
X1153609Y487739D01*
G01X1146163Y487218D02*
X1153609Y488708D01*
G01Y487739D02*
X1168278Y484804D01*
G01X1153609Y488708D02*
X1168278Y485773D01*
G01X1118118Y471720D02*
X1134819Y468380D01*
G01X1118164Y472680D02*
X1134819Y469349D01*
G01X1118118Y471720D02*
X1134819Y468380D01*
G01D02*
X1135722Y468199D01*
G01X1134819Y469349D02*
X1135722Y469168D01*
G01Y468199D02*
X1146163Y470287D01*
G01X1135722Y469168D02*
X1146163Y471256D01*
G01Y470287D02*
X1151267Y471308D01*
G01X1146163Y471256D02*
X1151267Y472277D01*
G01Y471308D02*
X1177225Y466115D01*
G01X1151267Y472277D02*
X1177227Y467084D01*
G01X1119535Y483355D02*
X1141972Y478868D01*
G01X1119581Y484315D02*
X1141972Y479837D01*
G01Y478868D02*
X1146163Y479704D01*
G01D02*
X1154167Y481302D01*
G01X1141972Y479837D02*
X1154167Y482271D01*
G01Y481302D02*
X1171661Y477803D01*
G01X1154167Y482271D02*
X1171661Y478772D01*
G01X1119966Y488186D02*
X1143981Y483383D01*
G01X1119920Y487226D02*
X1143980Y482414D01*
G01X1143981Y483383D02*
X1146163Y483815D01*
G01X1143980Y482414D02*
X1146163Y482847D01*
G01Y483815D02*
X1154002Y485369D01*
G01X1146163Y482847D02*
X1154001Y484400D01*
G01X1154002Y485369D02*
X1167858Y482598D01*
G01X1154001Y484400D02*
X1167858Y481629D01*
G01X1120574Y492080D02*
X1145516Y487089D01*
G01D02*
X1146163Y487218D01*
G01X1120528Y491120D02*
X1145516Y486120D01*
G01Y487089D02*
X1146163Y487218D01*
G01X1145516Y486120D02*
X1146163Y486249D01*
G01X1145516Y487089D02*
X1146163Y487218D01*
G01D02*
X1153609Y488708D01*
G01X1146163Y486249D02*
X1153609Y487739D01*
G01Y488708D02*
X1168278Y485773D01*
G01X1153609Y487739D02*
X1168278Y484804D01*
G01X1178913Y461892D02*
X1149330Y467807D01*
G01X1178915Y462861D02*
X1149330Y468776D01*
G01Y467807D02*
X1146163Y467174D01*
G01X1149330Y468776D02*
X1146163Y468143D01*
G01D02*
X1132420Y465396D01*
G01D02*
X1116174Y468645D01*
G01X1118685Y475606D02*
X1138052Y471733D01*
G01X1118731Y476566D02*
X1138052Y472702D01*
G01Y471733D02*
X1146163Y473358D01*
G01X1138052Y472702D02*
X1146163Y474327D01*
G01Y473358D02*
X1151416Y474410D01*
G01X1146163Y474327D02*
X1151416Y475379D01*
G01Y474410D02*
X1176448Y469400D01*
G01X1151416Y475379D02*
X1176448Y470369D01*
G01X1140378Y476257D02*
X1119354Y480462D01*
G01X1119308Y479502D02*
X1140378Y475288D01*
G01X1146163Y477414D02*
X1140378Y476257D01*
G01Y475288D02*
X1146163Y476445D01*
G01X1153796Y478940D02*
X1146163Y477414D01*
G01Y476445D02*
X1153796Y477971D01*
G01X1173039Y475089D02*
X1153796Y478940D01*
G01Y477971D02*
X1173039Y474120D01*
G01X1149417Y465679D02*
X1146163Y465028D01*
G01X1176273Y121514D02*
X1210680Y148140D01*
G01X1175868Y122402D02*
X1209817Y148675D01*
G01X1210680Y148140D02*
X1211400Y151741D01*
G01X1209817Y148675D02*
X1211400Y156596D01*
G01Y151741D02*
X1218796Y188727D01*
G01X1211400Y151741D02*
X1218796Y188727D01*
G01X1211400Y151741D02*
X1218796Y188727D01*
G01X1211400Y151741D02*
X1218796Y188727D01*
G01X1211400Y151741D02*
X1218796Y188727D01*
G01X1211400Y151741D02*
X1218796Y188727D01*
G01X1211400Y151741D02*
X1218796Y188727D01*
G01X1174469Y126811D02*
X1205903Y152015D01*
G01X1174891Y125931D02*
X1206774Y151494D01*
G01X1205903Y152015D02*
X1210061Y174531D01*
G01X1206774Y151494D02*
X1214154Y191446D01*
G01X1175868Y122402D02*
X1209817Y148675D01*
G01X1176273Y121514D02*
X1210680Y148140D01*
G01X1209817Y148675D02*
X1211400Y156596D01*
G01X1210680Y148140D02*
X1211400Y151741D01*
G01D02*
X1218796Y188727D01*
G01X1174891Y125931D02*
X1206774Y151494D01*
G01X1174469Y126811D02*
X1205903Y152015D01*
G01X1206774Y151494D02*
X1214154Y191446D01*
G01X1205903Y152015D02*
X1210061Y174531D01*
G01X1206774Y151494D02*
X1214154Y191446D01*
G01X1206774Y151494D02*
X1214154Y191446D01*
G01X1206774Y151494D02*
X1214154Y191446D01*
G01X1206774Y151494D02*
X1214154Y191446D01*
G01X1206774Y151494D02*
X1214154Y191446D01*
G01X1172796Y131032D02*
X1200448Y153454D01*
G01X1173227Y130157D02*
X1201319Y152937D01*
G01X1200448Y153454D02*
X1206873Y188442D01*
G01X1201319Y152937D02*
X1207829Y188388D01*
G01X1163958Y145689D02*
X1183651Y163405D01*
G01X1163482Y146540D02*
X1177570Y159214D01*
G01X1163958Y145689D02*
X1183651Y163405D01*
G01X1163958Y145689D02*
X1183651Y163405D01*
G01X1163958Y145689D02*
X1183651Y163405D01*
G01X1163958Y145689D02*
X1183651Y163405D01*
G01X1187631Y161972D02*
X1166781Y143702D01*
G01X1167245Y142845D02*
X1167764Y143300D01*
G01X1187631Y161972D02*
X1166781Y143702D01*
G01X1167764Y143300D02*
X1188508Y161476D01*
G01X1167348Y139000D02*
X1167400Y139014D01*
G01D02*
X1168372Y139278D01*
G01D02*
X1192285Y159331D01*
G01X1168823Y138415D02*
X1169521Y139000D01*
G01X1168372Y139278D02*
X1192285Y159331D01*
G01X1169521Y139000D02*
X1193161Y158825D01*
G01X1159950Y132335D02*
X1159951D01*
G01D02*
X1170990Y135155D01*
G01X1171431Y134286D02*
X1197347Y155623D01*
G01X1170990Y135155D02*
X1196468Y156130D01*
G01X1197347Y155623D02*
X1203083Y190099D01*
G01X1196468Y156130D02*
X1202131Y190171D01*
G01X1173227Y130157D02*
X1201319Y152937D01*
G01X1172796Y131032D02*
X1200448Y153454D01*
G01X1201319Y152937D02*
X1207829Y188388D01*
G01X1200448Y153454D02*
X1206873Y188442D01*
G01X1174891Y125931D02*
X1206774Y151494D01*
G01X1174469Y126811D02*
X1205903Y152015D01*
G01X1206774Y151494D02*
X1214154Y191446D01*
G01X1205903Y152015D02*
X1210061Y174531D01*
G01X1206774Y151494D02*
X1214154Y191446D01*
G01X1206774Y151494D02*
X1214154Y191446D01*
G01X1206774Y151494D02*
X1214154Y191446D01*
G01X1206774Y151494D02*
X1214154Y191446D01*
G01X1206774Y151494D02*
X1214154Y191446D01*
G01X1163482Y146540D02*
X1177570Y159214D01*
G01X1163958Y145689D02*
X1183651Y163405D01*
G01X1167245Y142845D02*
X1167764Y143300D01*
G01D02*
X1188508Y161476D01*
G01X1187631Y161972D02*
X1166781Y143702D01*
G01X1167348Y139000D02*
X1167400Y139014D01*
G01D02*
X1168372Y139278D01*
G01X1168823Y138415D02*
X1169521Y139000D01*
G01D02*
X1193161Y158825D01*
G01X1168372Y139278D02*
X1192285Y159331D01*
G01X1159950Y132335D02*
X1159951D01*
G01D02*
X1170990Y135155D01*
G01D02*
X1196468Y156130D01*
G01X1171431Y134286D02*
X1197347Y155623D01*
G01X1196468Y156130D02*
X1202131Y190171D01*
G01X1197347Y155623D02*
X1203083Y190099D01*
G01X1157608Y154983D02*
X1161550Y160963D01*
G01X1173071Y168825D02*
X1160479Y153236D01*
G01X1159831Y153946D02*
X1170005Y166543D01*
G01X1173071Y168825D02*
X1160479Y153236D01*
G01X1160688Y149268D02*
X1172223Y161681D01*
G01X1177849Y166337D02*
X1161209Y148432D01*
G01X1157608Y154983D02*
X1161550Y160963D01*
G01X1159831Y153946D02*
X1170005Y166543D01*
G01X1173071Y168825D02*
X1160479Y153236D01*
G01X1177849Y166337D02*
X1161209Y148432D01*
G01X1160688Y149268D02*
X1172223Y161681D01*
G01X1177849Y166337D02*
X1161209Y148432D01*
G01X1177849Y166337D02*
X1161209Y148432D01*
G01X1187631Y161972D02*
X1166781Y143702D01*
G01X1167245Y142845D02*
X1167764Y143300D01*
G01X1187631Y161972D02*
X1166781Y143702D01*
G01X1167764Y143300D02*
X1188508Y161476D01*
G01X1173227Y130157D02*
X1201319Y152937D01*
G01X1172796Y131032D02*
X1200448Y153454D01*
G01X1201319Y152937D02*
X1207829Y188388D01*
G01X1200448Y153454D02*
X1206873Y188442D01*
G01X1173071Y168825D02*
X1160479Y153236D01*
G01X1159831Y153946D02*
X1170005Y166543D01*
G01X1173071Y168825D02*
X1160479Y153236D01*
G01X1167348Y139000D02*
X1167400Y139014D01*
G01D02*
X1168372Y139278D01*
G01D02*
X1192285Y159331D01*
G01X1168823Y138415D02*
X1169521Y139000D01*
G01X1168372Y139278D02*
X1192285Y159331D01*
G01X1169521Y139000D02*
X1193161Y158825D01*
G01X1177849Y166337D02*
X1161209Y148432D01*
G01X1160688Y149268D02*
X1172223Y161681D01*
G01X1177849Y166337D02*
X1161209Y148432D01*
G01X1177849Y166337D02*
X1161209Y148432D01*
G01X1211400Y156596D02*
X1213718Y168196D01*
G01X1214141Y170306D02*
X1214405Y171629D01*
G01X1214828Y173739D02*
X1215092Y175062D01*
G01X1215515Y177172D02*
X1215779Y178495D01*
G01X1216202Y180605D02*
X1216466Y181928D01*
G01X1216889Y184038D02*
X1217153Y185361D01*
G01X1217576Y187471D02*
X1217840Y188794D01*
G01X1218796Y188727D02*
X1217906Y204324D01*
G01X1217840Y188794D02*
X1217424Y196092D01*
G01X1218796Y188727D02*
X1217906Y204324D01*
G01X1217301Y198240D02*
X1217225Y199587D01*
G01X1218796Y188727D02*
X1217906Y204324D01*
G01X1217101Y201735D02*
X1216961Y204203D01*
G01X1217906Y204324D02*
X1215186Y217933D01*
G01X1216961Y204203D02*
X1216368Y207170D01*
G01X1217906Y204324D02*
X1215186Y217933D01*
G01X1215946Y209280D02*
X1215682Y210603D01*
G01X1217906Y204324D02*
X1215186Y217933D01*
G01X1215260Y212713D02*
X1214996Y214036D01*
G01X1217906Y204324D02*
X1215186Y217933D01*
G01X1214573Y216146D02*
X1214309Y217469D01*
G01X1215186Y217933D02*
X1213735Y219408D01*
G01X1214309Y217469D02*
X1213135Y218663D01*
G01X1210452Y176646D02*
X1210697Y177973D01*
G01X1211088Y180088D02*
X1211333Y181415D01*
G01X1211724Y183530D02*
X1211969Y184857D01*
G01X1212360Y186972D02*
X1212605Y188299D01*
G01X1212996Y190414D02*
X1213200Y191515D01*
G01D02*
X1213128Y193368D01*
G01X1214154Y191446D02*
X1214074Y193510D01*
G01X1213128Y193368D02*
X1211735Y198612D01*
G01X1211246Y200450D02*
X1211015Y201319D01*
G01X1210526Y203157D02*
X1210280Y204085D01*
G01X1214074Y193510D02*
X1211400Y203571D01*
G01X1210526Y203157D02*
X1210280Y204085D01*
G01X1211400Y203571D02*
X1211180Y204399D01*
G01X1210280Y204085D02*
X1208460Y208247D01*
G01X1211180Y204399D02*
X1209331Y208627D01*
G01X1211400Y156596D02*
X1213718Y168196D01*
G01X1214141Y170306D02*
X1214405Y171629D01*
G01X1214828Y173739D02*
X1215092Y175062D01*
G01X1215515Y177172D02*
X1215779Y178495D01*
G01X1216202Y180605D02*
X1216466Y181928D01*
G01X1216889Y184038D02*
X1217153Y185361D01*
G01X1217576Y187471D02*
X1217840Y188794D01*
G01D02*
X1217424Y196092D01*
G01X1217301Y198240D02*
X1217225Y199587D01*
G01X1217101Y201735D02*
X1216961Y204203D01*
G01X1218796Y188727D02*
X1217906Y204324D01*
G01X1216961Y204203D02*
X1216368Y207170D01*
G01X1215946Y209280D02*
X1215682Y210603D01*
G01X1215260Y212713D02*
X1214996Y214036D01*
G01X1214573Y216146D02*
X1214309Y217469D01*
G01X1217906Y204324D02*
X1215186Y217933D01*
G01X1214309Y217469D02*
X1213135Y218663D01*
G01X1215186Y217933D02*
X1213735Y219408D01*
G01X1210452Y176646D02*
X1210697Y177973D01*
G01X1211088Y180088D02*
X1211333Y181415D01*
G01X1211724Y183530D02*
X1211969Y184857D01*
G01X1212360Y186972D02*
X1212605Y188299D01*
G01X1212996Y190414D02*
X1213200Y191515D01*
G01X1214154Y191446D02*
X1214074Y193510D01*
G01X1213200Y191515D02*
X1213128Y193368D01*
G01X1214074Y193510D02*
X1211400Y203571D01*
G01X1213128Y193368D02*
X1211735Y198612D01*
G01X1214074Y193510D02*
X1211400Y203571D01*
G01X1211246Y200450D02*
X1211015Y201319D01*
G01X1214074Y193510D02*
X1211400Y203571D01*
G01D02*
X1211180Y204399D01*
G01X1210526Y203157D02*
X1210280Y204085D01*
G01X1211180Y204399D02*
X1209331Y208627D01*
G01X1210280Y204085D02*
X1208460Y208247D01*
G01X1206873Y188442D02*
X1206292Y196982D01*
G01X1207829Y188388D02*
X1207232Y197165D01*
G01X1206292Y196982D02*
X1203930Y204172D01*
G01X1207232Y197165D02*
X1204785Y204614D01*
G01X1203930Y204172D02*
X1203154Y205223D01*
G01X1204785Y204614D02*
X1204023Y205646D01*
G01X1203154Y205223D02*
X1202683Y206922D01*
G01X1204023Y205646D02*
X1203599Y207176D01*
G01X1178605Y160682D02*
X1179170Y160653D01*
G01D02*
X1180173Y161555D01*
G01X1181208Y163024D02*
X1181773Y162994D01*
G01D02*
X1182776Y163896D01*
G01X1183651Y163405D02*
X1188652Y190171D01*
G01X1182776Y163896D02*
X1183193Y166133D01*
G01X1183651Y163405D02*
X1188652Y190171D01*
G01X1183589Y168247D02*
X1183836Y169574D01*
G01X1183651Y163405D02*
X1188652Y190171D01*
G01X1184232Y171688D02*
X1184479Y173015D01*
G01X1183651Y163405D02*
X1188652Y190171D01*
G01X1184875Y175129D02*
X1185122Y176456D01*
G01X1183651Y163405D02*
X1188652Y190171D01*
G01X1185518Y178570D02*
X1185765Y179897D01*
G01X1183651Y163405D02*
X1188652Y190171D01*
G01X1186161Y182011D02*
X1186408Y183338D01*
G01X1183651Y163405D02*
X1188652Y190171D01*
G01X1186804Y185452D02*
X1187694Y190220D01*
G01X1188652Y190171D02*
X1188075Y197169D01*
G01X1187694Y190220D02*
X1187128Y197092D01*
G01X1192795Y190633D02*
X1192556Y189305D01*
G01X1192174Y187188D02*
X1191935Y185860D01*
G01X1191553Y183743D02*
X1191314Y182415D01*
G01X1190932Y180298D02*
X1190693Y178970D01*
G01X1190311Y176853D02*
X1190072Y175525D01*
G01X1189690Y173408D02*
X1189451Y172080D01*
G01X1189069Y169963D02*
X1188830Y168635D01*
G01X1188449Y166518D02*
X1187631Y161972D01*
G01X1188508Y161476D02*
X1193767Y190669D01*
G01X1190668Y198866D02*
X1192795Y190633D01*
G01X1193767Y190669D02*
X1191597Y199069D01*
G01X1190463Y200001D02*
X1190661Y198901D01*
G01D02*
X1190668Y198866D01*
G01X1191597Y199069D02*
X1191399Y200169D01*
G01X1192285Y159331D02*
X1194630Y172639D01*
G01D02*
X1195148Y175579D01*
G01X1195479Y177451D02*
X1195722Y178831D01*
G01X1196053Y180703D02*
X1196365Y182476D01*
G01X1196696Y184348D02*
X1196956Y185825D01*
G01X1197287Y187697D02*
X1197756Y190360D01*
G01X1193161Y158825D02*
X1198732Y190420D01*
G01X1197756Y190360D02*
X1194630Y200552D01*
G01X1198732Y190420D02*
X1195556Y200773D01*
G01X1194606Y200630D02*
Y201247D01*
G01X1195556Y200773D02*
Y201235D01*
G01X1203083Y190099D02*
X1203015Y194750D01*
G01X1202131Y190171D02*
X1202066Y194650D01*
G01X1203015Y194750D02*
X1201583Y202022D01*
G01X1202066Y194650D02*
X1200671Y201732D01*
G01X1201583Y202022D02*
X1201003Y203297D01*
G01X1200671Y201732D02*
X1200138Y202903D01*
G01X1207829Y188388D02*
X1207232Y197165D01*
G01X1206873Y188442D02*
X1206292Y196982D01*
G01X1207232Y197165D02*
X1204785Y204614D01*
G01X1206292Y196982D02*
X1203930Y204172D01*
G01X1204785Y204614D02*
X1204023Y205646D01*
G01X1203930Y204172D02*
X1203154Y205223D01*
G01X1204023Y205646D02*
X1203599Y207176D01*
G01X1203154Y205223D02*
X1202683Y206922D01*
G01X1210452Y176646D02*
X1210697Y177973D01*
G01X1211088Y180088D02*
X1211333Y181415D01*
G01X1211724Y183530D02*
X1211969Y184857D01*
G01X1212360Y186972D02*
X1212605Y188299D01*
G01X1212996Y190414D02*
X1213200Y191515D01*
G01X1214154Y191446D02*
X1214074Y193510D01*
G01X1213200Y191515D02*
X1213128Y193368D01*
G01X1214074Y193510D02*
X1211400Y203571D01*
G01X1213128Y193368D02*
X1211735Y198612D01*
G01X1214074Y193510D02*
X1211400Y203571D01*
G01X1211246Y200450D02*
X1211015Y201319D01*
G01X1214074Y193510D02*
X1211400Y203571D01*
G01D02*
X1211180Y204399D01*
G01X1210526Y203157D02*
X1210280Y204085D01*
G01X1211180Y204399D02*
X1209331Y208627D01*
G01X1210280Y204085D02*
X1208460Y208247D01*
G01X1178605Y160682D02*
X1179170Y160653D01*
G01D02*
X1180173Y161555D01*
G01X1181208Y163024D02*
X1181773Y162994D01*
G01D02*
X1182776Y163896D01*
G01D02*
X1183193Y166133D01*
G01X1183589Y168247D02*
X1183836Y169574D01*
G01X1184232Y171688D02*
X1184479Y173015D01*
G01X1184875Y175129D02*
X1185122Y176456D01*
G01X1185518Y178570D02*
X1185765Y179897D01*
G01X1186161Y182011D02*
X1186408Y183338D01*
G01X1186804Y185452D02*
X1187694Y190220D01*
G01X1183651Y163405D02*
X1188652Y190171D01*
G01X1187694Y190220D02*
X1187128Y197092D01*
G01X1188652Y190171D02*
X1188075Y197169D01*
G01X1191597Y199069D02*
X1191399Y200169D01*
G01X1190463Y200001D02*
X1190661Y198901D01*
G01X1191597Y199069D02*
X1191399Y200169D01*
G01X1190661Y198901D02*
X1190668Y198866D01*
G01X1193767Y190669D02*
X1191597Y199069D01*
G01X1190668Y198866D02*
X1192795Y190633D01*
G01X1188508Y161476D02*
X1193767Y190669D01*
G01X1192795Y190633D02*
X1192556Y189305D01*
G01X1188508Y161476D02*
X1193767Y190669D01*
G01X1192174Y187188D02*
X1191935Y185860D01*
G01X1188508Y161476D02*
X1193767Y190669D01*
G01X1191553Y183743D02*
X1191314Y182415D01*
G01X1188508Y161476D02*
X1193767Y190669D01*
G01X1190932Y180298D02*
X1190693Y178970D01*
G01X1188508Y161476D02*
X1193767Y190669D01*
G01X1190311Y176853D02*
X1190072Y175525D01*
G01X1188508Y161476D02*
X1193767Y190669D01*
G01X1189690Y173408D02*
X1189451Y172080D01*
G01X1188508Y161476D02*
X1193767Y190669D01*
G01X1189069Y169963D02*
X1188830Y168635D01*
G01X1188508Y161476D02*
X1193767Y190669D01*
G01X1188449Y166518D02*
X1187631Y161972D01*
G01X1193161Y158825D02*
X1198732Y190420D01*
G01X1192285Y159331D02*
X1194630Y172639D01*
G01X1193161Y158825D02*
X1198732Y190420D01*
G01X1194630Y172639D02*
X1195148Y175579D01*
G01X1193161Y158825D02*
X1198732Y190420D01*
G01X1195479Y177451D02*
X1195722Y178831D01*
G01X1193161Y158825D02*
X1198732Y190420D01*
G01X1196053Y180703D02*
X1196365Y182476D01*
G01X1193161Y158825D02*
X1198732Y190420D01*
G01X1196696Y184348D02*
X1196956Y185825D01*
G01X1193161Y158825D02*
X1198732Y190420D01*
G01X1197287Y187697D02*
X1197756Y190360D01*
G01X1198732Y190420D02*
X1195556Y200773D01*
G01X1197756Y190360D02*
X1194630Y200552D01*
G01X1195556Y200773D02*
Y201235D01*
G01X1194606Y200630D02*
Y201247D01*
G01X1202131Y190171D02*
X1202066Y194650D01*
G01X1203083Y190099D02*
X1203015Y194750D01*
G01X1202066Y194650D02*
X1200671Y201732D01*
G01X1203015Y194750D02*
X1201583Y202022D01*
G01X1200671Y201732D02*
X1200138Y202903D01*
G01X1201583Y202022D02*
X1201003Y203297D01*
G01X1160740Y161461D02*
X1162682Y164861D01*
G01X1163625Y166512D02*
X1164071Y167293D01*
G01X1165015Y168944D02*
X1165878Y170455D01*
G01X1161550Y160963D02*
X1166753Y170070D01*
G01X1165878Y170455D02*
X1167400Y175214D01*
G01X1166753Y170070D02*
X1167400Y172093D01*
G01Y175214D02*
X1167415Y175261D01*
G01X1167994Y177072D02*
X1169451Y181629D01*
G01X1170031Y183439D02*
X1170305Y184296D01*
G01X1170885Y186107D02*
X1171356Y187580D01*
G01X1171936Y189391D02*
X1173031Y192814D01*
G01X1167400Y172093D02*
X1173925Y192490D01*
G01X1173031Y192814D02*
X1175040Y197758D01*
G01X1173925Y192490D02*
X1175920Y197400D01*
G01X1171357Y168216D02*
X1172205Y169266D01*
G01X1179857Y193992D02*
X1173071Y168825D01*
G01X1172205Y169266D02*
X1172592Y170703D01*
G01X1179857Y193992D02*
X1173071Y168825D01*
G01X1173152Y172780D02*
X1173503Y174083D01*
G01X1179857Y193992D02*
X1173071Y168825D01*
G01X1174063Y176160D02*
X1174414Y177463D01*
G01X1179857Y193992D02*
X1173071Y168825D01*
G01X1174975Y179540D02*
X1175326Y180843D01*
G01X1179857Y193992D02*
X1173071Y168825D01*
G01X1175886Y182920D02*
X1176237Y184223D01*
G01X1179857Y193992D02*
X1173071Y168825D01*
G01X1176797Y186300D02*
X1177148Y187603D01*
G01X1179857Y193992D02*
X1173071Y168825D01*
G01X1177709Y189680D02*
X1178060Y190983D01*
G01X1179857Y193992D02*
X1173071Y168825D01*
G01X1178621Y193060D02*
X1178972Y194363D01*
G01X1180004Y194243D02*
X1179857Y193992D01*
G01X1178972Y194363D02*
X1179054Y194502D01*
G01X1180004Y197400D02*
Y194243D01*
G01X1179054Y194502D02*
Y197400D01*
G01X1176989Y166809D02*
X1177629Y169266D01*
G01X1178172Y171347D02*
X1178512Y172653D01*
G01X1179056Y174734D02*
X1179396Y176040D01*
G01X1179940Y178121D02*
X1180280Y179427D01*
G01X1180824Y181508D02*
X1181164Y182814D01*
G01X1181708Y184895D02*
X1182048Y186201D01*
G01X1182592Y188282D02*
X1182932Y189588D01*
G01X1183882Y189465D02*
X1177849Y166337D01*
G01X1173688Y163257D02*
X1174606Y164245D01*
G01X1176070Y165821D02*
X1176989Y166809D01*
G01X1157481Y200148D02*
X1158335Y201193D01*
G01D02*
X1158689Y201547D01*
G01X1159041Y200555D02*
X1159361Y200875D01*
G01X1158730Y195703D02*
X1159478Y196826D01*
G01X1160672Y198615D02*
X1162182Y200881D01*
G01X1159183Y184701D02*
X1163366Y191023D01*
G01X1158493Y185381D02*
X1160593Y188556D01*
G01X1159183Y184701D02*
X1163366Y191023D01*
G01X1161781Y190351D02*
X1162525Y191476D01*
G01X1163366Y191023D02*
X1166943Y199402D01*
G01X1162525Y191476D02*
X1163328Y193359D01*
G01X1163366Y191023D02*
X1166943Y199402D01*
G01X1164173Y195337D02*
X1164703Y196578D01*
G01X1163366Y191023D02*
X1166943Y199402D01*
G01X1165548Y198556D02*
X1166078Y199797D01*
G01X1166943Y199402D02*
X1167235Y200001D01*
G01X1166078Y199797D02*
X1166381Y200418D01*
G01X1171068Y200773D02*
X1170554Y198965D01*
G01X1171982Y200513D02*
X1171439Y198597D01*
G01X1170552Y198958D02*
X1170033Y197712D01*
G01X1169205Y195727D02*
X1168686Y194481D01*
G01X1167858Y192496D02*
X1167400Y191397D01*
G01D02*
X1165925Y187857D01*
G01X1165097Y185872D02*
X1163919Y183043D01*
G01X1171429Y198592D02*
X1164686Y182411D01*
G01X1163919Y183043D02*
X1162796Y182295D01*
G01D02*
X1162242Y182405D01*
G01X1161007Y181101D02*
X1159884Y180353D01*
G01D02*
X1159330Y180463D01*
G01X1158094Y179159D02*
X1156971Y178411D01*
G01X1161550Y160963D02*
X1166753Y170070D01*
G01X1160740Y161461D02*
X1162682Y164861D01*
G01X1161550Y160963D02*
X1166753Y170070D01*
G01X1163625Y166512D02*
X1164071Y167293D01*
G01X1161550Y160963D02*
X1166753Y170070D01*
G01X1165015Y168944D02*
X1165878Y170455D01*
G01X1166753Y170070D02*
X1167400Y172093D01*
G01X1165878Y170455D02*
X1167400Y175214D01*
G01Y172093D02*
X1173925Y192490D01*
G01X1167400Y175214D02*
X1167415Y175261D01*
G01X1167400Y172093D02*
X1173925Y192490D01*
G01X1167994Y177072D02*
X1169451Y181629D01*
G01X1167400Y172093D02*
X1173925Y192490D01*
G01X1170031Y183439D02*
X1170305Y184296D01*
G01X1167400Y172093D02*
X1173925Y192490D01*
G01X1170885Y186107D02*
X1171356Y187580D01*
G01X1167400Y172093D02*
X1173925Y192490D01*
G01X1171936Y189391D02*
X1173031Y192814D01*
G01X1173925Y192490D02*
X1175920Y197400D01*
G01X1173031Y192814D02*
X1175040Y197758D01*
G01X1179054Y194502D02*
Y197400D01*
G01X1180004D02*
Y194243D01*
G01X1178972Y194363D02*
X1179054Y194502D01*
G01X1180004Y194243D02*
X1179857Y193992D01*
G01X1172205Y169266D02*
X1172592Y170703D01*
G01X1173152Y172780D02*
X1173503Y174083D01*
G01X1174063Y176160D02*
X1174414Y177463D01*
G01X1174975Y179540D02*
X1175326Y180843D01*
G01X1175886Y182920D02*
X1176237Y184223D01*
G01X1176797Y186300D02*
X1177148Y187603D01*
G01X1177709Y189680D02*
X1178060Y190983D01*
G01X1178621Y193060D02*
X1178972Y194363D01*
G01X1179857Y193992D02*
X1173071Y168825D01*
G01X1171357Y168216D02*
X1172205Y169266D01*
G01X1173688Y163257D02*
X1174606Y164245D01*
G01X1176070Y165821D02*
X1176989Y166809D01*
G01X1183882Y189465D02*
X1177849Y166337D01*
G01X1176989Y166809D02*
X1177629Y169266D01*
G01X1183882Y189465D02*
X1177849Y166337D01*
G01X1178172Y171347D02*
X1178512Y172653D01*
G01X1183882Y189465D02*
X1177849Y166337D01*
G01X1179056Y174734D02*
X1179396Y176040D01*
G01X1183882Y189465D02*
X1177849Y166337D01*
G01X1179940Y178121D02*
X1180280Y179427D01*
G01X1183882Y189465D02*
X1177849Y166337D01*
G01X1180824Y181508D02*
X1181164Y182814D01*
G01X1183882Y189465D02*
X1177849Y166337D01*
G01X1181708Y184895D02*
X1182048Y186201D01*
G01X1183882Y189465D02*
X1177849Y166337D01*
G01X1182592Y188282D02*
X1182932Y189588D01*
G01X1157481Y200148D02*
X1158335Y201193D01*
G01X1159041Y200555D02*
X1159361Y200875D01*
G01X1158335Y201193D02*
X1158689Y201547D01*
G01X1158730Y195703D02*
X1159478Y196826D01*
G01X1160672Y198615D02*
X1162182Y200881D01*
G01X1158493Y185381D02*
X1160593Y188556D01*
G01X1161781Y190351D02*
X1162525Y191476D01*
G01X1159183Y184701D02*
X1163366Y191023D01*
G01X1162525Y191476D02*
X1163328Y193359D01*
G01X1164173Y195337D02*
X1164703Y196578D01*
G01X1165548Y198556D02*
X1166078Y199797D01*
G01X1163366Y191023D02*
X1166943Y199402D01*
G01X1166078Y199797D02*
X1166381Y200418D01*
G01X1166943Y199402D02*
X1167235Y200001D01*
G01X1171982Y200513D02*
X1171439Y198597D01*
G01X1171068Y200773D02*
X1170554Y198965D01*
G01X1171429Y198592D02*
X1164686Y182411D01*
G01X1170552Y198958D02*
X1170033Y197712D01*
G01X1171429Y198592D02*
X1164686Y182411D01*
G01X1169205Y195727D02*
X1168686Y194481D01*
G01X1171429Y198592D02*
X1164686Y182411D01*
G01X1167858Y192496D02*
X1167400Y191397D01*
G01X1171429Y198592D02*
X1164686Y182411D01*
G01X1167400Y191397D02*
X1165925Y187857D01*
G01X1171429Y198592D02*
X1164686Y182411D01*
G01X1165097Y185872D02*
X1163919Y183043D01*
G01D02*
X1162796Y182295D01*
G01D02*
X1162242Y182405D01*
G01X1161007Y181101D02*
X1159884Y180353D01*
G01D02*
X1159330Y180463D01*
G01X1158094Y179159D02*
X1156971Y178411D01*
G01X1192795Y190633D02*
X1192556Y189305D01*
G01X1192174Y187188D02*
X1191935Y185860D01*
G01X1191553Y183743D02*
X1191314Y182415D01*
G01X1190932Y180298D02*
X1190693Y178970D01*
G01X1190311Y176853D02*
X1190072Y175525D01*
G01X1189690Y173408D02*
X1189451Y172080D01*
G01X1189069Y169963D02*
X1188830Y168635D01*
G01X1188449Y166518D02*
X1187631Y161972D01*
G01X1188508Y161476D02*
X1193767Y190669D01*
G01X1190668Y198866D02*
X1192795Y190633D01*
G01X1193767Y190669D02*
X1191597Y199069D01*
G01X1190463Y200001D02*
X1190661Y198901D01*
G01D02*
X1190668Y198866D01*
G01X1191597Y199069D02*
X1191399Y200169D01*
G01X1207829Y188388D02*
X1207232Y197165D01*
G01X1206873Y188442D02*
X1206292Y196982D01*
G01X1207232Y197165D02*
X1204785Y204614D01*
G01X1206292Y196982D02*
X1203930Y204172D01*
G01X1204785Y204614D02*
X1204023Y205646D01*
G01X1203930Y204172D02*
X1203154Y205223D01*
G01X1204023Y205646D02*
X1203599Y207176D01*
G01X1203154Y205223D02*
X1202683Y206922D01*
G01X1171357Y168216D02*
X1172205Y169266D01*
G01X1179857Y193992D02*
X1173071Y168825D01*
G01X1172205Y169266D02*
X1172592Y170703D01*
G01X1179857Y193992D02*
X1173071Y168825D01*
G01X1173152Y172780D02*
X1173503Y174083D01*
G01X1179857Y193992D02*
X1173071Y168825D01*
G01X1174063Y176160D02*
X1174414Y177463D01*
G01X1179857Y193992D02*
X1173071Y168825D01*
G01X1174975Y179540D02*
X1175326Y180843D01*
G01X1179857Y193992D02*
X1173071Y168825D01*
G01X1175886Y182920D02*
X1176237Y184223D01*
G01X1179857Y193992D02*
X1173071Y168825D01*
G01X1176797Y186300D02*
X1177148Y187603D01*
G01X1179857Y193992D02*
X1173071Y168825D01*
G01X1177709Y189680D02*
X1178060Y190983D01*
G01X1179857Y193992D02*
X1173071Y168825D01*
G01X1178621Y193060D02*
X1178972Y194363D01*
G01X1180004Y194243D02*
X1179857Y193992D01*
G01X1178972Y194363D02*
X1179054Y194502D01*
G01X1180004Y197400D02*
Y194243D01*
G01X1179054Y194502D02*
Y197400D01*
G01X1192285Y159331D02*
X1194630Y172639D01*
G01D02*
X1195148Y175579D01*
G01X1195479Y177451D02*
X1195722Y178831D01*
G01X1196053Y180703D02*
X1196365Y182476D01*
G01X1196696Y184348D02*
X1196956Y185825D01*
G01X1197287Y187697D02*
X1197756Y190360D01*
G01X1193161Y158825D02*
X1198732Y190420D01*
G01X1197756Y190360D02*
X1194630Y200552D01*
G01X1198732Y190420D02*
X1195556Y200773D01*
G01X1194606Y200630D02*
Y201247D01*
G01X1195556Y200773D02*
Y201235D01*
G01X1171068Y200773D02*
X1170554Y198965D01*
G01X1171982Y200513D02*
X1171439Y198597D01*
G01X1170552Y198958D02*
X1170033Y197712D01*
G01X1169205Y195727D02*
X1168686Y194481D01*
G01X1167858Y192496D02*
X1167400Y191397D01*
G01D02*
X1165925Y187857D01*
G01X1165097Y185872D02*
X1163919Y183043D01*
G01X1171429Y198592D02*
X1164686Y182411D01*
G01X1163919Y183043D02*
X1162796Y182295D01*
G01D02*
X1162242Y182405D01*
G01X1161007Y181101D02*
X1159884Y180353D01*
G01D02*
X1159330Y180463D01*
G01X1158094Y179159D02*
X1156971Y178411D01*
G01X1173688Y163257D02*
X1174606Y164245D01*
G01X1176070Y165821D02*
X1176989Y166809D01*
G01X1183882Y189465D02*
X1177849Y166337D01*
G01X1176989Y166809D02*
X1177629Y169266D01*
G01X1183882Y189465D02*
X1177849Y166337D01*
G01X1178172Y171347D02*
X1178512Y172653D01*
G01X1183882Y189465D02*
X1177849Y166337D01*
G01X1179056Y174734D02*
X1179396Y176040D01*
G01X1183882Y189465D02*
X1177849Y166337D01*
G01X1179940Y178121D02*
X1180280Y179427D01*
G01X1183882Y189465D02*
X1177849Y166337D01*
G01X1180824Y181508D02*
X1181164Y182814D01*
G01X1183882Y189465D02*
X1177849Y166337D01*
G01X1181708Y184895D02*
X1182048Y186201D01*
G01X1183882Y189465D02*
X1177849Y166337D01*
G01X1182592Y188282D02*
X1182932Y189588D01*
G01X1157481Y200148D02*
X1158335Y201193D01*
G01X1159041Y200555D02*
X1159361Y200875D01*
G01X1158335Y201193D02*
X1158689Y201547D01*
G01X1213735Y219408D02*
X1211400Y220878D01*
G01D02*
X1210667Y221340D01*
G01X1213135Y218663D02*
X1210070Y220592D01*
G01X1210667Y221340D02*
X1209544Y222463D01*
G01X1210070Y220592D02*
X1208871Y221791D01*
G01X1213135Y218663D02*
X1210070Y220592D01*
G01X1213735Y219408D02*
X1211400Y220878D01*
G01X1213135Y218663D02*
X1210070Y220592D01*
G01X1211400Y220878D02*
X1210667Y221340D01*
G01X1210070Y220592D02*
X1208871Y221791D01*
G01X1210667Y221340D02*
X1209544Y222463D01*
G01X1219754Y273422D02*
X1215687Y272743D01*
G01X1219511Y274345D02*
X1215230Y273630D01*
G01X1215687Y272743D02*
X1213460Y270516D01*
G01X1215230Y273630D02*
X1212510Y270910D01*
G01X1213460Y270516D02*
Y268509D01*
G01X1212510Y270910D02*
Y268903D01*
G01X1213460Y268509D02*
X1211373Y266422D01*
G01X1212510Y268903D02*
X1210979Y267372D01*
G01X1213460Y268509D02*
X1211373Y266422D01*
G01D02*
X1209657D01*
G01X1210979Y267372D02*
X1209657D01*
G01X1218990Y278850D02*
X1217849D01*
G01X1218990D02*
X1217849D01*
G01X1219225Y277900D02*
X1217900D01*
G01X1219511Y274345D02*
X1215230Y273630D01*
G01X1219754Y273422D02*
X1215687Y272743D01*
G01X1215230Y273630D02*
X1212510Y270910D01*
G01X1215687Y272743D02*
X1213460Y270516D01*
G01X1212510Y270910D02*
Y268903D01*
G01X1213460Y270516D02*
Y268509D01*
G01X1212510Y268903D02*
X1210979Y267372D01*
G01D02*
X1209657D01*
G01X1213460Y268509D02*
X1211373Y266422D01*
G01X1210979Y267372D02*
X1209657D01*
G01X1211373Y266422D02*
X1209657D01*
G01X1219511Y274345D02*
X1215230Y273630D01*
G01X1219754Y273422D02*
X1215687Y272743D01*
G01X1215230Y273630D02*
X1212510Y270910D01*
G01X1215687Y272743D02*
X1213460Y270516D01*
G01X1212510Y270910D02*
Y268903D01*
G01X1213460Y270516D02*
Y268509D01*
G01X1212510Y268903D02*
X1210979Y267372D01*
G01D02*
X1209657D01*
G01X1213460Y268509D02*
X1211373Y266422D01*
G01X1210979Y267372D02*
X1209657D01*
G01X1211373Y266422D02*
X1209657D01*
G01X1219225Y277900D02*
X1217900D01*
G01X1218990Y278850D02*
X1217849D01*
G01X1218990D02*
X1217849D01*
G01X1218990D02*
X1217849D01*
G01X1219225Y277900D02*
X1217900D01*
G01X1215823Y344556D02*
X1212637Y337651D01*
G01X1214866Y344750D02*
X1211837Y338187D01*
G01X1212637Y337651D02*
X1210174Y334993D01*
G01X1211837Y338187D02*
X1211400Y337715D01*
G01X1212637Y337651D02*
X1210174Y334993D01*
G01X1211400Y337715D02*
X1209376Y335531D01*
G01X1210174Y334993D02*
X1209281Y333088D01*
G01X1209376Y335531D02*
X1208359Y333360D01*
G01X1209281Y333088D02*
X1208720Y328970D01*
G01X1208359Y333360D02*
X1207610Y327860D01*
G01X1208720Y328970D02*
X1208290Y325810D01*
G01X1207610Y327860D02*
X1207366Y326072D01*
G01X1208290Y325810D02*
X1206811Y322500D01*
G01X1207366Y326072D02*
X1205770Y322500D01*
G01X1206811D02*
X1204410Y317129D01*
G01X1205770Y322500D02*
X1203460Y317332D01*
G01X1204410Y317129D02*
Y315668D01*
G01X1203460Y317332D02*
Y315668D01*
G01X1219268Y342708D02*
X1216905Y333914D01*
G01X1216421Y332111D02*
X1216187Y331244D01*
G01X1215701Y329437D02*
X1215466Y328566D01*
G01X1214981Y326763D02*
X1214747Y325896D01*
G01X1214261Y324089D02*
X1214027Y323222D01*
G01X1213541Y321415D02*
X1211632Y314279D01*
G01X1220215Y342570D02*
X1212506Y313867D01*
G01X1211632Y314279D02*
X1211400Y313953D01*
G01D02*
X1210125Y312163D01*
G01X1212506Y313867D02*
X1211400Y312315D01*
G01Y313953D02*
X1210125Y312163D01*
G01X1211400Y312315D02*
X1210853Y311547D01*
G01X1210125Y312163D02*
X1208276Y310314D01*
G01X1210853Y311547D02*
X1208948Y309642D01*
G01X1220257Y322500D02*
X1218369Y314335D01*
G01X1219282Y322500D02*
X1217473Y314680D01*
G01X1218350Y314300D02*
X1217548Y312861D01*
G01X1217473Y314680D02*
X1217261Y314300D01*
G01X1218350D02*
X1217548Y312861D01*
G01X1217261Y314300D02*
X1216782Y313440D01*
G01X1217548Y312861D02*
X1211509Y306821D01*
G01X1216782Y313440D02*
X1210837Y307493D01*
G01X1218953Y308277D02*
X1213265Y303899D01*
G01D02*
X1212788D01*
G01X1219688Y307643D02*
X1213589Y302949D01*
G01X1213265Y303899D02*
X1212788D01*
G01X1213589Y302949D02*
X1212788D01*
G01X1213762Y299769D02*
X1214061Y299771D01*
G01D02*
X1222597Y305751D01*
G01X1223321Y305098D02*
X1214362Y298821D01*
G01X1212528Y299769D02*
X1213460D01*
G01X1213464D02*
X1213762D01*
G01D02*
X1214061Y299771D01*
G01X1214362Y298821D02*
X1213467Y298819D01*
G01X1212528Y299769D02*
X1213460D01*
G01X1213464D02*
X1213762D01*
G01X1213467Y298819D02*
X1212528D01*
G01X1216663Y296666D02*
X1218798Y297702D01*
G01X1217078Y295811D02*
X1219166Y296824D01*
G01X1228093Y295423D02*
X1216265Y291100D01*
G01X1227435Y296194D02*
X1216096Y292050D01*
G01X1216265Y291100D02*
X1213400D01*
G01X1216096Y292050D02*
X1213013D01*
G01X1213400Y291100D02*
X1211836Y289568D01*
G01X1213013Y292050D02*
X1211164Y290240D01*
G01X1231058Y291796D02*
X1217934Y287000D01*
G01X1230400Y292567D02*
X1217765Y287950D01*
G01X1217934Y287000D02*
X1214900D01*
G01X1217765Y287950D02*
X1214506D01*
G01X1214900Y287000D02*
X1214300Y286400D01*
G01X1214506Y287950D02*
X1213700Y287144D01*
G01X1214866Y344750D02*
X1211837Y338187D01*
G01X1215823Y344556D02*
X1212637Y337651D01*
G01X1211837Y338187D02*
X1211400Y337715D01*
G01D02*
X1209376Y335531D01*
G01X1212637Y337651D02*
X1210174Y334993D01*
G01X1209376Y335531D02*
X1208359Y333360D01*
G01X1210174Y334993D02*
X1209281Y333088D01*
G01X1208359Y333360D02*
X1207610Y327860D01*
G01X1209281Y333088D02*
X1208720Y328970D01*
G01X1207610Y327860D02*
X1207366Y326072D01*
G01X1208720Y328970D02*
X1208290Y325810D01*
G01X1207366Y326072D02*
X1205770Y322500D01*
G01X1208290Y325810D02*
X1206811Y322500D01*
G01X1205770D02*
X1203460Y317332D01*
G01X1206811Y322500D02*
X1204410Y317129D01*
G01X1203460Y317332D02*
Y315668D01*
G01X1204410Y317129D02*
Y315668D01*
G01X1220215Y342570D02*
X1212506Y313867D01*
G01X1219268Y342708D02*
X1216905Y333914D01*
G01X1220215Y342570D02*
X1212506Y313867D01*
G01X1216421Y332111D02*
X1216187Y331244D01*
G01X1220215Y342570D02*
X1212506Y313867D01*
G01X1215701Y329437D02*
X1215466Y328566D01*
G01X1220215Y342570D02*
X1212506Y313867D01*
G01X1214981Y326763D02*
X1214747Y325896D01*
G01X1220215Y342570D02*
X1212506Y313867D01*
G01X1214261Y324089D02*
X1214027Y323222D01*
G01X1220215Y342570D02*
X1212506Y313867D01*
G01X1213541Y321415D02*
X1211632Y314279D01*
G01X1212506Y313867D02*
X1211400Y312315D01*
G01X1211632Y314279D02*
X1211400Y313953D01*
G01X1212506Y313867D02*
X1211400Y312315D01*
G01D02*
X1210853Y311547D01*
G01X1211400Y313953D02*
X1210125Y312163D01*
G01X1210853Y311547D02*
X1208948Y309642D01*
G01X1210125Y312163D02*
X1208276Y310314D01*
G01X1220215Y342570D02*
X1212506Y313867D01*
G01X1219268Y342708D02*
X1216905Y333914D01*
G01X1220215Y342570D02*
X1212506Y313867D01*
G01X1216421Y332111D02*
X1216187Y331244D01*
G01X1220215Y342570D02*
X1212506Y313867D01*
G01X1215701Y329437D02*
X1215466Y328566D01*
G01X1220215Y342570D02*
X1212506Y313867D01*
G01X1214981Y326763D02*
X1214747Y325896D01*
G01X1220215Y342570D02*
X1212506Y313867D01*
G01X1214261Y324089D02*
X1214027Y323222D01*
G01X1220215Y342570D02*
X1212506Y313867D01*
G01X1213541Y321415D02*
X1211632Y314279D01*
G01X1212506Y313867D02*
X1211400Y312315D01*
G01X1211632Y314279D02*
X1211400Y313953D01*
G01X1212506Y313867D02*
X1211400Y312315D01*
G01D02*
X1210853Y311547D01*
G01X1211400Y313953D02*
X1210125Y312163D01*
G01X1210853Y311547D02*
X1208948Y309642D01*
G01X1210125Y312163D02*
X1208276Y310314D01*
G01X1219282Y322500D02*
X1217473Y314680D01*
G01X1220257Y322500D02*
X1218369Y314335D01*
G01X1217473Y314680D02*
X1217261Y314300D01*
G01D02*
X1216782Y313440D01*
G01X1218350Y314300D02*
X1217548Y312861D01*
G01X1216782Y313440D02*
X1210837Y307493D01*
G01X1217548Y312861D02*
X1211509Y306821D01*
G01X1219688Y307643D02*
X1213589Y302949D01*
G01X1218953Y308277D02*
X1213265Y303899D01*
G01X1219688Y307643D02*
X1213589Y302949D01*
G01D02*
X1212788D01*
G01X1213265Y303899D02*
X1212788D01*
G01X1214362Y298821D02*
X1213467Y298819D01*
G01D02*
X1212528D01*
G01Y299769D02*
X1213460D01*
G01X1214362Y298821D02*
X1213467Y298819D01*
G01D02*
X1212528D01*
G01X1213464Y299769D02*
X1213762D01*
G01X1223321Y305098D02*
X1214362Y298821D01*
G01D02*
X1213467Y298819D01*
G01X1213762Y299769D02*
X1214061Y299771D01*
G01X1223321Y305098D02*
X1214362Y298821D01*
G01X1214061Y299771D02*
X1222597Y305751D01*
G01X1217078Y295811D02*
X1219166Y296824D01*
G01X1216663Y296666D02*
X1218798Y297702D01*
G01X1227435Y296194D02*
X1216096Y292050D01*
G01X1228093Y295423D02*
X1216265Y291100D01*
G01X1216096Y292050D02*
X1213013D01*
G01X1216265Y291100D02*
X1213400D01*
G01X1213013Y292050D02*
X1211164Y290240D01*
G01X1213400Y291100D02*
X1211836Y289568D01*
G01X1230400Y292567D02*
X1217765Y287950D01*
G01X1231058Y291796D02*
X1217934Y287000D01*
G01X1217765Y287950D02*
X1214506D01*
G01X1217934Y287000D02*
X1214900D01*
G01X1214506Y287950D02*
X1213700Y287144D01*
G01X1214900Y287000D02*
X1214300Y286400D01*
G01X1230400Y292567D02*
X1217765Y287950D01*
G01X1231058Y291796D02*
X1217934Y287000D01*
G01X1217765Y287950D02*
X1214506D01*
G01X1217934Y287000D02*
X1214900D01*
G01X1214506Y287950D02*
X1213700Y287144D01*
G01X1214900Y287000D02*
X1214300Y286400D01*
G01X1220257Y322500D02*
X1218369Y314335D01*
G01X1219282Y322500D02*
X1217473Y314680D01*
G01X1218350Y314300D02*
X1217548Y312861D01*
G01X1217473Y314680D02*
X1217261Y314300D01*
G01X1218350D02*
X1217548Y312861D01*
G01X1217261Y314300D02*
X1216782Y313440D01*
G01X1217548Y312861D02*
X1211509Y306821D01*
G01X1216782Y313440D02*
X1210837Y307493D01*
G01X1218953Y308277D02*
X1213265Y303899D01*
G01D02*
X1212788D01*
G01X1219688Y307643D02*
X1213589Y302949D01*
G01X1213265Y303899D02*
X1212788D01*
G01X1213589Y302949D02*
X1212788D01*
G01X1231058Y291796D02*
X1217934Y287000D01*
G01X1230400Y292567D02*
X1217765Y287950D01*
G01X1217934Y287000D02*
X1214900D01*
G01X1217765Y287950D02*
X1214506D01*
G01X1214900Y287000D02*
X1214300Y286400D01*
G01X1214506Y287950D02*
X1213700Y287144D01*
G01X1219688Y307643D02*
X1213589Y302949D01*
G01X1218953Y308277D02*
X1213265Y303899D01*
G01X1219688Y307643D02*
X1213589Y302949D01*
G01D02*
X1212788D01*
G01X1213265Y303899D02*
X1212788D01*
G01X1227435Y296194D02*
X1216096Y292050D01*
G01X1228093Y295423D02*
X1216265Y291100D01*
G01X1216096Y292050D02*
X1213013D01*
G01X1216265Y291100D02*
X1213400D01*
G01X1213013Y292050D02*
X1211164Y290240D01*
G01X1213400Y291100D02*
X1211836Y289568D01*
G01X1216663Y296666D02*
X1218798Y297702D01*
G01X1217078Y295811D02*
X1219166Y296824D01*
G01X1219282Y322500D02*
X1217473Y314680D01*
G01X1220257Y322500D02*
X1218369Y314335D01*
G01X1217473Y314680D02*
X1217261Y314300D01*
G01D02*
X1216782Y313440D01*
G01X1218350Y314300D02*
X1217548Y312861D01*
G01X1216782Y313440D02*
X1210837Y307493D01*
G01X1217548Y312861D02*
X1211509Y306821D01*
G01X1214362Y298821D02*
X1213467Y298819D01*
G01D02*
X1212528D01*
G01Y299769D02*
X1213460D01*
G01X1214362Y298821D02*
X1213467Y298819D01*
G01D02*
X1212528D01*
G01X1213464Y299769D02*
X1213762D01*
G01X1223321Y305098D02*
X1214362Y298821D01*
G01D02*
X1213467Y298819D01*
G01X1213762Y299769D02*
X1214061Y299771D01*
G01X1223321Y305098D02*
X1214362Y298821D01*
G01X1214061Y299771D02*
X1222597Y305751D01*
G01X1217078Y295811D02*
X1219166Y296824D01*
G01X1216663Y296666D02*
X1218798Y297702D01*
G01X1199451Y410747D02*
X1210794Y397826D01*
G01X1198832Y410012D02*
X1209945Y397353D01*
G01X1210794Y397826D02*
X1211400Y395844D01*
G01D02*
X1211568Y395294D01*
G01X1209945Y397353D02*
X1210632Y395104D01*
G01X1211568Y395294D02*
X1215345Y359585D01*
G01X1210632Y395104D02*
X1213133Y371449D01*
G01X1211568Y395294D02*
X1215345Y359585D01*
G01X1213333Y369558D02*
X1213371Y369200D01*
G01X1211568Y395294D02*
X1215345Y359585D01*
G01X1213371Y369200D02*
X1214396Y359519D01*
G01X1215345Y359585D02*
X1215630Y350630D01*
G01X1214396Y359519D02*
X1214708Y349708D01*
G01X1215630Y350630D02*
X1215823Y344556D01*
G01X1214708Y349708D02*
X1214866Y344750D01*
G01X1203466Y410710D02*
X1213433Y399518D01*
G01X1204083Y411446D02*
X1214279Y399997D01*
G01X1213433Y399518D02*
X1214304Y396732D01*
G01X1214279Y399997D02*
X1215239Y396926D01*
G01X1214304Y396732D02*
X1216981Y371532D01*
G01X1215239Y396926D02*
X1217900Y371882D01*
G01X1216981Y371532D02*
X1219910Y367453D01*
G01X1217900Y371882D02*
X1220868Y367748D01*
G01X1208016Y412762D02*
X1218141Y401553D01*
G01X1207406Y412020D02*
X1217299Y401066D01*
G01X1218141Y401553D02*
X1219396Y397681D01*
G01X1217299Y401066D02*
X1218460Y397486D01*
G01D02*
X1220767Y373820D01*
G01X1198832Y410012D02*
X1209945Y397353D01*
G01X1199451Y410747D02*
X1210794Y397826D01*
G01X1209945Y397353D02*
X1210632Y395104D01*
G01X1210794Y397826D02*
X1211400Y395844D01*
G01X1209945Y397353D02*
X1210632Y395104D01*
G01X1211400Y395844D02*
X1211568Y395294D01*
G01X1210632Y395104D02*
X1213133Y371449D01*
G01X1213333Y369558D02*
X1213371Y369200D01*
G01D02*
X1214396Y359519D01*
G01X1211568Y395294D02*
X1215345Y359585D01*
G01X1214396Y359519D02*
X1214708Y349708D01*
G01X1215345Y359585D02*
X1215630Y350630D01*
G01X1214708Y349708D02*
X1214866Y344750D01*
G01X1215630Y350630D02*
X1215823Y344556D01*
G01X1204083Y411446D02*
X1214279Y399997D01*
G01X1203466Y410710D02*
X1213433Y399518D01*
G01X1214279Y399997D02*
X1215239Y396926D01*
G01X1213433Y399518D02*
X1214304Y396732D01*
G01X1215239Y396926D02*
X1217900Y371882D01*
G01X1214304Y396732D02*
X1216981Y371532D01*
G01X1217900Y371882D02*
X1220868Y367748D01*
G01X1216981Y371532D02*
X1219910Y367453D01*
G01X1204083Y411446D02*
X1214279Y399997D01*
G01X1203466Y410710D02*
X1213433Y399518D01*
G01X1214279Y399997D02*
X1215239Y396926D01*
G01X1213433Y399518D02*
X1214304Y396732D01*
G01X1215239Y396926D02*
X1217900Y371882D01*
G01X1214304Y396732D02*
X1216981Y371532D01*
G01X1217900Y371882D02*
X1220868Y367748D01*
G01X1216981Y371532D02*
X1219910Y367453D01*
G01X1207406Y412020D02*
X1217299Y401066D01*
G01X1208016Y412762D02*
X1218141Y401553D01*
G01X1217299Y401066D02*
X1218460Y397486D01*
G01X1218141Y401553D02*
X1219396Y397681D01*
G01X1218460Y397486D02*
X1220767Y373820D01*
G01X1208016Y412762D02*
X1218141Y401553D01*
G01X1207406Y412020D02*
X1217299Y401066D01*
G01X1218141Y401553D02*
X1219396Y397681D01*
G01X1217299Y401066D02*
X1218460Y397486D01*
G01D02*
X1220767Y373820D01*
G01X1207406Y412020D02*
X1217299Y401066D01*
G01X1208016Y412762D02*
X1218141Y401553D01*
G01X1217299Y401066D02*
X1218460Y397486D01*
G01X1218141Y401553D02*
X1219396Y397681D01*
G01X1218460Y397486D02*
X1220767Y373820D01*
G01X1176209Y410252D02*
X1180557Y411121D01*
G01X1182401Y411490D02*
X1189284Y412866D01*
G01X1189310Y413841D02*
X1198039Y411612D01*
G01X1189284Y412866D02*
X1197664Y410726D01*
G01X1198039Y411612D02*
X1199451Y410747D01*
G01X1197664Y410726D02*
X1198831Y410012D01*
G01X1198039Y411612D02*
X1199451Y410747D01*
G01X1198831Y410012D02*
X1198832D01*
G01X1200906Y448942D02*
X1217449Y443008D01*
G01X1200651Y448024D02*
X1217062Y442137D01*
G01X1217449Y443008D02*
X1231509Y435481D01*
G01X1217062Y442137D02*
X1230949Y434703D01*
G01X1218355Y445796D02*
X1235152Y436809D01*
G01X1206590Y450016D02*
X1218355Y445796D01*
G01X1218742Y446667D02*
X1206845Y450934D01*
G01X1237984Y440723D02*
X1216356Y452297D01*
G01X1237424Y439945D02*
X1216031Y451392D01*
G01X1239617Y443125D02*
X1216521Y455485D01*
G01X1240177Y443903D02*
X1216846Y456390D01*
G01X1216521Y455485D02*
X1181719Y462445D01*
G01X1216846Y456390D02*
X1181720Y463414D01*
G01X1181719Y462445D02*
X1178913Y461892D01*
G01X1181720Y463414D02*
X1178915Y462861D01*
G01X1180176Y467664D02*
X1218168Y460066D01*
G01X1180174Y466695D02*
X1217843Y459161D01*
G01X1218168Y460066D02*
X1243126Y446707D01*
G01X1217843Y459161D02*
X1242566Y445929D01*
G01X1181378Y470386D02*
X1219203Y462822D01*
G01X1181378Y471355D02*
X1219529Y463726D01*
G01X1190601Y416272D02*
X1197354Y414473D01*
G01X1190632Y417248D02*
X1197734Y415356D01*
G01X1197354Y414473D02*
X1203466Y410710D01*
G01X1197734Y415356D02*
X1204083Y411446D01*
G01X1191163Y420443D02*
X1198057Y418730D01*
G01X1191141Y419469D02*
X1197690Y417842D01*
G01X1198057Y418730D02*
X1208016Y412762D01*
G01X1197690Y417842D02*
X1207406Y412020D01*
G01X1192191Y422758D02*
X1198447Y421021D01*
G01X1192227Y423735D02*
X1198829Y421901D01*
G01X1198447Y421021D02*
X1211400Y413111D01*
G01X1198829Y421901D02*
X1211400Y414225D01*
G01X1198447Y421021D02*
X1211400Y413111D01*
G01D02*
X1211872Y412823D01*
G01X1211400Y414225D02*
X1212480Y413565D01*
G01X1211872Y412823D02*
X1221221Y402692D01*
G01X1212480Y413565D02*
X1217245Y408403D01*
G01X1211872Y412823D02*
X1221221Y402692D01*
G01X1217245Y408402D02*
X1222080Y403163D01*
G01X1193537Y426208D02*
X1194630Y425907D01*
G01D02*
X1199973Y424433D01*
G01X1193572Y427184D02*
X1200349Y425315D01*
G01X1199973Y424433D02*
X1214407Y415854D01*
G01X1200349Y425315D02*
X1215003Y416606D01*
G01X1214407Y415854D02*
X1224805Y405072D01*
G01X1215003Y416606D02*
X1225664Y405551D01*
G01X1194645Y429798D02*
X1201476Y427941D01*
G01X1194678Y430774D02*
X1201725Y428858D01*
G01X1194645Y429798D02*
X1201476Y427941D01*
G01X1201725Y428859D02*
X1201849Y428825D01*
G01X1201476Y427941D02*
X1216834Y418874D01*
G01X1201849Y428825D02*
X1217428Y419628D01*
G01X1216834Y418874D02*
X1228533Y406799D01*
G01X1217428Y419628D02*
X1229397Y407274D01*
G01X1196300Y434534D02*
X1202972Y432674D01*
G01X1196267Y433556D02*
X1202596Y431792D01*
G01X1202972Y432674D02*
X1219915Y422646D01*
G01X1202596Y431792D02*
X1219323Y421892D01*
G01X1195408Y438523D02*
X1206319Y435106D01*
G01X1195368Y437540D02*
X1205936Y434230D01*
G01X1195408Y438523D02*
X1206319Y435106D01*
G01D02*
X1222255Y426024D01*
G01X1205936Y434230D02*
X1205937D01*
G01X1206319Y435106D02*
X1222255Y426024D01*
G01X1205937Y434230D02*
X1221665Y425266D01*
G01X1190732Y443581D02*
X1207494Y437599D01*
G01X1190989Y444498D02*
X1207876Y438472D01*
G01X1207494Y437599D02*
X1224348Y428788D01*
G01X1207876Y438472D02*
X1224905Y429570D01*
G01X1194630Y446920D02*
X1194735Y446899D01*
G01X1194482Y445981D02*
X1194630Y445929D01*
G01D02*
X1212408Y439716D01*
G01X1194735Y446899D02*
X1212792Y440589D01*
G01X1212408Y439716D02*
X1226879Y431964D01*
G01X1212792Y440589D02*
X1227436Y432744D01*
G01X1176209Y410252D02*
X1180557Y411121D01*
G01X1182401Y411490D02*
X1189284Y412866D01*
G01D02*
X1197664Y410726D01*
G01X1189310Y413841D02*
X1198039Y411612D01*
G01X1197664Y410726D02*
X1198831Y410012D01*
G01D02*
X1198832D01*
G01X1198039Y411612D02*
X1199451Y410747D01*
G01X1200651Y448024D02*
X1217062Y442137D01*
G01X1200906Y448942D02*
X1217449Y443008D01*
G01X1217062Y442137D02*
X1230949Y434703D01*
G01X1217449Y443008D02*
X1231509Y435481D01*
G01X1200651Y448024D02*
X1217062Y442137D01*
G01X1200906Y448942D02*
X1217449Y443008D01*
G01X1217062Y442137D02*
X1230949Y434703D01*
G01X1217449Y443008D02*
X1231509Y435481D01*
G01X1218742Y446667D02*
X1206845Y450934D01*
G01X1206590Y450016D02*
X1218355Y445796D01*
G01D02*
X1235152Y436809D01*
G01X1237424Y439945D02*
X1216031Y451392D01*
G01X1237984Y440723D02*
X1216356Y452297D01*
G01X1240177Y443903D02*
X1216846Y456390D01*
G01X1239617Y443125D02*
X1216521Y455485D01*
G01X1216846Y456390D02*
X1181720Y463414D01*
G01X1216521Y455485D02*
X1181719Y462445D01*
G01X1181720Y463414D02*
X1178915Y462861D01*
G01X1181719Y462445D02*
X1178913Y461892D01*
G01X1180174Y466695D02*
X1217843Y459161D01*
G01X1180176Y467664D02*
X1218168Y460066D01*
G01X1217843Y459161D02*
X1242566Y445929D01*
G01X1218168Y460066D02*
X1243126Y446707D01*
G01X1181378Y471355D02*
X1219529Y463726D01*
G01X1181378Y470386D02*
X1219203Y462822D01*
G01X1190632Y417248D02*
X1197734Y415356D01*
G01X1190601Y416272D02*
X1197354Y414473D01*
G01X1197734Y415356D02*
X1204083Y411446D01*
G01X1197354Y414473D02*
X1203466Y410710D01*
G01X1190632Y417248D02*
X1197734Y415356D01*
G01X1190601Y416272D02*
X1197354Y414473D01*
G01X1197734Y415356D02*
X1204083Y411446D01*
G01X1197354Y414473D02*
X1203466Y410710D01*
G01X1191141Y419469D02*
X1197690Y417842D01*
G01X1191163Y420443D02*
X1198057Y418730D01*
G01X1197690Y417842D02*
X1207406Y412020D01*
G01X1198057Y418730D02*
X1208016Y412762D01*
G01X1192227Y423735D02*
X1198829Y421901D01*
G01X1192191Y422758D02*
X1198447Y421021D01*
G01X1198829Y421901D02*
X1211400Y414225D01*
G01D02*
X1212480Y413565D01*
G01X1198447Y421021D02*
X1211400Y413111D01*
G01Y414225D02*
X1212480Y413565D01*
G01X1211400Y413111D02*
X1211872Y412823D01*
G01X1212480Y413565D02*
X1217245Y408403D01*
G01Y408402D02*
X1222080Y403163D01*
G01X1211872Y412823D02*
X1221221Y402692D01*
G01X1193572Y427184D02*
X1200349Y425315D01*
G01X1193537Y426208D02*
X1194630Y425907D01*
G01X1193572Y427184D02*
X1200349Y425315D01*
G01X1194630Y425907D02*
X1199973Y424433D01*
G01X1200349Y425315D02*
X1215003Y416606D01*
G01X1199973Y424433D02*
X1214407Y415854D01*
G01X1215003Y416606D02*
X1225664Y405551D01*
G01X1214407Y415854D02*
X1224805Y405072D01*
G01X1194678Y430774D02*
X1201725Y428858D01*
G01Y428859D02*
X1201849Y428825D01*
G01X1194645Y429798D02*
X1201476Y427941D01*
G01X1201849Y428825D02*
X1217428Y419628D01*
G01X1201476Y427941D02*
X1216834Y418874D01*
G01X1217428Y419628D02*
X1229397Y407274D01*
G01X1216834Y418874D02*
X1228533Y406799D01*
G01X1196267Y433556D02*
X1202596Y431792D01*
G01X1196300Y434534D02*
X1202972Y432674D01*
G01X1202596Y431792D02*
X1219323Y421892D01*
G01X1202972Y432674D02*
X1219915Y422646D01*
G01X1195368Y437540D02*
X1205936Y434230D01*
G01D02*
X1205937D01*
G01X1195408Y438523D02*
X1206319Y435106D01*
G01X1205936Y434230D02*
X1205937D01*
G01D02*
X1221665Y425266D01*
G01X1206319Y435106D02*
X1222255Y426024D01*
G01X1190989Y444498D02*
X1207876Y438472D01*
G01X1190732Y443581D02*
X1207494Y437599D01*
G01X1207876Y438472D02*
X1224905Y429570D01*
G01X1207494Y437599D02*
X1224348Y428788D01*
G01X1194630Y446920D02*
X1194735Y446899D01*
G01D02*
X1212792Y440589D01*
G01X1194482Y445981D02*
X1194630Y445929D01*
G01X1194735Y446899D02*
X1212792Y440589D01*
G01X1194630Y445929D02*
X1212408Y439716D01*
G01X1212792Y440589D02*
X1227436Y432744D01*
G01X1212408Y439716D02*
X1226879Y431964D01*
G01X1180174Y466695D02*
X1217843Y459161D01*
G01X1180176Y467664D02*
X1218168Y460066D01*
G01X1217843Y459161D02*
X1242566Y445929D01*
G01X1218168Y460066D02*
X1243126Y446707D01*
G01X1218355Y445796D02*
X1235152Y436809D01*
G01X1206590Y450016D02*
X1218355Y445796D01*
G01X1218742Y446667D02*
X1206845Y450934D01*
G01X1239617Y443125D02*
X1216521Y455485D01*
G01X1240177Y443903D02*
X1216846Y456390D01*
G01X1216521Y455485D02*
X1181719Y462445D01*
G01X1216846Y456390D02*
X1181720Y463414D01*
G01X1181719Y462445D02*
X1178913Y461892D01*
G01X1181720Y463414D02*
X1178915Y462861D01*
G01X1181378Y470386D02*
X1219203Y462822D01*
G01X1181378Y471355D02*
X1219529Y463726D01*
G01X1237424Y439945D02*
X1216031Y451392D01*
G01X1237984Y440723D02*
X1216356Y452297D01*
G01X1195368Y437540D02*
X1205936Y434230D01*
G01D02*
X1205937D01*
G01X1195408Y438523D02*
X1206319Y435106D01*
G01X1205936Y434230D02*
X1205937D01*
G01D02*
X1221665Y425266D01*
G01X1206319Y435106D02*
X1222255Y426024D01*
G01X1194630Y446920D02*
X1194735Y446899D01*
G01X1194482Y445981D02*
X1194630Y445929D01*
G01D02*
X1212408Y439716D01*
G01X1194735Y446899D02*
X1212792Y440589D01*
G01X1212408Y439716D02*
X1226879Y431964D01*
G01X1212792Y440589D02*
X1227436Y432744D01*
G01X1191163Y420443D02*
X1198057Y418730D01*
G01X1191141Y419469D02*
X1197690Y417842D01*
G01X1198057Y418730D02*
X1208016Y412762D01*
G01X1197690Y417842D02*
X1207406Y412020D01*
G01X1192191Y422758D02*
X1198447Y421021D01*
G01X1192227Y423735D02*
X1198829Y421901D01*
G01X1198447Y421021D02*
X1211400Y413111D01*
G01X1198829Y421901D02*
X1211400Y414225D01*
G01X1198447Y421021D02*
X1211400Y413111D01*
G01D02*
X1211872Y412823D01*
G01X1211400Y414225D02*
X1212480Y413565D01*
G01X1211872Y412823D02*
X1221221Y402692D01*
G01X1212480Y413565D02*
X1217245Y408403D01*
G01X1211872Y412823D02*
X1221221Y402692D01*
G01X1217245Y408402D02*
X1222080Y403163D01*
G01X1195408Y438523D02*
X1206319Y435106D01*
G01X1195368Y437540D02*
X1205936Y434230D01*
G01X1195408Y438523D02*
X1206319Y435106D01*
G01D02*
X1222255Y426024D01*
G01X1205936Y434230D02*
X1205937D01*
G01X1206319Y435106D02*
X1222255Y426024D01*
G01X1205937Y434230D02*
X1221665Y425266D01*
G01X1192227Y423735D02*
X1198829Y421901D01*
G01X1192191Y422758D02*
X1198447Y421021D01*
G01X1198829Y421901D02*
X1211400Y414225D01*
G01D02*
X1212480Y413565D01*
G01X1198447Y421021D02*
X1211400Y413111D01*
G01Y414225D02*
X1212480Y413565D01*
G01X1211400Y413111D02*
X1211872Y412823D01*
G01X1212480Y413565D02*
X1217245Y408403D01*
G01Y408402D02*
X1222080Y403163D01*
G01X1211872Y412823D02*
X1221221Y402692D01*
G01X1196267Y433556D02*
X1202596Y431792D01*
G01X1196300Y434534D02*
X1202972Y432674D01*
G01X1202596Y431792D02*
X1219323Y421892D01*
G01X1202972Y432674D02*
X1219915Y422646D01*
G01X1190989Y444498D02*
X1207876Y438472D01*
G01X1190732Y443581D02*
X1207494Y437599D01*
G01X1207876Y438472D02*
X1224905Y429570D01*
G01X1207494Y437599D02*
X1224348Y428788D01*
G01X1194645Y429798D02*
X1201476Y427941D01*
G01X1194678Y430774D02*
X1201725Y428858D01*
G01X1194645Y429798D02*
X1201476Y427941D01*
G01X1201725Y428859D02*
X1201849Y428825D01*
G01X1201476Y427941D02*
X1216834Y418874D01*
G01X1201849Y428825D02*
X1217428Y419628D01*
G01X1216834Y418874D02*
X1228533Y406799D01*
G01X1217428Y419628D02*
X1229397Y407274D01*
G01X1191141Y419469D02*
X1197690Y417842D01*
G01X1191163Y420443D02*
X1198057Y418730D01*
G01X1197690Y417842D02*
X1207406Y412020D01*
G01X1198057Y418730D02*
X1208016Y412762D01*
G01X1193572Y427184D02*
X1200349Y425315D01*
G01X1193537Y426208D02*
X1194630Y425907D01*
G01X1193572Y427184D02*
X1200349Y425315D01*
G01X1194630Y425907D02*
X1199973Y424433D01*
G01X1200349Y425315D02*
X1215003Y416606D01*
G01X1199973Y424433D02*
X1214407Y415854D01*
G01X1215003Y416606D02*
X1225664Y405551D01*
G01X1214407Y415854D02*
X1224805Y405072D01*
G01X1194678Y430774D02*
X1201725Y428858D01*
G01Y428859D02*
X1201849Y428825D01*
G01X1194645Y429798D02*
X1201476Y427941D01*
G01X1201849Y428825D02*
X1217428Y419628D01*
G01X1201476Y427941D02*
X1216834Y418874D01*
G01X1217428Y419628D02*
X1229397Y407274D01*
G01X1216834Y418874D02*
X1228533Y406799D01*
G01X1177227Y467084D02*
X1180176Y467664D01*
G01X1177225Y466115D02*
X1180174Y466695D01*
G01X1176448Y469400D02*
X1181378Y470386D01*
G01X1176448Y470369D02*
X1181378Y471355D01*
G01X1177772Y476037D02*
X1173039Y475089D01*
G01Y474120D02*
X1174239Y474360D01*
G01X1177772Y476037D02*
X1173039Y475089D01*
G01X1176103Y474734D02*
X1177772Y475068D01*
G01X1220684Y467452D02*
X1177772Y476037D01*
G01Y475068D02*
X1179457Y474731D01*
G01X1220684Y467452D02*
X1177772Y476037D01*
G01X1181321Y474358D02*
X1220359Y466547D01*
G01X1177225Y466115D02*
X1180174Y466695D01*
G01X1177227Y467084D02*
X1180176Y467664D01*
G01X1176448Y470369D02*
X1181378Y471355D01*
G01X1176448Y469400D02*
X1181378Y470386D01*
G01X1177772Y475068D02*
X1179457Y474731D01*
G01X1181321Y474358D02*
X1220359Y466547D01*
G01X1220684Y467452D02*
X1177772Y476037D01*
G01X1173039Y474120D02*
X1174239Y474360D01*
G01X1176103Y474734D02*
X1177772Y475068D01*
G01Y476037D02*
X1173039Y475089D01*
G01X1171661Y478772D02*
X1179456Y480335D01*
G01X1171661Y477803D02*
X1179456Y479366D01*
G01Y480335D02*
X1219546Y472296D01*
G01X1179456Y479366D02*
X1219232Y471390D01*
G01X1171661Y478772D02*
X1179456Y480335D01*
G01X1171661Y477803D02*
X1179456Y479366D01*
G01Y480335D02*
X1219546Y472296D01*
G01X1179456Y479366D02*
X1219232Y471390D01*
G01X1167858Y481629D02*
X1178255Y483714D01*
G01X1167858Y482598D02*
X1178255Y484684D01*
G01Y483714D02*
X1220088Y475292D01*
G01X1178255Y484684D02*
X1220400Y476199D01*
G01X1168278Y484804D02*
X1180200Y487187D01*
G01X1168278Y485773D02*
X1180191Y488155D01*
G01X1180200Y487187D02*
X1188333Y485715D01*
G01X1180191Y488155D02*
X1188511Y486649D01*
G01X1188333Y485715D02*
X1221056Y479171D01*
G01X1188511Y486649D02*
X1221365Y480079D01*
G01X1177225Y466115D02*
X1180174Y466695D01*
G01X1177227Y467084D02*
X1180176Y467664D01*
G01X1171661Y477803D02*
X1179456Y479366D01*
G01X1171661Y478772D02*
X1179456Y480335D01*
G01Y479366D02*
X1219232Y471390D01*
G01X1179456Y480335D02*
X1219546Y472296D01*
G01X1167858Y482598D02*
X1178255Y484684D01*
G01X1167858Y481629D02*
X1178255Y483714D01*
G01Y484684D02*
X1220400Y476199D01*
G01X1178255Y483714D02*
X1220088Y475292D01*
G01X1168278Y485773D02*
X1180191Y488155D01*
G01X1168278Y484804D02*
X1180200Y487187D01*
G01X1180191Y488155D02*
X1188511Y486649D01*
G01X1180200Y487187D02*
X1188333Y485715D01*
G01X1188511Y486649D02*
X1221365Y480079D01*
G01X1188333Y485715D02*
X1221056Y479171D01*
G01X1176448Y469400D02*
X1181378Y470386D01*
G01X1176448Y470369D02*
X1181378Y471355D01*
G01X1177772Y476037D02*
X1173039Y475089D01*
G01Y474120D02*
X1174239Y474360D01*
G01X1177772Y476037D02*
X1173039Y475089D01*
G01X1176103Y474734D02*
X1177772Y475068D01*
G01X1220684Y467452D02*
X1177772Y476037D01*
G01Y475068D02*
X1179457Y474731D01*
G01X1220684Y467452D02*
X1177772Y476037D01*
G01X1181321Y474358D02*
X1220359Y466547D01*
G01X1240114Y280859D02*
X1219754Y273422D01*
G01X1239456Y281631D02*
X1229398Y277957D01*
G01X1240114Y280859D02*
X1219754Y273422D01*
G01X1227612Y277304D02*
X1226767Y276996D01*
G01X1240114Y280859D02*
X1219754Y273422D01*
G01X1224982Y276344D02*
X1223887Y275944D01*
G01X1240114Y280859D02*
X1219754Y273422D01*
G01X1222101Y275291D02*
X1219511Y274345D01*
G01X1225018Y271663D02*
X1222379Y269023D01*
G01D02*
X1222001Y268645D01*
G01X1222673Y267973D02*
X1225542Y270842D01*
G01X1242421Y278019D02*
X1225018Y271663D01*
G01X1225542Y270842D02*
X1243079Y277247D01*
G01X1262787Y314559D02*
X1242421Y278019D01*
G01X1243079Y277247D02*
X1263731Y314300D01*
G01X1224130Y264969D02*
X1226666Y266332D01*
G01X1223676Y265805D02*
X1223680Y265807D01*
G01X1224130Y264969D02*
X1226666Y266332D01*
G01X1223680Y265807D02*
X1226248Y267186D01*
G01X1226666Y266332D02*
X1229478Y267582D01*
G01D02*
X1229486Y267586D01*
G01X1226248Y267186D02*
X1229091Y268454D01*
G01X1229486Y267586D02*
X1234453Y269400D01*
G01X1229091Y268454D02*
X1231681Y269400D01*
G01X1234453D02*
X1246223Y273698D01*
G01X1231681Y269400D02*
X1245565Y274470D01*
G01X1246223Y273698D02*
X1268110Y312969D01*
G01X1245565Y274470D02*
X1267166Y313227D01*
G01X1221990Y256931D02*
X1225188D01*
G01X1221990Y255981D02*
X1225366D01*
G01X1225188Y256931D02*
X1230000Y258791D01*
G01X1225366Y255981D02*
X1230437Y257941D01*
G01X1230000Y258791D02*
X1231919Y260053D01*
G01X1233508Y261098D02*
X1234260Y261592D01*
G01X1235848Y262637D02*
X1236600Y263131D01*
G01X1230437Y257941D02*
X1238711Y263381D01*
G01X1238188Y264176D02*
X1248746Y271117D01*
G01X1238710Y263382D02*
X1249463Y270450D01*
G01X1248746Y271117D02*
X1270865Y310802D01*
G01X1249463Y270450D02*
X1272492Y311769D01*
G01X1276890Y310509D02*
X1252870Y267414D01*
G01X1275946Y310767D02*
X1252153Y268081D01*
G01X1252870Y267414D02*
X1232689Y254144D01*
G01X1252153Y268081D02*
X1232242Y254988D01*
G01X1232689Y254144D02*
X1226488Y251581D01*
G01X1232242Y254988D02*
X1226299Y252531D01*
G01X1226488Y251581D02*
X1223200D01*
G01X1226299Y252531D02*
X1223200D01*
G01X1280048Y309158D02*
X1255404Y264939D01*
G01X1280048Y309158D02*
X1255404Y264939D01*
G01X1280747Y308459D02*
X1256121Y264272D01*
G01X1255404Y264939D02*
X1233856Y250770D01*
G01X1256121Y264272D02*
X1234304Y249926D01*
G01X1233856Y250770D02*
X1227508Y248135D01*
G01X1234304Y249926D02*
X1231047Y248574D01*
G01X1233856Y250770D02*
X1227508Y248135D01*
G01X1231046Y248574D02*
X1227697Y247185D01*
G01X1227508Y248135D02*
X1224995D01*
G01X1227697Y247185D02*
X1224995D01*
G01X1263961Y269400D02*
X1283946Y305260D01*
G01X1284695Y308557D02*
X1262872Y269400D01*
G01X1259341Y261110D02*
X1263961Y269400D01*
G01X1262872D02*
X1258624Y261777D01*
G01X1236333Y245983D02*
X1259341Y261110D01*
G01X1258624Y261777D02*
X1235886Y246827D01*
G01X1228608Y242787D02*
X1236333Y245983D01*
G01X1235886Y246827D02*
X1228419Y243737D01*
G01X1224340Y242787D02*
X1228608D01*
G01X1228419Y243737D02*
X1224340D01*
G01X1236331Y285187D02*
X1218990Y278850D01*
G01X1236989Y284415D02*
X1219230Y277926D01*
G01X1239456Y281631D02*
X1229398Y277957D01*
G01X1227612Y277304D02*
X1226767Y276996D01*
G01X1224982Y276344D02*
X1223887Y275944D01*
G01X1222101Y275291D02*
X1219511Y274345D01*
G01X1240114Y280859D02*
X1219754Y273422D01*
G01X1239456Y281631D02*
X1229398Y277957D01*
G01X1227612Y277304D02*
X1226767Y276996D01*
G01X1224982Y276344D02*
X1223887Y275944D01*
G01X1222101Y275291D02*
X1219511Y274345D01*
G01X1240114Y280859D02*
X1219754Y273422D01*
G01X1243079Y277247D02*
X1263731Y314300D01*
G01X1262787Y314559D02*
X1242421Y278019D01*
G01X1225542Y270842D02*
X1243079Y277247D01*
G01X1242421Y278019D02*
X1225018Y271663D01*
G01X1222673Y267973D02*
X1225542Y270842D01*
G01X1225018Y271663D02*
X1222379Y269023D01*
G01X1222673Y267973D02*
X1225542Y270842D01*
G01X1222379Y269023D02*
X1222001Y268645D01*
G01X1223676Y265805D02*
X1223680Y265807D01*
G01D02*
X1226248Y267186D01*
G01X1224130Y264969D02*
X1226666Y266332D01*
G01X1226248Y267186D02*
X1229091Y268454D01*
G01X1226666Y266332D02*
X1229478Y267582D01*
G01X1226248Y267186D02*
X1229091Y268454D01*
G01X1229478Y267582D02*
X1229486Y267586D01*
G01X1229091Y268454D02*
X1231681Y269400D01*
G01X1229486Y267586D02*
X1234453Y269400D01*
G01X1231681D02*
X1245565Y274470D01*
G01X1234453Y269400D02*
X1246223Y273698D01*
G01X1245565Y274470D02*
X1267166Y313227D01*
G01X1246223Y273698D02*
X1268110Y312969D01*
G01X1221990Y255981D02*
X1225366D01*
G01X1221990Y256931D02*
X1225188D01*
G01X1225366Y255981D02*
X1230437Y257941D01*
G01X1225188Y256931D02*
X1230000Y258791D01*
G01X1230437Y257941D02*
X1238711Y263381D01*
G01X1230000Y258791D02*
X1231919Y260053D01*
G01X1230437Y257941D02*
X1238711Y263381D01*
G01X1233508Y261098D02*
X1234260Y261592D01*
G01X1230437Y257941D02*
X1238711Y263381D01*
G01X1235848Y262637D02*
X1236600Y263131D01*
G01X1238710Y263382D02*
X1249463Y270450D01*
G01X1238188Y264176D02*
X1248746Y271117D01*
G01X1249463Y270450D02*
X1272492Y311769D01*
G01X1248746Y271117D02*
X1270865Y310802D01*
G01X1249463Y270450D02*
X1272492Y311769D01*
G01X1275946Y310767D02*
X1252153Y268081D01*
G01X1276890Y310509D02*
X1252870Y267414D01*
G01X1252153Y268081D02*
X1232242Y254988D01*
G01X1252870Y267414D02*
X1232689Y254144D01*
G01X1232242Y254988D02*
X1226299Y252531D01*
G01X1232689Y254144D02*
X1226488Y251581D01*
G01X1226299Y252531D02*
X1223200D01*
G01X1226488Y251581D02*
X1223200D01*
G01X1280747Y308459D02*
X1256121Y264272D01*
G01X1280048Y309158D02*
X1255404Y264939D01*
G01X1256121Y264272D02*
X1234304Y249926D01*
G01X1255404Y264939D02*
X1233856Y250770D01*
G01X1234304Y249926D02*
X1231047Y248574D01*
G01X1231046D02*
X1227697Y247185D01*
G01X1233856Y250770D02*
X1227508Y248135D01*
G01X1227697Y247185D02*
X1224995D01*
G01X1227508Y248135D02*
X1224995D01*
G01X1228419Y243737D02*
X1224340D01*
G01Y242787D02*
X1228608D01*
G01X1235886Y246827D02*
X1228419Y243737D01*
G01X1228608Y242787D02*
X1236333Y245983D01*
G01X1258624Y261777D02*
X1235886Y246827D01*
G01X1236333Y245983D02*
X1259341Y261110D01*
G01X1262872Y269400D02*
X1258624Y261777D01*
G01X1259341Y261110D02*
X1263961Y269400D01*
G01X1284695Y308557D02*
X1262872Y269400D01*
G01X1263961D02*
X1283946Y305260D01*
G01X1284695Y308557D02*
X1262872Y269400D01*
G01X1236989Y284415D02*
X1219230Y277926D01*
G01X1236331Y285187D02*
X1218990Y278850D01*
G01X1236989Y284415D02*
X1219230Y277926D01*
G01X1290003Y306946D02*
X1262779Y258094D01*
G01X1290003Y306946D02*
X1262779Y258094D01*
G01X1286534Y302672D02*
X1262062Y258761D01*
G01X1262779Y258094D02*
X1238645Y242225D01*
G01X1262062Y258761D02*
X1238198Y243069D01*
G01X1238645Y242225D02*
X1229157Y238300D01*
G01X1238198Y243069D02*
X1228968Y239250D01*
G01X1229157Y238300D02*
X1223200D01*
G01X1228968Y239250D02*
X1223200D01*
G01X1290003Y306946D02*
X1262779Y258094D01*
G01X1290003Y306946D02*
X1262779Y258094D01*
G01X1286534Y302672D02*
X1262062Y258761D01*
G01X1262779Y258094D02*
X1238645Y242225D01*
G01X1262062Y258761D02*
X1238198Y243069D01*
G01X1238645Y242225D02*
X1229157Y238300D01*
G01X1238198Y243069D02*
X1228968Y239250D01*
G01X1229157Y238300D02*
X1223200D01*
G01X1228968Y239250D02*
X1223200D01*
G01X1293456Y306031D02*
X1273041Y269400D01*
G01X1294400Y305773D02*
X1274129Y269400D01*
G01X1273041D02*
X1265390Y255672D01*
G01X1274129Y269400D02*
X1266107Y255005D01*
G01X1265390Y255672D02*
X1240141Y239069D01*
G01X1266107Y255005D02*
X1240588Y238225D01*
G01X1240141Y239069D02*
X1229956Y234850D01*
G01X1240588Y238225D02*
X1230145Y233900D01*
G01X1229956Y234850D02*
X1223200D01*
G01X1230145Y233900D02*
X1223260D01*
G01X1297860Y304871D02*
X1268719Y252582D01*
G01X1298796Y304598D02*
X1269436Y251915D01*
G01X1268719Y252582D02*
X1242324Y235228D01*
G01X1269436Y251915D02*
X1242771Y234384D01*
G01X1242324Y235228D02*
X1230971Y230529D01*
G01X1242771Y234384D02*
X1231699Y229801D01*
G01X1242324Y235228D02*
X1230971Y230529D01*
G01D02*
X1230854Y230480D01*
G01D02*
X1223200D01*
G01X1231699Y229801D02*
X1231217Y229602D01*
G01X1230971Y230529D02*
X1230854Y230480D01*
G01D02*
X1223200D01*
G01X1231217Y229601D02*
X1231043Y229530D01*
G01X1230854Y230480D02*
X1223200D01*
G01X1231043Y229530D02*
X1223200D01*
G01X1275946Y310767D02*
X1252153Y268081D01*
G01X1276890Y310509D02*
X1252870Y267414D01*
G01X1252153Y268081D02*
X1232242Y254988D01*
G01X1252870Y267414D02*
X1232689Y254144D01*
G01X1232242Y254988D02*
X1226299Y252531D01*
G01X1232689Y254144D02*
X1226488Y251581D01*
G01X1226299Y252531D02*
X1223200D01*
G01X1226488Y251581D02*
X1223200D01*
G01X1286534Y302672D02*
X1262062Y258761D01*
G01X1290003Y306946D02*
X1262779Y258094D01*
G01X1262062Y258761D02*
X1238198Y243069D01*
G01X1262779Y258094D02*
X1238645Y242225D01*
G01X1238198Y243069D02*
X1228968Y239250D01*
G01X1238645Y242225D02*
X1229157Y238300D01*
G01X1228968Y239250D02*
X1223200D01*
G01X1229157Y238300D02*
X1223200D01*
G01X1294400Y305773D02*
X1274129Y269400D01*
G01X1293456Y306031D02*
X1273041Y269400D01*
G01X1274129D02*
X1266107Y255005D01*
G01X1273041Y269400D02*
X1265390Y255672D01*
G01X1266107Y255005D02*
X1240588Y238225D01*
G01X1265390Y255672D02*
X1240141Y239069D01*
G01X1240588Y238225D02*
X1230145Y233900D01*
G01X1240141Y239069D02*
X1229956Y234850D01*
G01X1230145Y233900D02*
X1223260D01*
G01X1229956Y234850D02*
X1223200D01*
G01X1298796Y304598D02*
X1269436Y251915D01*
G01X1297860Y304871D02*
X1268719Y252582D01*
G01X1269436Y251915D02*
X1242771Y234384D01*
G01X1268719Y252582D02*
X1242324Y235228D01*
G01X1242771Y234384D02*
X1231699Y229801D01*
G01D02*
X1231217Y229602D01*
G01X1242324Y235228D02*
X1230971Y230529D01*
G01X1231699Y229801D02*
X1231217Y229602D01*
G01Y229601D02*
X1231043Y229530D01*
G01X1230971Y230529D02*
X1230854Y230480D01*
G01X1231699Y229801D02*
X1231217Y229602D01*
G01Y229601D02*
X1231043Y229530D01*
G01D02*
X1223200D01*
G01X1230854Y230480D02*
X1223200D01*
G01X1225018Y271663D02*
X1222379Y269023D01*
G01D02*
X1222001Y268645D01*
G01X1222673Y267973D02*
X1225542Y270842D01*
G01X1242421Y278019D02*
X1225018Y271663D01*
G01X1225542Y270842D02*
X1243079Y277247D01*
G01X1262787Y314559D02*
X1242421Y278019D01*
G01X1243079Y277247D02*
X1263731Y314300D01*
G01X1221990Y256931D02*
X1225188D01*
G01X1221990Y255981D02*
X1225366D01*
G01X1225188Y256931D02*
X1230000Y258791D01*
G01X1225366Y255981D02*
X1230437Y257941D01*
G01X1230000Y258791D02*
X1231919Y260053D01*
G01X1233508Y261098D02*
X1234260Y261592D01*
G01X1235848Y262637D02*
X1236600Y263131D01*
G01X1230437Y257941D02*
X1238711Y263381D01*
G01X1238188Y264176D02*
X1248746Y271117D01*
G01X1238710Y263382D02*
X1249463Y270450D01*
G01X1248746Y271117D02*
X1270865Y310802D01*
G01X1249463Y270450D02*
X1272492Y311769D01*
G01X1280048Y309158D02*
X1255404Y264939D01*
G01X1280048Y309158D02*
X1255404Y264939D01*
G01X1280747Y308459D02*
X1256121Y264272D01*
G01X1255404Y264939D02*
X1233856Y250770D01*
G01X1256121Y264272D02*
X1234304Y249926D01*
G01X1233856Y250770D02*
X1227508Y248135D01*
G01X1234304Y249926D02*
X1231047Y248574D01*
G01X1233856Y250770D02*
X1227508Y248135D01*
G01X1231046Y248574D02*
X1227697Y247185D01*
G01X1227508Y248135D02*
X1224995D01*
G01X1227697Y247185D02*
X1224995D01*
G01X1263961Y269400D02*
X1283946Y305260D01*
G01X1284695Y308557D02*
X1262872Y269400D01*
G01X1259341Y261110D02*
X1263961Y269400D01*
G01X1262872D02*
X1258624Y261777D01*
G01X1236333Y245983D02*
X1259341Y261110D01*
G01X1258624Y261777D02*
X1235886Y246827D01*
G01X1228608Y242787D02*
X1236333Y245983D01*
G01X1235886Y246827D02*
X1228419Y243737D01*
G01X1224340Y242787D02*
X1228608D01*
G01X1228419Y243737D02*
X1224340D01*
G01X1223676Y265805D02*
X1223680Y265807D01*
G01D02*
X1226248Y267186D01*
G01X1224130Y264969D02*
X1226666Y266332D01*
G01X1226248Y267186D02*
X1229091Y268454D01*
G01X1226666Y266332D02*
X1229478Y267582D01*
G01X1226248Y267186D02*
X1229091Y268454D01*
G01X1229478Y267582D02*
X1229486Y267586D01*
G01X1229091Y268454D02*
X1231681Y269400D01*
G01X1229486Y267586D02*
X1234453Y269400D01*
G01X1231681D02*
X1245565Y274470D01*
G01X1234453Y269400D02*
X1246223Y273698D01*
G01X1245565Y274470D02*
X1267166Y313227D01*
G01X1246223Y273698D02*
X1268110Y312969D01*
G01X1236331Y285187D02*
X1218990Y278850D01*
G01X1236989Y284415D02*
X1219230Y277926D01*
G01X1260179Y347424D02*
X1259531Y322500D01*
G01X1259233Y347620D02*
X1258581Y322500D01*
G01X1259531D02*
X1259346Y315368D01*
G01X1258581Y322500D02*
X1258402Y315626D01*
G01X1259346Y315368D02*
X1258751Y314300D01*
G01D02*
X1240114Y280859D01*
G01X1258402Y315626D02*
X1239456Y281631D01*
G01X1262993Y322500D02*
X1262787Y314559D01*
G01X1263731Y314300D02*
X1263944Y322500D01*
G01X1263623Y346721D02*
X1262993Y322500D01*
G01X1263944D02*
X1264569Y346526D01*
G01X1268110Y312969D02*
X1268145Y314300D01*
G01X1267166Y313227D02*
X1267194Y314300D01*
G01X1268145D02*
X1268358Y322500D01*
G01X1267194Y314300D02*
X1267407Y322500D01*
G01X1268358D02*
X1268958Y345624D01*
G01X1267407Y322500D02*
X1268012Y345819D01*
G01X1270865Y310802D02*
X1271548Y312027D01*
G01D02*
X1271820Y322500D01*
G01X1272492Y311769D02*
X1272771Y322500D01*
G01X1271820D02*
X1272407Y345122D01*
G01X1272771Y322500D02*
X1273353Y344927D01*
G01X1277756Y343871D02*
X1277201Y322500D01*
G01X1276810Y344066D02*
X1276250Y322500D01*
G01X1277201D02*
X1276936Y312270D01*
G01X1276250Y322500D02*
X1276009Y313197D01*
G01X1276936Y312270D02*
X1276890Y310509D01*
G01X1276009Y313197D02*
X1275946Y310767D01*
G01X1280316Y309638D02*
X1280048Y309158D01*
G01X1224730Y341840D02*
X1223997Y338670D01*
G01X1223782Y341961D02*
X1223071Y338885D01*
G01X1223453Y336318D02*
X1220257Y322500D01*
G01X1223997Y338670D02*
X1223453Y336318D01*
G01X1223071Y338885D02*
X1219282Y322500D01*
G01X1228120Y340070D02*
X1228066Y337955D01*
G01X1229071Y340046D02*
X1229014Y337836D01*
G01X1228066Y337955D02*
X1225428Y326327D01*
G01X1225027Y324552D02*
X1224827Y323673D01*
G01X1224425Y321898D02*
X1224225Y321019D01*
G01X1223823Y319244D02*
X1223624Y318369D01*
G01X1223221Y316590D02*
X1222969Y315480D01*
G01X1229014Y337836D02*
X1223866Y315136D01*
G01X1222969Y315480D02*
X1218953Y308277D01*
G01X1223866Y315136D02*
X1223400Y314300D01*
G01X1222969Y315480D02*
X1218953Y308277D01*
G01X1223400Y314300D02*
X1219688Y307643D01*
G01X1228715Y362963D02*
X1228120Y340070D01*
G01X1229665Y362938D02*
X1229071Y340046D01*
G01X1232424Y334849D02*
X1232900Y353150D01*
G01X1233876Y354126D02*
X1233372Y334727D01*
G01X1229683Y323117D02*
X1229888Y323994D01*
G01X1230301Y325763D02*
X1230506Y326640D01*
G01X1230919Y328409D02*
X1231124Y329286D01*
G01X1231537Y331055D02*
X1231742Y331932D01*
G01X1232155Y333701D02*
X1232424Y334849D01*
G01X1233372Y334727D02*
X1230520Y322500D01*
G01X1228447Y317825D02*
X1228652Y318702D01*
G01X1229065Y320471D02*
X1229270Y321348D01*
G01X1230520Y322500D02*
X1228722Y314789D01*
G01X1227362Y314300D02*
X1227827Y315135D01*
G01X1228722Y314789D02*
X1228449Y314300D01*
G01X1222597Y305751D02*
X1227362Y314300D01*
G01D02*
X1227827Y315135D01*
G01X1228449Y314300D02*
X1223321Y305098D01*
G01X1218798Y297702D02*
X1219640Y298002D01*
G01D02*
X1219641D01*
G01D02*
X1220482Y298302D01*
G01X1219166Y296824D02*
X1220954Y297461D01*
G01X1220482Y298302D02*
X1225982Y302760D01*
G01X1220954Y297461D02*
X1226723Y302137D01*
G01X1225982Y302760D02*
X1232412Y314300D01*
G01X1226723Y302137D02*
X1227913Y304273D01*
G01X1225982Y302760D02*
X1232412Y314300D01*
G01X1227913Y304273D02*
X1233501Y314300D01*
G01X1232412D02*
X1233213Y315738D01*
G01X1233501Y314300D02*
X1234113Y315399D01*
G01X1233213Y315738D02*
X1233566Y317383D01*
G01X1233952Y319181D02*
X1234142Y320063D01*
G01X1234528Y321861D02*
X1234666Y322500D01*
G01D02*
X1234718Y322743D01*
G01X1234113Y315399D02*
X1235635Y322500D01*
G01X1234666D02*
X1234718Y322743D01*
G01X1235104Y324541D02*
X1235294Y325423D01*
G01X1235680Y327221D02*
X1235870Y328103D01*
G01X1236247Y329896D02*
X1236795Y332449D01*
G01X1235635Y322500D02*
X1237743Y332336D01*
G01X1236795Y332449D02*
X1236921Y337307D01*
G01X1237841Y372724D02*
X1236921Y337307D01*
G01X1237743Y332336D02*
X1238475Y360530D01*
G01X1237841Y372724D02*
X1236921Y337307D01*
G01X1242459Y344788D02*
X1242047Y328923D01*
G01X1242270Y374119D02*
X1241099Y329033D01*
G01X1242047Y328923D02*
X1239255Y315443D01*
G01X1241099Y329033D02*
X1240821Y327690D01*
G01X1242047Y328923D02*
X1239255Y315443D01*
G01X1240419Y325750D02*
X1240217Y324771D01*
G01X1242047Y328923D02*
X1239255Y315443D01*
G01X1239815Y322831D02*
X1239613Y321852D01*
G01X1242047Y328923D02*
X1239255Y315443D01*
G01X1239210Y319912D02*
X1239008Y318933D01*
G01X1242047Y328923D02*
X1239255Y315443D01*
G01X1238606Y316993D02*
X1238354Y315779D01*
G01X1239255Y315443D02*
X1228093Y295423D01*
G01X1238354Y315779D02*
X1227435Y296194D01*
G01X1247388Y366609D02*
X1246216Y321512D01*
G01X1246438Y366646D02*
X1245281Y322107D01*
G01X1246214Y321511D02*
X1246147Y318870D01*
G01X1245279Y322106D02*
X1245203Y319128D01*
G01X1246147Y318870D02*
X1231058Y291796D01*
G01X1245203Y319128D02*
X1244198Y317324D01*
G01X1246147Y318870D02*
X1231058Y291796D01*
G01X1243233Y315593D02*
X1230400Y292567D01*
G01X1250110Y336170D02*
X1249640Y318051D01*
G01X1250454Y349421D02*
X1250110Y336170D01*
G01X1251400Y349226D02*
X1250584Y317793D01*
G01X1249640Y318051D02*
X1233481Y289061D01*
G01X1250584Y317793D02*
X1234144Y288297D01*
G01X1233481Y289061D02*
X1221480Y284436D01*
G01X1234144Y288297D02*
X1227821Y285861D01*
G01X1233481Y289061D02*
X1221480Y284436D01*
G01X1227821Y285860D02*
X1221789Y283536D01*
G01X1254844Y348524D02*
X1254169Y322500D01*
G01X1255790Y348329D02*
X1255119Y322500D01*
G01X1254169D02*
X1254024Y316929D01*
G01X1255119Y322500D02*
X1254968Y316671D01*
G01X1254024Y316929D02*
X1236331Y285187D01*
G01X1254968Y316671D02*
X1236989Y284415D01*
G01X1259233Y347620D02*
X1258581Y322500D01*
G01X1260179Y347424D02*
X1259531Y322500D01*
G01X1258581D02*
X1258402Y315626D01*
G01X1259531Y322500D02*
X1259346Y315368D01*
G01X1258402Y315626D02*
X1239456Y281631D01*
G01X1259346Y315368D02*
X1258751Y314300D01*
G01X1258402Y315626D02*
X1239456Y281631D01*
G01X1258751Y314300D02*
X1240114Y280859D01*
G01X1259233Y347620D02*
X1258581Y322500D01*
G01X1260179Y347424D02*
X1259531Y322500D01*
G01X1258581D02*
X1258402Y315626D01*
G01X1259531Y322500D02*
X1259346Y315368D01*
G01X1258402Y315626D02*
X1239456Y281631D01*
G01X1259346Y315368D02*
X1258751Y314300D01*
G01X1258402Y315626D02*
X1239456Y281631D01*
G01X1258751Y314300D02*
X1240114Y280859D01*
G01X1263944Y322500D02*
X1264569Y346526D01*
G01X1263623Y346721D02*
X1262993Y322500D01*
G01X1263731Y314300D02*
X1263944Y322500D01*
G01X1262993D02*
X1262787Y314559D01*
G01X1267166Y313227D02*
X1267194Y314300D01*
G01X1268110Y312969D02*
X1268145Y314300D01*
G01X1267194D02*
X1267407Y322500D01*
G01X1268145Y314300D02*
X1268358Y322500D01*
G01X1267407D02*
X1268012Y345819D01*
G01X1268358Y322500D02*
X1268958Y345624D01*
G01X1270865Y310802D02*
X1271548Y312027D01*
G01X1272492Y311769D02*
X1272771Y322500D01*
G01X1271548Y312027D02*
X1271820Y322500D01*
G01X1272771D02*
X1273353Y344927D01*
G01X1271820Y322500D02*
X1272407Y345122D01*
G01X1276810Y344066D02*
X1276250Y322500D01*
G01X1277756Y343871D02*
X1277201Y322500D01*
G01X1276250D02*
X1276009Y313197D01*
G01X1277201Y322500D02*
X1276936Y312270D01*
G01X1276009Y313197D02*
X1275946Y310767D01*
G01X1276936Y312270D02*
X1276890Y310509D01*
G01X1280316Y309638D02*
X1280048Y309158D01*
G01X1223071Y338885D02*
X1219282Y322500D01*
G01X1223453Y336318D02*
X1220257Y322500D01*
G01X1223782Y341961D02*
X1223071Y338885D01*
G01X1224730Y341840D02*
X1223997Y338670D01*
G01X1223071Y338885D02*
X1219282Y322500D01*
G01X1223997Y338670D02*
X1223453Y336318D01*
G01X1229665Y362938D02*
X1229071Y340046D01*
G01X1228715Y362963D02*
X1228120Y340070D01*
G01X1229071Y340046D02*
X1229014Y337836D01*
G01X1228120Y340070D02*
X1228066Y337955D01*
G01X1229014Y337836D02*
X1223866Y315136D01*
G01X1228066Y337955D02*
X1225428Y326327D01*
G01X1229014Y337836D02*
X1223866Y315136D01*
G01X1225027Y324552D02*
X1224827Y323673D01*
G01X1229014Y337836D02*
X1223866Y315136D01*
G01X1224425Y321898D02*
X1224225Y321019D01*
G01X1229014Y337836D02*
X1223866Y315136D01*
G01X1223823Y319244D02*
X1223624Y318369D01*
G01X1229014Y337836D02*
X1223866Y315136D01*
G01X1223221Y316590D02*
X1222969Y315480D01*
G01X1223866Y315136D02*
X1223400Y314300D01*
G01D02*
X1219688Y307643D01*
G01X1222969Y315480D02*
X1218953Y308277D01*
G01X1229665Y362938D02*
X1229071Y340046D01*
G01X1228449Y314300D02*
X1223321Y305098D01*
G01X1222597Y305751D02*
X1227362Y314300D01*
G01X1228722Y314789D02*
X1228449Y314300D01*
G01D02*
X1223321Y305098D01*
G01X1227362Y314300D02*
X1227827Y315135D01*
G01X1230520Y322500D02*
X1228722Y314789D01*
G01X1228447Y317825D02*
X1228652Y318702D01*
G01X1230520Y322500D02*
X1228722Y314789D01*
G01X1229065Y320471D02*
X1229270Y321348D01*
G01X1233372Y334727D02*
X1230520Y322500D01*
G01X1229683Y323117D02*
X1229888Y323994D01*
G01X1233372Y334727D02*
X1230520Y322500D01*
G01X1230301Y325763D02*
X1230506Y326640D01*
G01X1233372Y334727D02*
X1230520Y322500D01*
G01X1230919Y328409D02*
X1231124Y329286D01*
G01X1233372Y334727D02*
X1230520Y322500D01*
G01X1231537Y331055D02*
X1231742Y331932D01*
G01X1233372Y334727D02*
X1230520Y322500D01*
G01X1232155Y333701D02*
X1232424Y334849D01*
G01X1233876Y354126D02*
X1233372Y334727D01*
G01X1232424Y334849D02*
X1232900Y353150D01*
G01X1219166Y296824D02*
X1220954Y297461D01*
G01X1218798Y297702D02*
X1219640Y298002D01*
G01X1219166Y296824D02*
X1220954Y297461D01*
G01X1219640Y298002D02*
X1219641D01*
G01X1219166Y296824D02*
X1220954Y297461D01*
G01X1219641Y298002D02*
X1220482Y298302D01*
G01X1220954Y297461D02*
X1226723Y302137D01*
G01X1220482Y298302D02*
X1225982Y302760D01*
G01X1226723Y302137D02*
X1227913Y304273D01*
G01D02*
X1233501Y314300D01*
G01X1225982Y302760D02*
X1232412Y314300D01*
G01X1233501D02*
X1234113Y315399D01*
G01X1232412Y314300D02*
X1233213Y315738D01*
G01X1234113Y315399D02*
X1235635Y322500D01*
G01X1233213Y315738D02*
X1233566Y317383D01*
G01X1234113Y315399D02*
X1235635Y322500D01*
G01X1233952Y319181D02*
X1234142Y320063D01*
G01X1234113Y315399D02*
X1235635Y322500D01*
G01X1234528Y321861D02*
X1234666Y322500D01*
G01X1234113Y315399D02*
X1235635Y322500D01*
G01D02*
X1237743Y332336D01*
G01X1234666Y322500D02*
X1234718Y322743D01*
G01X1235635Y322500D02*
X1237743Y332336D01*
G01X1235104Y324541D02*
X1235294Y325423D01*
G01X1235635Y322500D02*
X1237743Y332336D01*
G01X1235680Y327221D02*
X1235870Y328103D01*
G01X1235635Y322500D02*
X1237743Y332336D01*
G01X1236247Y329896D02*
X1236795Y332449D01*
G01X1237743Y332336D02*
X1238475Y360530D01*
G01X1236795Y332449D02*
X1236921Y337307D01*
G01X1237743Y332336D02*
X1238475Y360530D01*
G01X1237841Y372724D02*
X1236921Y337307D01*
G01X1242270Y374119D02*
X1241099Y329033D01*
G01X1242459Y344788D02*
X1242047Y328923D01*
G01X1241099Y329033D02*
X1240821Y327690D01*
G01X1240419Y325750D02*
X1240217Y324771D01*
G01X1239815Y322831D02*
X1239613Y321852D01*
G01X1239210Y319912D02*
X1239008Y318933D01*
G01X1238606Y316993D02*
X1238354Y315779D01*
G01X1242047Y328923D02*
X1239255Y315443D01*
G01X1238354Y315779D02*
X1227435Y296194D01*
G01X1239255Y315443D02*
X1228093Y295423D01*
G01X1242270Y374119D02*
X1241099Y329033D01*
G01X1246438Y366646D02*
X1245281Y322107D01*
G01X1247388Y366609D02*
X1246216Y321512D01*
G01X1245279Y322106D02*
X1245203Y319128D01*
G01X1246214Y321511D02*
X1246147Y318870D01*
G01X1245203Y319128D02*
X1244198Y317324D01*
G01X1243233Y315593D02*
X1230400Y292567D01*
G01X1246147Y318870D02*
X1231058Y291796D01*
G01X1251400Y349226D02*
X1250584Y317793D01*
G01X1250110Y336170D02*
X1249640Y318051D01*
G01X1250584Y317793D02*
X1234144Y288297D01*
G01X1249640Y318051D02*
X1233481Y289061D01*
G01X1234144Y288297D02*
X1227821Y285861D01*
G01Y285860D02*
X1221789Y283536D01*
G01X1233481Y289061D02*
X1221480Y284436D01*
G01X1251400Y349226D02*
X1250584Y317793D01*
G01X1250454Y349421D02*
X1250110Y336170D01*
G01X1255790Y348329D02*
X1255119Y322500D01*
G01X1254844Y348524D02*
X1254169Y322500D01*
G01X1255119D02*
X1254968Y316671D01*
G01X1254169Y322500D02*
X1254024Y316929D01*
G01X1254968Y316671D02*
X1236989Y284415D01*
G01X1254024Y316929D02*
X1236331Y285187D01*
G01X1276810Y344066D02*
X1276250Y322500D01*
G01X1277756Y343871D02*
X1277201Y322500D01*
G01X1276250D02*
X1276009Y313197D01*
G01X1277201Y322500D02*
X1276936Y312270D01*
G01X1276009Y313197D02*
X1275946Y310767D01*
G01X1276936Y312270D02*
X1276890Y310509D01*
G01X1262993Y322500D02*
X1262787Y314559D01*
G01X1263731Y314300D02*
X1263944Y322500D01*
G01X1263623Y346721D02*
X1262993Y322500D01*
G01X1263944D02*
X1264569Y346526D01*
G01X1270865Y310802D02*
X1271548Y312027D01*
G01D02*
X1271820Y322500D01*
G01X1272492Y311769D02*
X1272771Y322500D01*
G01X1271820D02*
X1272407Y345122D01*
G01X1272771Y322500D02*
X1273353Y344927D01*
G01X1280316Y309638D02*
X1280048Y309158D01*
G01X1267166Y313227D02*
X1267194Y314300D01*
G01X1268110Y312969D02*
X1268145Y314300D01*
G01X1267194D02*
X1267407Y322500D01*
G01X1268145Y314300D02*
X1268358Y322500D01*
G01X1267407D02*
X1268012Y345819D01*
G01X1268358Y322500D02*
X1268958Y345624D01*
G01X1246438Y366646D02*
X1245281Y322107D01*
G01X1247388Y366609D02*
X1246216Y321512D01*
G01X1245279Y322106D02*
X1245203Y319128D01*
G01X1246214Y321511D02*
X1246147Y318870D01*
G01X1245203Y319128D02*
X1244198Y317324D01*
G01X1243233Y315593D02*
X1230400Y292567D01*
G01X1246147Y318870D02*
X1231058Y291796D01*
G01X1254844Y348524D02*
X1254169Y322500D01*
G01X1255790Y348329D02*
X1255119Y322500D01*
G01X1254169D02*
X1254024Y316929D01*
G01X1255119Y322500D02*
X1254968Y316671D01*
G01X1254024Y316929D02*
X1236331Y285187D01*
G01X1254968Y316671D02*
X1236989Y284415D01*
G01X1224730Y341840D02*
X1223997Y338670D01*
G01X1223782Y341961D02*
X1223071Y338885D01*
G01X1223453Y336318D02*
X1220257Y322500D01*
G01X1223997Y338670D02*
X1223453Y336318D01*
G01X1223071Y338885D02*
X1219282Y322500D01*
G01X1228120Y340070D02*
X1228066Y337955D01*
G01X1229071Y340046D02*
X1229014Y337836D01*
G01X1228066Y337955D02*
X1225428Y326327D01*
G01X1225027Y324552D02*
X1224827Y323673D01*
G01X1224425Y321898D02*
X1224225Y321019D01*
G01X1223823Y319244D02*
X1223624Y318369D01*
G01X1223221Y316590D02*
X1222969Y315480D01*
G01X1229014Y337836D02*
X1223866Y315136D01*
G01X1222969Y315480D02*
X1218953Y308277D01*
G01X1223866Y315136D02*
X1223400Y314300D01*
G01X1222969Y315480D02*
X1218953Y308277D01*
G01X1223400Y314300D02*
X1219688Y307643D01*
G01X1228715Y362963D02*
X1228120Y340070D01*
G01X1229665Y362938D02*
X1229071Y340046D01*
G01X1247388Y366609D02*
X1246216Y321512D01*
G01X1246438Y366646D02*
X1245281Y322107D01*
G01X1246214Y321511D02*
X1246147Y318870D01*
G01X1245279Y322106D02*
X1245203Y319128D01*
G01X1246147Y318870D02*
X1231058Y291796D01*
G01X1245203Y319128D02*
X1244198Y317324D01*
G01X1246147Y318870D02*
X1231058Y291796D01*
G01X1243233Y315593D02*
X1230400Y292567D01*
G01X1229665Y362938D02*
X1229071Y340046D01*
G01X1228715Y362963D02*
X1228120Y340070D01*
G01X1229071Y340046D02*
X1229014Y337836D01*
G01X1228120Y340070D02*
X1228066Y337955D01*
G01X1229014Y337836D02*
X1223866Y315136D01*
G01X1228066Y337955D02*
X1225428Y326327D01*
G01X1229014Y337836D02*
X1223866Y315136D01*
G01X1225027Y324552D02*
X1224827Y323673D01*
G01X1229014Y337836D02*
X1223866Y315136D01*
G01X1224425Y321898D02*
X1224225Y321019D01*
G01X1229014Y337836D02*
X1223866Y315136D01*
G01X1223823Y319244D02*
X1223624Y318369D01*
G01X1229014Y337836D02*
X1223866Y315136D01*
G01X1223221Y316590D02*
X1222969Y315480D01*
G01X1223866Y315136D02*
X1223400Y314300D01*
G01D02*
X1219688Y307643D01*
G01X1222969Y315480D02*
X1218953Y308277D01*
G01X1229665Y362938D02*
X1229071Y340046D01*
G01X1242270Y374119D02*
X1241099Y329033D01*
G01X1242459Y344788D02*
X1242047Y328923D01*
G01X1241099Y329033D02*
X1240821Y327690D01*
G01X1240419Y325750D02*
X1240217Y324771D01*
G01X1239815Y322831D02*
X1239613Y321852D01*
G01X1239210Y319912D02*
X1239008Y318933D01*
G01X1238606Y316993D02*
X1238354Y315779D01*
G01X1242047Y328923D02*
X1239255Y315443D01*
G01X1238354Y315779D02*
X1227435Y296194D01*
G01X1239255Y315443D02*
X1228093Y295423D01*
G01X1242270Y374119D02*
X1241099Y329033D01*
G01X1251400Y349226D02*
X1250584Y317793D01*
G01X1250110Y336170D02*
X1249640Y318051D01*
G01X1250584Y317793D02*
X1234144Y288297D01*
G01X1249640Y318051D02*
X1233481Y289061D01*
G01X1234144Y288297D02*
X1227821Y285861D01*
G01Y285860D02*
X1221789Y283536D01*
G01X1233481Y289061D02*
X1221480Y284436D01*
G01X1251400Y349226D02*
X1250584Y317793D01*
G01X1250454Y349421D02*
X1250110Y336170D01*
G01X1218798Y297702D02*
X1219640Y298002D01*
G01D02*
X1219641D01*
G01D02*
X1220482Y298302D01*
G01X1219166Y296824D02*
X1220954Y297461D01*
G01X1220482Y298302D02*
X1225982Y302760D01*
G01X1220954Y297461D02*
X1226723Y302137D01*
G01X1225982Y302760D02*
X1232412Y314300D01*
G01X1226723Y302137D02*
X1227913Y304273D01*
G01X1225982Y302760D02*
X1232412Y314300D01*
G01X1227913Y304273D02*
X1233501Y314300D01*
G01X1232412D02*
X1233213Y315738D01*
G01X1233501Y314300D02*
X1234113Y315399D01*
G01X1233213Y315738D02*
X1233566Y317383D01*
G01X1233952Y319181D02*
X1234142Y320063D01*
G01X1234528Y321861D02*
X1234666Y322500D01*
G01D02*
X1234718Y322743D01*
G01X1234113Y315399D02*
X1235635Y322500D01*
G01X1234666D02*
X1234718Y322743D01*
G01X1235104Y324541D02*
X1235294Y325423D01*
G01X1235680Y327221D02*
X1235870Y328103D01*
G01X1236247Y329896D02*
X1236795Y332449D01*
G01X1235635Y322500D02*
X1237743Y332336D01*
G01X1236795Y332449D02*
X1236921Y337307D01*
G01X1237841Y372724D02*
X1236921Y337307D01*
G01X1237743Y332336D02*
X1238475Y360530D01*
G01X1237841Y372724D02*
X1236921Y337307D01*
G01X1223071Y338885D02*
X1219282Y322500D01*
G01X1223453Y336318D02*
X1220257Y322500D01*
G01X1223782Y341961D02*
X1223071Y338885D01*
G01X1224730Y341840D02*
X1223997Y338670D01*
G01X1223071Y338885D02*
X1219282Y322500D01*
G01X1223997Y338670D02*
X1223453Y336318D01*
G01X1228449Y314300D02*
X1223321Y305098D01*
G01X1222597Y305751D02*
X1227362Y314300D01*
G01X1228722Y314789D02*
X1228449Y314300D01*
G01D02*
X1223321Y305098D01*
G01X1227362Y314300D02*
X1227827Y315135D01*
G01X1230520Y322500D02*
X1228722Y314789D01*
G01X1228447Y317825D02*
X1228652Y318702D01*
G01X1230520Y322500D02*
X1228722Y314789D01*
G01X1229065Y320471D02*
X1229270Y321348D01*
G01X1233372Y334727D02*
X1230520Y322500D01*
G01X1229683Y323117D02*
X1229888Y323994D01*
G01X1233372Y334727D02*
X1230520Y322500D01*
G01X1230301Y325763D02*
X1230506Y326640D01*
G01X1233372Y334727D02*
X1230520Y322500D01*
G01X1230919Y328409D02*
X1231124Y329286D01*
G01X1233372Y334727D02*
X1230520Y322500D01*
G01X1231537Y331055D02*
X1231742Y331932D01*
G01X1233372Y334727D02*
X1230520Y322500D01*
G01X1232155Y333701D02*
X1232424Y334849D01*
G01X1233876Y354126D02*
X1233372Y334727D01*
G01X1232424Y334849D02*
X1232900Y353150D01*
G01X1219166Y296824D02*
X1220954Y297461D01*
G01X1218798Y297702D02*
X1219640Y298002D01*
G01X1219166Y296824D02*
X1220954Y297461D01*
G01X1219640Y298002D02*
X1219641D01*
G01X1219166Y296824D02*
X1220954Y297461D01*
G01X1219641Y298002D02*
X1220482Y298302D01*
G01X1220954Y297461D02*
X1226723Y302137D01*
G01X1220482Y298302D02*
X1225982Y302760D01*
G01X1226723Y302137D02*
X1227913Y304273D01*
G01D02*
X1233501Y314300D01*
G01X1225982Y302760D02*
X1232412Y314300D01*
G01X1233501D02*
X1234113Y315399D01*
G01X1232412Y314300D02*
X1233213Y315738D01*
G01X1234113Y315399D02*
X1235635Y322500D01*
G01X1233213Y315738D02*
X1233566Y317383D01*
G01X1234113Y315399D02*
X1235635Y322500D01*
G01X1233952Y319181D02*
X1234142Y320063D01*
G01X1234113Y315399D02*
X1235635Y322500D01*
G01X1234528Y321861D02*
X1234666Y322500D01*
G01X1234113Y315399D02*
X1235635Y322500D01*
G01D02*
X1237743Y332336D01*
G01X1234666Y322500D02*
X1234718Y322743D01*
G01X1235635Y322500D02*
X1237743Y332336D01*
G01X1235104Y324541D02*
X1235294Y325423D01*
G01X1235635Y322500D02*
X1237743Y332336D01*
G01X1235680Y327221D02*
X1235870Y328103D01*
G01X1235635Y322500D02*
X1237743Y332336D01*
G01X1236247Y329896D02*
X1236795Y332449D01*
G01X1237743Y332336D02*
X1238475Y360530D01*
G01X1236795Y332449D02*
X1236921Y337307D01*
G01X1237743Y332336D02*
X1238475Y360530D01*
G01X1237841Y372724D02*
X1236921Y337307D01*
G01X1231509Y435481D02*
X1272576Y396794D01*
G01X1230949Y434703D02*
X1271638Y396371D01*
G01X1272576Y396794D02*
X1273123Y379662D01*
G01X1271638Y396371D02*
X1272167Y379831D01*
G01X1273123Y379662D02*
X1266582Y363372D01*
G01X1272167Y379831D02*
X1270865Y376588D01*
G01X1273123Y379662D02*
X1266582Y363372D01*
G01X1266583D02*
X1263043Y354557D01*
G01D02*
X1260179Y347424D01*
G01X1270865Y376588D02*
X1259233Y347620D01*
G01X1276600Y379163D02*
X1263623Y346721D01*
G01X1264569Y346526D02*
X1277556Y378995D01*
G01X1275988Y398336D02*
X1276600Y379163D01*
G01X1277556Y378995D02*
X1276926Y398759D01*
G01X1235152Y436809D02*
X1275988Y398336D01*
G01X1276926Y398759D02*
X1235712Y437587D01*
G01X1268958Y345624D02*
X1269820Y347780D01*
G01X1268012Y345819D02*
X1269089Y348511D01*
G01X1269820Y347780D02*
X1275408Y361749D01*
G01X1275407D02*
X1281993Y378216D01*
G01X1269089Y348511D02*
X1281037Y378384D01*
G01X1281276Y400721D02*
X1249700Y430473D01*
G01X1280338Y400298D02*
X1249151Y429685D01*
G01X1272407Y345122D02*
X1284900Y376349D01*
G01X1273353Y344927D02*
X1286425Y377603D01*
G01X1290600Y375987D02*
X1277756Y343871D01*
G01X1290600Y375987D02*
X1277756Y343871D01*
G01X1285093Y364775D02*
X1276810Y344066D01*
G01X1219910Y367453D02*
X1219767Y361939D01*
G01X1219640Y357080D02*
X1219268Y342708D01*
G01X1220868Y367748D02*
X1220215Y342570D01*
G01X1225340Y365452D02*
X1225205Y360205D01*
G01X1224391Y365477D02*
X1224229Y359229D01*
G01X1225205Y360205D02*
X1224813Y345063D01*
G01X1224229Y359229D02*
X1223837Y344087D01*
G01X1224813Y345063D02*
X1224730Y341840D01*
G01X1223837Y344087D02*
X1223782Y341961D01*
G01X1219396Y397681D02*
X1221688Y374167D01*
G01D02*
X1225254Y369200D01*
G01X1220767Y373820D02*
X1224084Y369200D01*
G01X1221688Y374167D02*
X1225254Y369200D01*
G01D02*
X1225432Y368952D01*
G01X1224084Y369200D02*
X1224474Y368657D01*
G01X1225432Y368952D02*
X1225341Y365453D01*
G01X1224474Y368657D02*
X1224391Y365477D01*
G01X1221221Y402692D02*
X1222802Y396709D01*
G01X1222080Y403163D02*
X1223739Y396884D01*
G01X1222802Y396709D02*
X1225211Y375192D01*
G01X1223739Y396884D02*
X1226128Y375545D01*
G01X1225211Y375192D02*
X1228899Y370056D01*
G01X1226128Y375545D02*
X1229858Y370351D01*
G01X1228899Y370056D02*
X1228735Y363735D01*
G01X1229858Y370351D02*
X1229712Y364712D01*
G01X1228899Y370056D02*
X1228735Y363735D01*
G01D02*
X1228715Y362963D01*
G01X1229712Y364712D02*
X1229665Y362938D01*
G01X1228735Y363735D02*
X1228715Y362963D01*
G01X1224805Y405072D02*
X1226480Y398509D01*
G01X1225664Y405551D02*
X1227410Y398710D01*
G01X1226480Y398509D02*
X1228389Y387762D01*
G01X1227410Y398710D02*
X1229250Y388350D01*
G01X1226480Y398509D02*
X1228389Y387762D01*
G01X1229250Y388350D02*
X1229330Y387900D01*
G01X1228389Y387762D02*
X1229687Y376520D01*
G01X1229330Y387900D02*
X1230603Y376874D01*
G01X1229687Y376520D02*
X1233374Y371385D01*
G01X1230603Y376874D02*
X1234332Y371680D01*
G01X1233374Y371385D02*
X1233317Y369200D01*
G01X1234332Y371680D02*
X1234270Y369270D01*
G01X1233317Y369200D02*
X1233293Y368293D01*
G01D02*
X1233239Y366212D01*
G01X1234268Y369200D02*
X1234189Y366187D01*
G01X1232900Y353150D02*
X1233239Y366212D01*
G01X1234189Y366187D02*
X1233876Y354126D01*
G01X1228533Y406799D02*
X1229953Y400885D01*
G01X1229397Y407274D02*
X1230883Y401082D01*
G01X1229953Y400885D02*
X1232290Y388210D01*
G01X1230883Y401082D02*
X1233230Y388354D01*
G01X1232290Y388210D02*
X1233427Y378874D01*
G01X1233230Y388354D02*
X1234341Y379230D01*
G01X1233427Y378874D02*
X1237841Y372724D01*
G01X1234341Y379230D02*
X1238473Y373473D01*
G01X1233427Y378874D02*
X1237841Y372724D01*
G01X1238473Y373473D02*
X1238799Y373019D01*
G01D02*
X1238475Y360530D01*
G01X1233161Y409088D02*
X1236834Y391168D01*
G01X1232286Y408624D02*
X1235897Y391007D01*
G01X1236834Y391168D02*
X1238188Y381432D01*
G01X1235897Y391007D02*
X1237279Y381069D01*
G01X1238188Y381432D02*
X1243228Y374414D01*
G01X1237279Y381069D02*
X1242270Y374119D01*
G01X1243228Y374414D02*
X1242459Y344788D01*
G01X1236946Y410747D02*
X1240843Y390649D01*
G01X1236066Y410290D02*
X1239906Y390486D01*
G01X1240843Y390649D02*
X1241885Y383846D01*
G01X1239906Y390486D02*
X1240980Y383477D01*
G01X1241885Y383846D02*
X1244794Y379794D01*
G01X1240980Y383477D02*
X1244113Y379113D01*
G01X1244794Y379794D02*
X1247627Y375849D01*
G01X1244113Y379113D02*
X1246669Y375554D01*
G01X1247627Y375849D02*
X1247387Y366609D01*
G01X1246669Y375554D02*
X1246438Y366646D01*
G01X1224348Y428788D02*
X1262906Y392475D01*
G01X1224905Y429570D02*
X1263843Y392898D01*
G01X1262906Y392475D02*
X1263258Y381434D01*
G01X1263843Y392898D02*
X1264214Y381266D01*
G01X1263258Y381434D02*
X1256558Y364683D01*
G01X1255822Y362843D02*
X1250454Y349421D01*
G01X1264214Y381266D02*
X1252750Y352602D01*
G01X1255822Y362843D02*
X1250454Y349421D01*
G01X1252750Y352602D02*
X1251400Y349226D01*
G01X1226879Y431964D02*
X1267287Y394410D01*
G01X1227436Y432744D02*
X1268225Y394837D01*
G01X1267287Y394410D02*
X1267500Y387750D01*
G01X1268225Y394837D02*
X1268422Y388672D01*
G01X1267500Y387750D02*
X1267600Y384631D01*
G01D02*
X1267725Y380726D01*
G01X1268422Y388672D02*
X1268681Y380558D01*
G01X1267725Y380726D02*
X1254844Y348524D01*
G01X1268681Y380558D02*
X1255790Y348329D01*
G01X1230949Y434703D02*
X1271638Y396371D01*
G01X1231509Y435481D02*
X1272576Y396794D01*
G01X1271638Y396371D02*
X1272167Y379831D01*
G01X1272576Y396794D02*
X1273123Y379662D01*
G01X1272167Y379831D02*
X1270865Y376588D01*
G01D02*
X1259233Y347620D01*
G01X1273123Y379662D02*
X1266582Y363372D01*
G01X1270865Y376588D02*
X1259233Y347620D01*
G01X1266583Y363372D02*
X1263043Y354557D01*
G01X1270865Y376588D02*
X1259233Y347620D01*
G01X1263043Y354557D02*
X1260179Y347424D01*
G01X1230949Y434703D02*
X1271638Y396371D01*
G01X1231509Y435481D02*
X1272576Y396794D01*
G01X1271638Y396371D02*
X1272167Y379831D01*
G01X1272576Y396794D02*
X1273123Y379662D01*
G01X1272167Y379831D02*
X1270865Y376588D01*
G01D02*
X1259233Y347620D01*
G01X1273123Y379662D02*
X1266582Y363372D01*
G01X1270865Y376588D02*
X1259233Y347620D01*
G01X1266583Y363372D02*
X1263043Y354557D01*
G01X1270865Y376588D02*
X1259233Y347620D01*
G01X1263043Y354557D02*
X1260179Y347424D01*
G01X1276926Y398759D02*
X1235712Y437587D01*
G01X1235152Y436809D02*
X1275988Y398336D01*
G01X1277556Y378995D02*
X1276926Y398759D01*
G01X1275988Y398336D02*
X1276600Y379163D01*
G01X1264569Y346526D02*
X1277556Y378995D01*
G01X1276600Y379163D02*
X1263623Y346721D01*
G01X1268012Y345819D02*
X1269089Y348511D01*
G01X1268958Y345624D02*
X1269820Y347780D01*
G01X1269089Y348511D02*
X1281037Y378384D01*
G01X1269820Y347780D02*
X1275408Y361749D01*
G01X1269089Y348511D02*
X1281037Y378384D01*
G01X1275407Y361749D02*
X1281993Y378216D01*
G01X1280338Y400298D02*
X1249151Y429685D01*
G01X1281276Y400721D02*
X1249700Y430473D01*
G01X1273353Y344927D02*
X1286425Y377603D01*
G01X1272407Y345122D02*
X1284900Y376349D01*
G01X1273353Y344927D02*
X1286425Y377603D01*
G01X1285093Y364775D02*
X1276810Y344066D01*
G01X1290600Y375987D02*
X1277756Y343871D01*
G01X1220868Y367748D02*
X1220215Y342570D01*
G01X1219910Y367453D02*
X1219767Y361939D01*
G01X1220868Y367748D02*
X1220215Y342570D01*
G01X1219640Y357080D02*
X1219268Y342708D01*
G01X1220868Y367748D02*
X1220215Y342570D01*
G01X1219910Y367453D02*
X1219767Y361939D01*
G01X1220868Y367748D02*
X1220215Y342570D01*
G01X1219640Y357080D02*
X1219268Y342708D01*
G01X1219396Y397681D02*
X1221688Y374167D01*
G01X1220767Y373820D02*
X1224084Y369200D01*
G01D02*
X1224474Y368657D01*
G01X1221688Y374167D02*
X1225254Y369200D01*
G01X1224084D02*
X1224474Y368657D01*
G01X1225254Y369200D02*
X1225432Y368952D01*
G01X1224474Y368657D02*
X1224391Y365477D01*
G01X1225432Y368952D02*
X1225341Y365453D01*
G01X1224391Y365477D02*
X1224229Y359229D01*
G01X1225340Y365452D02*
X1225205Y360205D01*
G01X1224229Y359229D02*
X1223837Y344087D01*
G01X1225205Y360205D02*
X1224813Y345063D01*
G01X1223837Y344087D02*
X1223782Y341961D01*
G01X1224813Y345063D02*
X1224730Y341840D01*
G01X1222080Y403163D02*
X1223739Y396884D01*
G01X1221221Y402692D02*
X1222802Y396709D01*
G01X1223739Y396884D02*
X1226128Y375545D01*
G01X1222802Y396709D02*
X1225211Y375192D01*
G01X1226128Y375545D02*
X1229858Y370351D01*
G01X1225211Y375192D02*
X1228899Y370056D01*
G01X1229858Y370351D02*
X1229712Y364712D01*
G01D02*
X1229665Y362938D01*
G01X1228899Y370056D02*
X1228735Y363735D01*
G01X1229712Y364712D02*
X1229665Y362938D01*
G01X1228735Y363735D02*
X1228715Y362963D01*
G01X1234189Y366187D02*
X1233876Y354126D01*
G01X1232900Y353150D02*
X1233239Y366212D01*
G01X1225664Y405551D02*
X1227410Y398710D01*
G01X1224805Y405072D02*
X1226480Y398509D01*
G01X1227410Y398710D02*
X1229250Y388350D01*
G01D02*
X1229330Y387900D01*
G01X1226480Y398509D02*
X1228389Y387762D01*
G01X1229330Y387900D02*
X1230603Y376874D01*
G01X1228389Y387762D02*
X1229687Y376520D01*
G01X1230603Y376874D02*
X1234332Y371680D01*
G01X1229687Y376520D02*
X1233374Y371385D01*
G01X1234332Y371680D02*
X1234270Y369270D01*
G01X1233374Y371385D02*
X1233317Y369200D01*
G01X1234268D02*
X1234189Y366187D01*
G01X1233317Y369200D02*
X1233293Y368293D01*
G01X1234268Y369200D02*
X1234189Y366187D01*
G01X1233293Y368293D02*
X1233239Y366212D01*
G01X1229397Y407274D02*
X1230883Y401082D01*
G01X1228533Y406799D02*
X1229953Y400885D01*
G01X1230883Y401082D02*
X1233230Y388354D01*
G01X1229953Y400885D02*
X1232290Y388210D01*
G01X1233230Y388354D02*
X1234341Y379230D01*
G01X1232290Y388210D02*
X1233427Y378874D01*
G01X1234341Y379230D02*
X1238473Y373473D01*
G01D02*
X1238799Y373019D01*
G01X1233427Y378874D02*
X1237841Y372724D01*
G01X1238799Y373019D02*
X1238475Y360530D01*
G01X1232286Y408624D02*
X1235897Y391007D01*
G01X1233161Y409088D02*
X1236834Y391168D01*
G01X1235897Y391007D02*
X1237279Y381069D01*
G01X1236834Y391168D02*
X1238188Y381432D01*
G01X1237279Y381069D02*
X1242270Y374119D01*
G01X1238188Y381432D02*
X1243228Y374414D01*
G01D02*
X1242459Y344788D01*
G01X1236066Y410290D02*
X1239906Y390486D01*
G01X1236946Y410747D02*
X1240843Y390649D01*
G01X1239906Y390486D02*
X1240980Y383477D01*
G01X1240843Y390649D02*
X1241885Y383846D01*
G01X1240980Y383477D02*
X1244113Y379113D01*
G01X1241885Y383846D02*
X1244794Y379794D01*
G01X1244113Y379113D02*
X1246669Y375554D01*
G01X1244794Y379794D02*
X1247627Y375849D01*
G01X1246669Y375554D02*
X1246438Y366646D01*
G01X1247627Y375849D02*
X1247387Y366609D01*
G01X1224905Y429570D02*
X1263843Y392898D01*
G01X1224348Y428788D02*
X1262906Y392475D01*
G01X1263843Y392898D02*
X1264214Y381266D01*
G01X1262906Y392475D02*
X1263258Y381434D01*
G01X1264214Y381266D02*
X1252750Y352602D01*
G01X1263258Y381434D02*
X1256558Y364683D01*
G01X1264214Y381266D02*
X1252750Y352602D01*
G01D02*
X1251400Y349226D01*
G01X1255822Y362843D02*
X1250454Y349421D01*
G01X1227436Y432744D02*
X1268225Y394837D01*
G01X1226879Y431964D02*
X1267287Y394410D01*
G01X1268225Y394837D02*
X1268422Y388672D01*
G01X1267287Y394410D02*
X1267500Y387750D01*
G01X1268422Y388672D02*
X1268681Y380558D01*
G01X1267500Y387750D02*
X1267600Y384631D01*
G01X1268422Y388672D02*
X1268681Y380558D01*
G01X1267600Y384631D02*
X1267725Y380726D01*
G01X1268681Y380558D02*
X1255790Y348329D01*
G01X1267725Y380726D02*
X1254844Y348524D01*
G01X1285093Y364775D02*
X1276810Y344066D01*
G01X1290600Y375987D02*
X1277756Y343871D01*
G01X1276600Y379163D02*
X1263623Y346721D01*
G01X1264569Y346526D02*
X1277556Y378995D01*
G01X1275988Y398336D02*
X1276600Y379163D01*
G01X1277556Y378995D02*
X1276926Y398759D01*
G01X1235152Y436809D02*
X1275988Y398336D01*
G01X1276926Y398759D02*
X1235712Y437587D01*
G01X1272407Y345122D02*
X1284900Y376349D01*
G01X1273353Y344927D02*
X1286425Y377603D01*
G01X1268012Y345819D02*
X1269089Y348511D01*
G01X1268958Y345624D02*
X1269820Y347780D01*
G01X1269089Y348511D02*
X1281037Y378384D01*
G01X1269820Y347780D02*
X1275408Y361749D01*
G01X1269089Y348511D02*
X1281037Y378384D01*
G01X1275407Y361749D02*
X1281993Y378216D01*
G01X1280338Y400298D02*
X1249151Y429685D01*
G01X1281276Y400721D02*
X1249700Y430473D01*
G01X1236066Y410290D02*
X1239906Y390486D01*
G01X1236946Y410747D02*
X1240843Y390649D01*
G01X1239906Y390486D02*
X1240980Y383477D01*
G01X1240843Y390649D02*
X1241885Y383846D01*
G01X1240980Y383477D02*
X1244113Y379113D01*
G01X1241885Y383846D02*
X1244794Y379794D01*
G01X1244113Y379113D02*
X1246669Y375554D01*
G01X1244794Y379794D02*
X1247627Y375849D01*
G01X1246669Y375554D02*
X1246438Y366646D01*
G01X1247627Y375849D02*
X1247387Y366609D01*
G01X1226879Y431964D02*
X1267287Y394410D01*
G01X1227436Y432744D02*
X1268225Y394837D01*
G01X1267287Y394410D02*
X1267500Y387750D01*
G01X1268225Y394837D02*
X1268422Y388672D01*
G01X1267500Y387750D02*
X1267600Y384631D01*
G01D02*
X1267725Y380726D01*
G01X1268422Y388672D02*
X1268681Y380558D01*
G01X1267725Y380726D02*
X1254844Y348524D01*
G01X1268681Y380558D02*
X1255790Y348329D01*
G01X1225340Y365452D02*
X1225205Y360205D01*
G01X1224391Y365477D02*
X1224229Y359229D01*
G01X1225205Y360205D02*
X1224813Y345063D01*
G01X1224229Y359229D02*
X1223837Y344087D01*
G01X1224813Y345063D02*
X1224730Y341840D01*
G01X1223837Y344087D02*
X1223782Y341961D01*
G01X1219396Y397681D02*
X1221688Y374167D01*
G01D02*
X1225254Y369200D01*
G01X1220767Y373820D02*
X1224084Y369200D01*
G01X1221688Y374167D02*
X1225254Y369200D01*
G01D02*
X1225432Y368952D01*
G01X1224084Y369200D02*
X1224474Y368657D01*
G01X1225432Y368952D02*
X1225341Y365453D01*
G01X1224474Y368657D02*
X1224391Y365477D01*
G01X1221221Y402692D02*
X1222802Y396709D01*
G01X1222080Y403163D02*
X1223739Y396884D01*
G01X1222802Y396709D02*
X1225211Y375192D01*
G01X1223739Y396884D02*
X1226128Y375545D01*
G01X1225211Y375192D02*
X1228899Y370056D01*
G01X1226128Y375545D02*
X1229858Y370351D01*
G01X1228899Y370056D02*
X1228735Y363735D01*
G01X1229858Y370351D02*
X1229712Y364712D01*
G01X1228899Y370056D02*
X1228735Y363735D01*
G01D02*
X1228715Y362963D01*
G01X1229712Y364712D02*
X1229665Y362938D01*
G01X1228735Y363735D02*
X1228715Y362963D01*
G01X1236946Y410747D02*
X1240843Y390649D01*
G01X1236066Y410290D02*
X1239906Y390486D01*
G01X1240843Y390649D02*
X1241885Y383846D01*
G01X1239906Y390486D02*
X1240980Y383477D01*
G01X1241885Y383846D02*
X1244794Y379794D01*
G01X1240980Y383477D02*
X1244113Y379113D01*
G01X1244794Y379794D02*
X1247627Y375849D01*
G01X1244113Y379113D02*
X1246669Y375554D01*
G01X1247627Y375849D02*
X1247387Y366609D01*
G01X1246669Y375554D02*
X1246438Y366646D01*
G01X1222080Y403163D02*
X1223739Y396884D01*
G01X1221221Y402692D02*
X1222802Y396709D01*
G01X1223739Y396884D02*
X1226128Y375545D01*
G01X1222802Y396709D02*
X1225211Y375192D01*
G01X1226128Y375545D02*
X1229858Y370351D01*
G01X1225211Y375192D02*
X1228899Y370056D01*
G01X1229858Y370351D02*
X1229712Y364712D01*
G01D02*
X1229665Y362938D01*
G01X1228899Y370056D02*
X1228735Y363735D01*
G01X1229712Y364712D02*
X1229665Y362938D01*
G01X1228735Y363735D02*
X1228715Y362963D01*
G01X1232286Y408624D02*
X1235897Y391007D01*
G01X1233161Y409088D02*
X1236834Y391168D01*
G01X1235897Y391007D02*
X1237279Y381069D01*
G01X1236834Y391168D02*
X1238188Y381432D01*
G01X1237279Y381069D02*
X1242270Y374119D01*
G01X1238188Y381432D02*
X1243228Y374414D01*
G01D02*
X1242459Y344788D01*
G01X1224905Y429570D02*
X1263843Y392898D01*
G01X1224348Y428788D02*
X1262906Y392475D01*
G01X1263843Y392898D02*
X1264214Y381266D01*
G01X1262906Y392475D02*
X1263258Y381434D01*
G01X1264214Y381266D02*
X1252750Y352602D01*
G01X1263258Y381434D02*
X1256558Y364683D01*
G01X1264214Y381266D02*
X1252750Y352602D01*
G01D02*
X1251400Y349226D01*
G01X1255822Y362843D02*
X1250454Y349421D01*
G01X1228533Y406799D02*
X1229953Y400885D01*
G01X1229397Y407274D02*
X1230883Y401082D01*
G01X1229953Y400885D02*
X1232290Y388210D01*
G01X1230883Y401082D02*
X1233230Y388354D01*
G01X1232290Y388210D02*
X1233427Y378874D01*
G01X1233230Y388354D02*
X1234341Y379230D01*
G01X1233427Y378874D02*
X1237841Y372724D01*
G01X1234341Y379230D02*
X1238473Y373473D01*
G01X1233427Y378874D02*
X1237841Y372724D01*
G01X1238473Y373473D02*
X1238799Y373019D01*
G01D02*
X1238475Y360530D01*
G01X1219396Y397681D02*
X1221688Y374167D01*
G01X1220767Y373820D02*
X1224084Y369200D01*
G01D02*
X1224474Y368657D01*
G01X1221688Y374167D02*
X1225254Y369200D01*
G01X1224084D02*
X1224474Y368657D01*
G01X1225254Y369200D02*
X1225432Y368952D01*
G01X1224474Y368657D02*
X1224391Y365477D01*
G01X1225432Y368952D02*
X1225341Y365453D01*
G01X1224391Y365477D02*
X1224229Y359229D01*
G01X1225340Y365452D02*
X1225205Y360205D01*
G01X1224229Y359229D02*
X1223837Y344087D01*
G01X1225205Y360205D02*
X1224813Y345063D01*
G01X1223837Y344087D02*
X1223782Y341961D01*
G01X1224813Y345063D02*
X1224730Y341840D01*
G01X1234189Y366187D02*
X1233876Y354126D01*
G01X1232900Y353150D02*
X1233239Y366212D01*
G01X1225664Y405551D02*
X1227410Y398710D01*
G01X1224805Y405072D02*
X1226480Y398509D01*
G01X1227410Y398710D02*
X1229250Y388350D01*
G01D02*
X1229330Y387900D01*
G01X1226480Y398509D02*
X1228389Y387762D01*
G01X1229330Y387900D02*
X1230603Y376874D01*
G01X1228389Y387762D02*
X1229687Y376520D01*
G01X1230603Y376874D02*
X1234332Y371680D01*
G01X1229687Y376520D02*
X1233374Y371385D01*
G01X1234332Y371680D02*
X1234270Y369270D01*
G01X1233374Y371385D02*
X1233317Y369200D01*
G01X1234268D02*
X1234189Y366187D01*
G01X1233317Y369200D02*
X1233293Y368293D01*
G01X1234268Y369200D02*
X1234189Y366187D01*
G01X1233293Y368293D02*
X1233239Y366212D01*
G01X1229397Y407274D02*
X1230883Y401082D01*
G01X1228533Y406799D02*
X1229953Y400885D01*
G01X1230883Y401082D02*
X1233230Y388354D01*
G01X1229953Y400885D02*
X1232290Y388210D01*
G01X1233230Y388354D02*
X1234341Y379230D01*
G01X1232290Y388210D02*
X1233427Y378874D01*
G01X1234341Y379230D02*
X1238473Y373473D01*
G01D02*
X1238799Y373019D01*
G01X1233427Y378874D02*
X1237841Y372724D01*
G01X1238799Y373019D02*
X1238475Y360530D01*
G01X1235712Y437587D02*
X1218742Y446667D01*
G01X1249700Y430473D02*
X1247925Y431357D01*
G01X1249151Y429685D02*
X1247376Y430569D01*
G01X1247925Y431357D02*
X1237984Y440723D01*
G01X1247376Y430569D02*
X1237424Y439945D01*
G01X1284687Y402262D02*
X1252245Y432830D01*
G01X1285625Y402685D02*
X1252797Y433616D01*
G01X1252245Y432830D02*
X1248559Y434700D01*
G01X1252750Y433640D02*
X1249111Y435486D01*
G01X1248559Y434700D02*
X1239617Y443125D01*
G01X1249111Y435486D02*
X1240177Y443903D01*
G01X1243126Y446707D02*
X1251850Y438487D01*
G01X1242566Y445929D02*
X1251371Y437632D01*
G01X1251850Y438487D02*
X1252750Y438242D01*
G01D02*
X1254584Y437744D01*
G01X1251371Y437632D02*
X1254105Y436889D01*
G01X1254584Y437744D02*
X1289983Y404387D01*
G01X1254105Y436889D02*
X1289045Y403964D01*
G01X1219203Y462822D02*
X1244894Y449075D01*
G01X1219529Y463726D02*
X1245454Y449853D01*
G01X1244894Y449075D02*
X1252750Y441673D01*
G01X1245454Y449853D02*
X1252750Y442979D01*
G01X1244894Y449075D02*
X1252750Y441673D01*
G01D02*
X1252926Y441507D01*
G01X1252750Y442979D02*
X1253399Y442367D01*
G01X1252926Y441507D02*
X1256304Y440642D01*
G01X1253399Y442367D02*
X1256777Y441502D01*
G01X1256304Y440642D02*
X1293402Y405697D01*
G01X1256777Y441502D02*
X1294340Y406120D01*
G01X1254778Y449205D02*
X1220684Y467452D01*
G01X1220359Y466547D02*
X1254218Y448427D01*
G01X1298699Y407830D02*
X1254778Y449205D01*
G01X1254218Y448427D02*
X1297761Y407407D01*
G01X1219915Y422646D02*
X1233161Y409088D01*
G01X1219323Y421892D02*
X1232286Y408624D01*
G01X1222255Y426024D02*
X1222365Y425910D01*
G01D02*
X1236946Y410747D01*
G01X1221665Y425266D02*
X1236066Y410290D01*
G01X1235712Y437587D02*
X1218742Y446667D01*
G01X1249151Y429685D02*
X1247376Y430569D01*
G01X1249700Y430473D02*
X1247925Y431357D01*
G01X1247376Y430569D02*
X1237424Y439945D01*
G01X1247925Y431357D02*
X1237984Y440723D01*
G01X1285625Y402685D02*
X1252797Y433616D01*
G01X1284687Y402262D02*
X1252245Y432830D01*
G01X1252750Y433640D02*
X1249111Y435486D01*
G01X1252245Y432830D02*
X1248559Y434700D01*
G01X1249111Y435486D02*
X1240177Y443903D01*
G01X1248559Y434700D02*
X1239617Y443125D01*
G01X1242566Y445929D02*
X1251371Y437632D01*
G01X1243126Y446707D02*
X1251850Y438487D01*
G01X1251371Y437632D02*
X1254105Y436889D01*
G01X1251850Y438487D02*
X1252750Y438242D01*
G01X1251371Y437632D02*
X1254105Y436889D01*
G01X1252750Y438242D02*
X1254584Y437744D01*
G01X1254105Y436889D02*
X1289045Y403964D01*
G01X1254584Y437744D02*
X1289983Y404387D01*
G01X1219529Y463726D02*
X1245454Y449853D01*
G01X1219203Y462822D02*
X1244894Y449075D01*
G01X1245454Y449853D02*
X1252750Y442979D01*
G01D02*
X1253399Y442367D01*
G01X1244894Y449075D02*
X1252750Y441673D01*
G01Y442979D02*
X1253399Y442367D01*
G01X1252750Y441673D02*
X1252926Y441507D01*
G01X1253399Y442367D02*
X1256777Y441502D01*
G01X1252926Y441507D02*
X1256304Y440642D01*
G01X1256777Y441502D02*
X1294340Y406120D01*
G01X1256304Y440642D02*
X1293402Y405697D01*
G01X1254218Y448427D02*
X1297761Y407407D01*
G01X1298699Y407830D02*
X1254778Y449205D01*
G01X1220359Y466547D02*
X1254218Y448427D01*
G01X1254778Y449205D02*
X1220684Y467452D01*
G01X1219323Y421892D02*
X1232286Y408624D01*
G01X1219915Y422646D02*
X1233161Y409088D01*
G01X1221665Y425266D02*
X1236066Y410290D01*
G01X1222255Y426024D02*
X1222365Y425910D01*
G01X1221665Y425266D02*
X1236066Y410290D01*
G01X1222365Y425910D02*
X1236946Y410747D01*
G01X1219546Y472296D02*
X1256046Y453800D01*
G01X1219232Y471390D02*
X1255494Y453014D01*
G01X1256046Y453800D02*
X1303056Y409513D01*
G01X1255494Y453014D02*
X1302118Y409090D01*
G01X1219546Y472296D02*
X1256046Y453800D01*
G01X1219232Y471390D02*
X1255494Y453014D01*
G01X1256046Y453800D02*
X1303056Y409513D01*
G01X1255494Y453014D02*
X1302118Y409090D01*
G01X1220088Y475292D02*
X1257229Y456669D01*
G01X1220400Y476199D02*
X1257780Y457457D01*
G01X1257229Y456669D02*
X1305000Y411647D01*
G01X1257780Y457457D02*
X1307432Y410662D01*
G01X1221056Y479171D02*
X1258922Y460471D01*
G01X1221365Y480079D02*
X1259470Y461260D01*
G01X1258922Y460471D02*
X1310865Y411524D01*
G01X1259470Y461260D02*
X1311803Y411947D01*
G01X1242566Y445929D02*
X1251371Y437632D01*
G01X1243126Y446707D02*
X1251850Y438487D01*
G01X1251371Y437632D02*
X1254105Y436889D01*
G01X1251850Y438487D02*
X1252750Y438242D01*
G01X1251371Y437632D02*
X1254105Y436889D01*
G01X1252750Y438242D02*
X1254584Y437744D01*
G01X1254105Y436889D02*
X1289045Y403964D01*
G01X1254584Y437744D02*
X1289983Y404387D01*
G01X1219232Y471390D02*
X1255494Y453014D01*
G01X1219546Y472296D02*
X1256046Y453800D01*
G01X1255494Y453014D02*
X1302118Y409090D01*
G01X1256046Y453800D02*
X1303056Y409513D01*
G01X1220400Y476199D02*
X1257780Y457457D01*
G01X1220088Y475292D02*
X1257229Y456669D01*
G01X1257780Y457457D02*
X1307432Y410662D01*
G01X1257229Y456669D02*
X1305000Y411647D01*
G01X1257780Y457457D02*
X1307432Y410662D01*
G01X1257780Y457457D02*
X1307432Y410662D01*
G01X1221365Y480079D02*
X1259470Y461260D01*
G01X1221056Y479171D02*
X1258922Y460471D01*
G01X1259470Y461260D02*
X1311803Y411947D01*
G01X1258922Y460471D02*
X1310865Y411524D01*
G01X1235712Y437587D02*
X1218742Y446667D01*
G01X1284687Y402262D02*
X1252245Y432830D01*
G01X1285625Y402685D02*
X1252797Y433616D01*
G01X1252245Y432830D02*
X1248559Y434700D01*
G01X1252750Y433640D02*
X1249111Y435486D01*
G01X1248559Y434700D02*
X1239617Y443125D01*
G01X1249111Y435486D02*
X1240177Y443903D01*
G01X1219203Y462822D02*
X1244894Y449075D01*
G01X1219529Y463726D02*
X1245454Y449853D01*
G01X1244894Y449075D02*
X1252750Y441673D01*
G01X1245454Y449853D02*
X1252750Y442979D01*
G01X1244894Y449075D02*
X1252750Y441673D01*
G01D02*
X1252926Y441507D01*
G01X1252750Y442979D02*
X1253399Y442367D01*
G01X1252926Y441507D02*
X1256304Y440642D01*
G01X1253399Y442367D02*
X1256777Y441502D01*
G01X1256304Y440642D02*
X1293402Y405697D01*
G01X1256777Y441502D02*
X1294340Y406120D01*
G01X1254778Y449205D02*
X1220684Y467452D01*
G01X1220359Y466547D02*
X1254218Y448427D01*
G01X1298699Y407830D02*
X1254778Y449205D01*
G01X1254218Y448427D02*
X1297761Y407407D01*
G01X1249151Y429685D02*
X1247376Y430569D01*
G01X1249700Y430473D02*
X1247925Y431357D01*
G01X1247376Y430569D02*
X1237424Y439945D01*
G01X1247925Y431357D02*
X1237984Y440723D01*
G01X1221665Y425266D02*
X1236066Y410290D01*
G01X1222255Y426024D02*
X1222365Y425910D01*
G01X1221665Y425266D02*
X1236066Y410290D01*
G01X1222365Y425910D02*
X1236946Y410747D01*
G01X1222255Y426024D02*
X1222365Y425910D01*
G01D02*
X1236946Y410747D01*
G01X1221665Y425266D02*
X1236066Y410290D01*
G01X1219323Y421892D02*
X1232286Y408624D01*
G01X1219915Y422646D02*
X1233161Y409088D01*
G01X1320030Y281451D02*
Y279203D01*
G01X1320980Y281450D02*
Y278809D01*
G01X1320030Y279203D02*
X1318297Y277470D01*
G01X1320980Y278809D02*
X1319247Y277076D01*
G01X1318297Y277470D02*
Y255241D01*
G01X1319247Y277076D02*
Y266720D01*
G01X1318297Y277470D02*
Y255241D01*
G01D02*
Y250148D01*
G01X1319247Y266720D02*
Y249754D01*
G01X1318297Y250148D02*
X1315140Y246991D01*
G01X1319247Y249754D02*
X1316090Y246597D01*
G01X1315140Y246991D02*
Y243922D01*
G01X1316090Y246597D02*
Y242970D01*
G01X1320030Y281451D02*
Y279203D01*
G01X1320980Y281450D02*
Y278809D01*
G01X1320030Y279203D02*
X1318297Y277470D01*
G01X1320980Y278809D02*
X1319247Y277076D01*
G01X1318297Y277470D02*
Y255241D01*
G01X1319247Y277076D02*
Y266720D01*
G01X1318297Y277470D02*
Y255241D01*
G01D02*
Y250148D01*
G01X1319247Y266720D02*
Y249754D01*
G01X1318297Y250148D02*
X1315140Y246991D01*
G01X1319247Y249754D02*
X1316090Y246597D01*
G01X1315140Y246991D02*
Y243922D01*
G01X1316090Y246597D02*
Y242970D01*
G01X1325743Y244643D02*
Y247413D01*
G01X1326693Y244707D02*
Y247807D01*
G01X1325743Y247413D02*
X1323510Y249646D01*
G01X1326693Y247807D02*
X1324460Y250040D01*
G01X1323510Y249646D02*
Y272768D01*
G01X1324460Y250040D02*
Y260962D01*
G01X1323510Y249646D02*
Y272768D01*
G01D02*
Y275239D01*
G01X1324460Y260962D02*
Y274845D01*
G01X1323510Y275239D02*
X1324800Y276529D01*
G01X1324460Y274845D02*
X1325750Y276135D01*
G01X1324800Y276529D02*
Y278597D01*
G01X1325750Y276135D02*
Y278170D01*
G01X1325743Y244643D02*
Y247413D01*
G01X1326693Y244707D02*
Y247807D01*
G01X1325743Y247413D02*
X1323510Y249646D01*
G01X1326693Y247807D02*
X1324460Y250040D01*
G01X1323510Y249646D02*
Y272768D01*
G01X1324460Y250040D02*
Y260962D01*
G01X1323510Y249646D02*
Y272768D01*
G01D02*
Y275239D01*
G01X1324460Y260962D02*
Y274845D01*
G01X1323510Y275239D02*
X1324800Y276529D01*
G01X1324460Y274845D02*
X1325750Y276135D01*
G01X1324800Y276529D02*
Y278597D01*
G01X1325750Y276135D02*
Y278170D01*
G01X1331250Y274949D02*
Y271194D01*
G01X1332200Y274555D02*
Y270800D01*
G01X1331250Y271194D02*
X1328865Y268809D01*
G01X1332200Y270800D02*
X1329815Y268415D01*
G01X1328865Y268809D02*
Y266711D01*
G01D02*
Y253093D01*
G01X1329815Y268415D02*
Y255507D01*
G01X1328865Y266711D02*
Y253093D01*
G01X1329815Y255507D02*
Y253487D01*
G01X1328865Y253093D02*
X1336762Y245196D01*
G01X1329815Y253487D02*
X1337712Y245590D01*
G01X1336762Y245196D02*
Y243544D01*
G01X1337712Y245590D02*
Y243348D01*
G01X1331250Y274949D02*
Y271194D01*
G01X1332200Y274555D02*
Y270800D01*
G01X1331250Y271194D02*
X1328865Y268809D01*
G01X1332200Y270800D02*
X1329815Y268415D01*
G01X1328865Y268809D02*
Y266711D01*
G01D02*
Y253093D01*
G01X1329815Y268415D02*
Y255507D01*
G01X1328865Y266711D02*
Y253093D01*
G01X1329815Y255507D02*
Y253487D01*
G01X1328865Y253093D02*
X1336762Y245196D01*
G01X1329815Y253487D02*
X1337712Y245590D01*
G01X1336762Y245196D02*
Y243544D01*
G01X1337712Y245590D02*
Y243348D01*
G01X1339862Y256652D02*
X1347723Y248791D01*
G01X1337851Y258663D02*
X1339862Y256652D01*
G01D02*
X1347723Y248791D01*
G01X1346683Y251175D02*
X1338801Y259057D01*
G01X1337851Y270352D02*
Y258663D01*
G01X1338801Y259057D02*
Y270308D01*
G01X1320980Y281450D02*
Y278809D01*
G01X1320030Y281451D02*
Y279203D01*
G01X1320980Y278809D02*
X1319247Y277076D01*
G01X1320030Y279203D02*
X1318297Y277470D01*
G01X1319247Y277076D02*
Y266720D01*
G01D02*
Y249754D01*
G01X1318297Y277470D02*
Y255241D01*
G01X1319247Y266720D02*
Y249754D01*
G01X1318297Y255241D02*
Y250148D01*
G01X1319247Y249754D02*
X1316090Y246597D01*
G01X1318297Y250148D02*
X1315140Y246991D01*
G01X1316090Y246597D02*
Y242970D01*
G01X1315140Y246991D02*
Y243922D01*
G01X1320980Y281450D02*
Y278809D01*
G01X1320030Y281451D02*
Y279203D01*
G01X1320980Y278809D02*
X1319247Y277076D01*
G01X1320030Y279203D02*
X1318297Y277470D01*
G01X1319247Y277076D02*
Y266720D01*
G01D02*
Y249754D01*
G01X1318297Y277470D02*
Y255241D01*
G01X1319247Y266720D02*
Y249754D01*
G01X1318297Y255241D02*
Y250148D01*
G01X1319247Y249754D02*
X1316090Y246597D01*
G01X1318297Y250148D02*
X1315140Y246991D01*
G01X1316090Y246597D02*
Y242970D01*
G01X1315140Y246991D02*
Y243922D01*
G01X1326693Y244707D02*
Y247807D01*
G01X1325743Y244643D02*
Y247413D01*
G01X1326693Y247807D02*
X1324460Y250040D01*
G01X1325743Y247413D02*
X1323510Y249646D01*
G01X1324460Y250040D02*
Y260962D01*
G01D02*
Y274845D01*
G01X1323510Y249646D02*
Y272768D01*
G01X1324460Y260962D02*
Y274845D01*
G01X1323510Y272768D02*
Y275239D01*
G01X1324460Y274845D02*
X1325750Y276135D01*
G01X1323510Y275239D02*
X1324800Y276529D01*
G01X1325750Y276135D02*
Y278170D01*
G01X1324800Y276529D02*
Y278597D01*
G01X1326693Y244707D02*
Y247807D01*
G01X1325743Y244643D02*
Y247413D01*
G01X1326693Y247807D02*
X1324460Y250040D01*
G01X1325743Y247413D02*
X1323510Y249646D01*
G01X1324460Y250040D02*
Y260962D01*
G01D02*
Y274845D01*
G01X1323510Y249646D02*
Y272768D01*
G01X1324460Y260962D02*
Y274845D01*
G01X1323510Y272768D02*
Y275239D01*
G01X1324460Y274845D02*
X1325750Y276135D01*
G01X1323510Y275239D02*
X1324800Y276529D01*
G01X1325750Y276135D02*
Y278170D01*
G01X1324800Y276529D02*
Y278597D01*
G01X1332200Y274555D02*
Y270800D01*
G01X1331250Y274949D02*
Y271194D01*
G01X1332200Y270800D02*
X1329815Y268415D01*
G01X1331250Y271194D02*
X1328865Y268809D01*
G01X1329815Y268415D02*
Y255507D01*
G01X1328865Y268809D02*
Y266711D01*
G01X1329815Y268415D02*
Y255507D01*
G01D02*
Y253487D01*
G01X1328865Y266711D02*
Y253093D01*
G01X1329815Y253487D02*
X1337712Y245590D01*
G01X1328865Y253093D02*
X1336762Y245196D01*
G01X1337712Y245590D02*
Y243348D01*
G01X1336762Y245196D02*
Y243544D01*
G01X1332200Y274555D02*
Y270800D01*
G01X1331250Y274949D02*
Y271194D01*
G01X1332200Y270800D02*
X1329815Y268415D01*
G01X1331250Y271194D02*
X1328865Y268809D01*
G01X1329815Y268415D02*
Y255507D01*
G01X1328865Y268809D02*
Y266711D01*
G01X1329815Y268415D02*
Y255507D01*
G01D02*
Y253487D01*
G01X1328865Y266711D02*
Y253093D01*
G01X1329815Y253487D02*
X1337712Y245590D01*
G01X1328865Y253093D02*
X1336762Y245196D01*
G01X1337712Y245590D02*
Y243348D01*
G01X1336762Y245196D02*
Y243544D01*
G01X1338801Y259057D02*
Y270308D01*
G01X1337851Y270352D02*
Y258663D01*
G01X1346683Y251175D02*
X1338801Y259057D01*
G01X1337851Y258663D02*
X1339862Y256652D01*
G01X1346683Y251175D02*
X1338801Y259057D01*
G01X1339862Y256652D02*
X1347723Y248791D01*
G01X1338801Y259057D02*
Y270308D01*
G01X1337851Y270352D02*
Y258663D01*
G01X1346683Y251175D02*
X1338801Y259057D01*
G01X1337851Y258663D02*
X1339862Y256652D01*
G01X1346683Y251175D02*
X1338801Y259057D01*
G01X1339862Y256652D02*
X1347723Y248791D01*
G01X1339862Y256652D02*
X1347723Y248791D01*
G01X1337851Y258663D02*
X1339862Y256652D01*
G01D02*
X1347723Y248791D01*
G01X1346683Y251175D02*
X1338801Y259057D01*
G01X1337851Y270352D02*
Y258663D01*
G01X1338801Y259057D02*
Y270308D01*
G01X1281188Y343137D02*
X1280651Y322500D01*
G01X1282134Y342942D02*
X1281602Y322500D01*
G01X1280651D02*
X1280316Y309638D01*
G01X1281602Y322500D02*
X1281260Y309380D01*
G01D02*
X1280747Y308459D01*
G01X1285795Y314300D02*
X1286515Y342000D01*
G01X1285564Y342017D02*
X1284844Y314300D01*
G01X1285639Y308299D02*
X1285795Y314300D01*
G01X1284844D02*
X1284695Y308557D01*
G01X1283946Y305260D02*
X1285639Y308299D01*
G01X1282134Y342942D02*
X1281602Y322500D01*
G01X1281188Y343137D02*
X1280651Y322500D01*
G01X1281602D02*
X1281260Y309380D01*
G01X1280651Y322500D02*
X1280316Y309638D01*
G01X1281260Y309380D02*
X1280747Y308459D01*
G01X1281260Y309380D02*
X1280747Y308459D01*
G01X1283946Y305260D02*
X1285639Y308299D01*
G01X1284844Y314300D02*
X1284695Y308557D01*
G01X1285639Y308299D02*
X1285795Y314300D01*
G01X1285564Y342017D02*
X1284844Y314300D01*
G01X1285795D02*
X1286515Y342000D01*
G01X1304176Y374391D02*
X1290893Y341187D01*
G01X1304176Y374391D02*
X1290893Y341187D01*
G01D02*
X1290003Y306946D01*
G01X1289947Y341382D02*
X1289059Y307204D01*
G01D02*
X1286534Y302672D01*
G01X1304176Y374391D02*
X1290893Y341187D01*
G01X1304176Y374391D02*
X1290893Y341187D01*
G01D02*
X1290003Y306946D01*
G01X1289947Y341382D02*
X1289059Y307204D01*
G01D02*
X1286534Y302672D01*
G01X1295000Y342044D02*
X1294349Y340416D01*
G01X1295865Y341646D02*
X1295295Y340221D01*
G01X1294349Y340416D02*
X1293671Y314300D01*
G01X1295295Y340221D02*
X1295000Y328859D01*
G01X1294349Y340416D02*
X1293671Y314300D01*
G01X1295000Y328859D02*
X1294622Y314300D01*
G01X1293671D02*
X1293456Y306031D01*
G01X1294622Y314300D02*
X1294400Y305773D01*
G01X1307729Y361992D02*
X1299851Y338503D01*
G01X1308621Y361664D02*
X1300792Y338321D01*
G01X1299851Y338503D02*
X1297860Y304871D01*
G01X1300792Y338321D02*
X1298796Y304598D01*
G01X1304176Y374391D02*
X1290893Y341187D01*
G01X1289947Y341382D02*
X1289059Y307204D01*
G01X1290893Y341187D02*
X1290003Y306946D01*
G01X1289059Y307204D02*
X1286534Y302672D01*
G01X1295865Y341646D02*
X1295295Y340221D01*
G01X1295000Y342044D02*
X1294349Y340416D01*
G01X1295295Y340221D02*
X1295000Y328859D01*
G01D02*
X1294622Y314300D01*
G01X1294349Y340416D02*
X1293671Y314300D01*
G01X1294622D02*
X1294400Y305773D01*
G01X1293671Y314300D02*
X1293456Y306031D01*
G01X1308621Y361664D02*
X1300792Y338321D01*
G01X1307729Y361992D02*
X1299851Y338503D01*
G01X1300792Y338321D02*
X1298796Y304598D01*
G01X1299851Y338503D02*
X1297860Y304871D01*
G01X1281188Y343137D02*
X1280651Y322500D01*
G01X1282134Y342942D02*
X1281602Y322500D01*
G01X1280651D02*
X1280316Y309638D01*
G01X1281602Y322500D02*
X1281260Y309380D01*
G01D02*
X1280747Y308459D01*
G01X1285795Y314300D02*
X1286515Y342000D01*
G01X1285564Y342017D02*
X1284844Y314300D01*
G01X1285639Y308299D02*
X1285795Y314300D01*
G01X1284844D02*
X1284695Y308557D01*
G01X1283946Y305260D02*
X1285639Y308299D01*
G01X1340621Y317770D02*
X1338636D01*
G01X1340924Y316820D02*
X1339030D01*
G01X1338636Y317770D02*
X1335950Y315084D01*
G01X1339030Y316820D02*
X1336900Y314690D01*
G01X1335950Y315084D02*
Y312150D01*
G01X1336900Y314690D02*
Y312150D01*
G01X1340924Y316820D02*
X1339030D01*
G01X1340621Y317770D02*
X1338636D01*
G01X1339030Y316820D02*
X1336900Y314690D01*
G01X1338636Y317770D02*
X1335950Y315084D01*
G01X1336900Y314690D02*
Y312150D01*
G01X1335950Y315084D02*
Y312150D01*
G01X1281993Y378216D02*
X1281276Y400721D01*
G01X1281037Y378384D02*
X1280338Y400298D01*
G01X1284900Y376349D02*
X1285469Y377771D01*
G01D02*
X1284900Y395591D01*
G01D02*
X1284687Y402262D01*
G01X1286425Y377603D02*
X1285625Y402685D01*
G01X1289983Y404387D02*
X1290867Y376655D01*
G01X1289045Y403964D02*
X1289911Y376823D01*
G01X1290867Y376655D02*
X1290600Y375987D01*
G01X1289911Y376823D02*
X1285093Y364775D01*
G01X1293402Y405697D02*
X1294348Y376037D01*
G01X1294340Y406120D02*
X1295000Y385409D01*
G01X1293402Y405697D02*
X1294348Y376037D01*
G01X1295000Y385409D02*
X1295304Y375869D01*
G01X1294348Y376037D02*
X1288486Y361382D01*
G01X1295304Y375869D02*
X1295000Y375109D01*
G01X1294348Y376037D02*
X1288486Y361382D01*
G01X1295000Y375109D02*
X1292637Y369200D01*
G01X1294348Y376037D02*
X1288486Y361382D01*
G01X1292637Y369200D02*
X1291900Y367358D01*
G01X1294348Y376037D02*
X1288486Y361382D01*
G01X1291900Y367358D02*
X1289217Y360651D01*
G01X1288486Y361382D02*
X1287775Y359605D01*
G01X1289217Y360651D02*
X1288658Y359253D01*
G01X1288486Y361382D02*
X1287775Y359605D01*
G01X1287772Y359598D02*
X1287768Y359588D01*
G01X1288657Y359250D02*
X1288651Y359235D01*
G01X1287759Y359562D02*
X1281188Y343137D01*
G01X1288647Y359224D02*
X1282134Y342942D01*
G01X1299742Y375092D02*
X1298699Y407830D01*
G01X1297761Y407407D02*
X1298786Y375260D01*
G01X1293060Y358386D02*
X1297385Y369200D01*
G01D02*
X1299742Y375092D01*
G01X1298786Y375260D02*
X1292178Y358739D01*
G01X1292610Y357258D02*
X1293060Y358384D01*
G01Y358386D02*
X1297385Y369200D01*
G01X1292177Y358736D02*
X1291900Y358043D01*
G01X1286516Y342022D02*
X1292610Y357258D01*
G01D02*
X1293060Y358384D01*
G01X1291879Y357989D02*
X1285570Y342217D01*
G01X1281037Y378384D02*
X1280338Y400298D01*
G01X1281993Y378216D02*
X1281276Y400721D01*
G01X1284900Y376349D02*
X1285469Y377771D01*
G01X1286425Y377603D02*
X1285625Y402685D01*
G01X1285469Y377771D02*
X1284900Y395591D01*
G01X1286425Y377603D02*
X1285625Y402685D01*
G01X1284900Y395591D02*
X1284687Y402262D01*
G01X1289045Y403964D02*
X1289911Y376823D01*
G01X1289983Y404387D02*
X1290867Y376655D01*
G01X1289911Y376823D02*
X1285093Y364775D01*
G01X1290867Y376655D02*
X1290600Y375987D01*
G01X1289911Y376823D02*
X1285093Y364775D01*
G01X1294340Y406120D02*
X1295000Y385409D01*
G01D02*
X1295304Y375869D01*
G01X1293402Y405697D02*
X1294348Y376037D01*
G01X1295304Y375869D02*
X1295000Y375109D01*
G01D02*
X1292637Y369200D01*
G01D02*
X1291900Y367358D01*
G01D02*
X1289217Y360651D01*
G01X1294348Y376037D02*
X1288486Y361382D01*
G01X1289217Y360651D02*
X1288658Y359253D01*
G01X1288657Y359250D02*
X1288651Y359235D01*
G01X1288486Y361382D02*
X1287775Y359605D01*
G01X1288657Y359250D02*
X1288651Y359235D01*
G01X1287772Y359598D02*
X1287768Y359588D01*
G01X1288647Y359224D02*
X1282134Y342942D01*
G01X1287759Y359562D02*
X1281188Y343137D01*
G01X1291879Y357989D02*
X1285570Y342217D01*
G01X1286516Y342022D02*
X1292610Y357258D01*
G01X1292177Y358736D02*
X1291900Y358043D01*
G01X1291879Y357989D02*
X1285570Y342217D01*
G01X1292610Y357258D02*
X1293060Y358384D01*
G01X1298786Y375260D02*
X1292178Y358739D01*
G01X1292177Y358736D02*
X1291900Y358043D01*
G01X1293060Y358386D02*
X1297385Y369200D01*
G01X1298786Y375260D02*
X1292178Y358739D01*
G01X1297385Y369200D02*
X1299742Y375092D01*
G01X1297761Y407407D02*
X1298786Y375260D01*
G01X1299742Y375092D02*
X1298699Y407830D01*
G01X1303056Y409513D02*
X1304176Y374391D01*
G01X1302118Y409090D02*
X1303220Y374559D01*
G01D02*
X1295244Y354624D01*
G01D02*
X1289947Y341382D01*
G01X1303056Y409513D02*
X1304176Y374391D01*
G01X1302118Y409090D02*
X1303220Y374559D01*
G01D02*
X1295244Y354624D01*
G01D02*
X1289947Y341382D01*
G01X1306494Y410239D02*
X1307660Y373696D01*
G01X1307432Y410662D02*
X1308616Y373528D01*
G01X1307660Y373696D02*
X1305861Y369200D01*
G01X1308616Y373528D02*
X1306885Y369200D01*
G01X1305861D02*
X1305000Y367048D01*
G01D02*
X1301003Y357055D01*
G01X1306885Y369200D02*
X1301896Y356728D01*
G01X1300999Y357043D02*
X1298664Y351204D01*
G01D02*
X1295000Y342044D01*
G01X1301892Y356716D02*
X1295865Y341647D01*
G01X1310865Y411524D02*
X1312097Y372911D01*
G01X1311803Y411947D02*
X1312768Y381682D01*
G01X1310865Y411524D02*
X1312097Y372911D01*
G01X1312768Y381682D02*
X1313053Y372743D01*
G01X1312097Y372911D02*
X1307729Y361992D01*
G01X1313053Y372743D02*
X1308621Y361664D01*
G01X1289045Y403964D02*
X1289911Y376823D01*
G01X1289983Y404387D02*
X1290867Y376655D01*
G01X1289911Y376823D02*
X1285093Y364775D01*
G01X1290867Y376655D02*
X1290600Y375987D01*
G01X1289911Y376823D02*
X1285093Y364775D01*
G01X1302118Y409090D02*
X1303220Y374559D01*
G01X1303056Y409513D02*
X1304176Y374391D01*
G01X1303220Y374559D02*
X1295244Y354624D01*
G01D02*
X1289947Y341382D01*
G01X1307432Y410662D02*
X1308616Y373528D01*
G01X1306494Y410239D02*
X1307660Y373696D01*
G01X1308616Y373528D02*
X1306885Y369200D01*
G01X1307660Y373696D02*
X1305861Y369200D01*
G01X1306885D02*
X1301896Y356728D01*
G01X1305861Y369200D02*
X1305000Y367048D01*
G01X1306885Y369200D02*
X1301896Y356728D01*
G01X1305000Y367048D02*
X1301003Y357055D01*
G01X1301892Y356716D02*
X1295865Y341647D01*
G01X1300999Y357043D02*
X1298664Y351204D01*
G01X1301892Y356716D02*
X1295865Y341647D01*
G01X1298664Y351204D02*
X1295000Y342044D01*
G01X1311803Y411947D02*
X1312768Y381682D01*
G01D02*
X1313053Y372743D01*
G01X1310865Y411524D02*
X1312097Y372911D01*
G01X1313053Y372743D02*
X1308621Y361664D01*
G01X1312097Y372911D02*
X1307729Y361992D01*
G01X1284900Y376349D02*
X1285469Y377771D01*
G01D02*
X1284900Y395591D01*
G01D02*
X1284687Y402262D01*
G01X1286425Y377603D02*
X1285625Y402685D01*
G01X1293402Y405697D02*
X1294348Y376037D01*
G01X1294340Y406120D02*
X1295000Y385409D01*
G01X1293402Y405697D02*
X1294348Y376037D01*
G01X1295000Y385409D02*
X1295304Y375869D01*
G01X1294348Y376037D02*
X1288486Y361382D01*
G01X1295304Y375869D02*
X1295000Y375109D01*
G01X1294348Y376037D02*
X1288486Y361382D01*
G01X1295000Y375109D02*
X1292637Y369200D01*
G01X1294348Y376037D02*
X1288486Y361382D01*
G01X1292637Y369200D02*
X1291900Y367358D01*
G01X1294348Y376037D02*
X1288486Y361382D01*
G01X1291900Y367358D02*
X1289217Y360651D01*
G01X1288486Y361382D02*
X1287775Y359605D01*
G01X1289217Y360651D02*
X1288658Y359253D01*
G01X1288486Y361382D02*
X1287775Y359605D01*
G01X1287772Y359598D02*
X1287768Y359588D01*
G01X1288657Y359250D02*
X1288651Y359235D01*
G01X1287759Y359562D02*
X1281188Y343137D01*
G01X1288647Y359224D02*
X1282134Y342942D01*
G01X1299742Y375092D02*
X1298699Y407830D01*
G01X1297761Y407407D02*
X1298786Y375260D01*
G01X1293060Y358386D02*
X1297385Y369200D01*
G01D02*
X1299742Y375092D01*
G01X1298786Y375260D02*
X1292178Y358739D01*
G01X1292610Y357258D02*
X1293060Y358384D01*
G01Y358386D02*
X1297385Y369200D01*
G01X1292177Y358736D02*
X1291900Y358043D01*
G01X1286516Y342022D02*
X1292610Y357258D01*
G01D02*
X1293060Y358384D01*
G01X1291879Y357989D02*
X1285570Y342217D01*
G01X1281037Y378384D02*
X1280338Y400298D01*
G01X1281993Y378216D02*
X1281276Y400721D01*
G01X1305000Y411647D02*
X1306000Y410705D01*
G01D02*
X1306494Y410239D01*
G01X1305000Y411647D02*
X1306000Y410705D01*
G01D02*
X1306494Y410239D01*
G01X1347723Y248791D02*
Y243505D01*
G01X1348673Y243387D02*
Y249185D01*
G01D02*
X1346683Y251175D01*
G01X1348673Y249185D02*
X1346683Y251175D01*
G01X1348673Y243387D02*
Y249185D01*
G01X1347723Y248791D02*
Y243505D01*
G01X1348673Y249185D02*
X1346683Y251175D01*
G01X1348673Y243387D02*
Y249185D01*
G01X1347723Y248791D02*
Y243505D01*
G01Y248791D02*
Y243505D01*
G01X1348673Y243387D02*
Y249185D01*
G01D02*
X1346683Y251175D01*
G01X1345105Y266658D02*
Y262331D01*
G01X1346055Y266682D02*
Y262725D01*
G01X1345105Y262331D02*
X1346640Y260796D01*
G01D02*
X1358723Y248713D01*
G01X1346055Y262725D02*
X1353668Y255112D01*
G01X1346640Y260796D02*
X1358723Y248713D01*
G01X1353668Y255112D02*
X1359673Y249107D01*
G01X1358723Y248713D02*
Y243505D01*
G01X1359673Y249107D02*
Y243387D01*
G01X1345105Y266658D02*
Y262331D01*
G01X1346055Y266682D02*
Y262725D01*
G01X1345105Y262331D02*
X1346640Y260796D01*
G01D02*
X1358723Y248713D01*
G01X1346055Y262725D02*
X1353668Y255112D01*
G01X1346640Y260796D02*
X1358723Y248713D01*
G01X1353668Y255112D02*
X1359673Y249107D01*
G01X1358723Y248713D02*
Y243505D01*
G01X1359673Y249107D02*
Y243387D01*
G01X1353893Y261263D02*
Y264270D01*
G01X1354843D02*
Y261657D01*
G01X1369623Y245533D02*
X1362848Y252308D01*
G01D02*
X1353893Y261263D01*
G01X1354843Y261657D02*
X1368828Y247672D01*
G01X1369623Y245533D02*
X1362848Y252308D01*
G01X1368828Y247672D02*
X1370573Y245927D01*
G01X1369623Y243405D02*
Y245533D01*
G01X1370573Y245927D02*
Y243487D01*
G01X1353893Y261263D02*
Y264270D01*
G01X1354843D02*
Y261657D01*
G01X1369623Y245533D02*
X1362848Y252308D01*
G01D02*
X1353893Y261263D01*
G01X1354843Y261657D02*
X1368828Y247672D01*
G01X1369623Y245533D02*
X1362848Y252308D01*
G01X1368828Y247672D02*
X1370573Y245927D01*
G01X1369623Y243405D02*
Y245533D01*
G01X1370573Y245927D02*
Y243487D01*
G01X1364628Y268284D02*
Y265911D01*
G01X1363678Y266400D02*
Y268678D01*
G01X1365434Y269090D02*
X1364628Y268284D01*
G01X1363678Y268678D02*
X1365040Y270040D01*
G01X1369749Y269090D02*
X1368834D01*
G01X1366584D02*
X1365434D01*
G01X1365040Y270040D02*
X1370143D01*
G01X1372060Y266779D02*
X1369749Y269090D01*
G01X1370143Y270040D02*
X1373010Y267173D01*
G01X1372060Y264658D02*
Y266779D01*
G01X1373010Y267173D02*
Y264264D01*
G01X1366331Y258929D02*
X1372060Y264658D01*
G01X1373010Y264264D02*
X1371834Y263088D01*
G01X1366331Y258929D02*
X1372060Y264658D01*
G01X1366331Y258929D02*
X1364701Y257299D01*
G01X1371834Y263088D02*
X1365651Y256905D01*
G01X1364701Y257299D02*
Y255875D01*
G01X1365651Y256905D02*
Y256269D01*
G01X1364701Y255875D02*
X1367040Y253536D01*
G01X1365651Y256269D02*
X1367434Y254486D01*
G01X1367040Y253536D02*
X1368464D01*
G01D02*
X1371542Y256614D01*
G01X1367434Y254486D02*
X1368070D01*
G01X1368464Y253536D02*
X1371542Y256614D01*
G01X1368070Y254486D02*
X1371148Y257564D01*
G01X1371542Y256614D02*
X1372176D01*
G01X1371148Y257564D02*
X1372570D01*
G01X1372176Y256614D02*
X1373964Y254826D01*
G01X1372570Y257564D02*
X1374914Y255220D01*
G01X1373964Y254826D02*
Y254192D01*
G01X1374914Y255220D02*
Y253798D01*
G01X1373964Y254192D02*
X1370886Y251114D01*
G01X1374914Y253798D02*
X1371836Y250720D01*
G01X1370886Y251114D02*
Y249690D01*
G01X1371836Y250720D02*
Y250084D01*
G01X1370886Y249690D02*
X1373225Y247351D01*
G01X1371836Y250084D02*
X1373619Y248301D01*
G01X1373225Y247351D02*
X1374649D01*
G01D02*
X1378036Y250738D01*
G01X1373619Y248301D02*
X1374255D01*
G01X1374649Y247351D02*
X1378036Y250738D01*
G01D02*
X1378670D01*
G01X1374255Y248301D02*
X1377642Y251688D01*
G01X1378036Y250738D02*
X1378670D01*
G01X1377642Y251688D02*
X1379064D01*
G01X1378036Y250738D02*
X1378670D01*
G01D02*
X1381283Y248125D01*
G01X1379064Y251688D02*
X1382233Y248519D01*
G01X1381283Y248125D02*
Y247235D01*
G01Y244985D02*
Y243277D01*
G01X1382233Y248519D02*
Y242827D01*
G01X1364628Y268284D02*
Y265911D01*
G01X1363678Y266400D02*
Y268678D01*
G01X1365434Y269090D02*
X1364628Y268284D01*
G01X1363678Y268678D02*
X1365040Y270040D01*
G01X1369749Y269090D02*
X1368834D01*
G01X1366584D02*
X1365434D01*
G01X1365040Y270040D02*
X1370143D01*
G01X1372060Y266779D02*
X1369749Y269090D01*
G01X1370143Y270040D02*
X1373010Y267173D01*
G01X1372060Y264658D02*
Y266779D01*
G01X1373010Y267173D02*
Y264264D01*
G01X1366331Y258929D02*
X1372060Y264658D01*
G01X1373010Y264264D02*
X1371834Y263088D01*
G01X1366331Y258929D02*
X1372060Y264658D01*
G01X1366331Y258929D02*
X1364701Y257299D01*
G01X1371834Y263088D02*
X1365651Y256905D01*
G01X1364701Y257299D02*
Y255875D01*
G01X1365651Y256905D02*
Y256269D01*
G01X1364701Y255875D02*
X1367040Y253536D01*
G01X1365651Y256269D02*
X1367434Y254486D01*
G01X1367040Y253536D02*
X1368464D01*
G01D02*
X1371542Y256614D01*
G01X1367434Y254486D02*
X1368070D01*
G01X1368464Y253536D02*
X1371542Y256614D01*
G01X1368070Y254486D02*
X1371148Y257564D01*
G01X1371542Y256614D02*
X1372176D01*
G01X1371148Y257564D02*
X1372570D01*
G01X1372176Y256614D02*
X1373964Y254826D01*
G01X1372570Y257564D02*
X1374914Y255220D01*
G01X1373964Y254826D02*
Y254192D01*
G01X1374914Y255220D02*
Y253798D01*
G01X1373964Y254192D02*
X1370886Y251114D01*
G01X1374914Y253798D02*
X1371836Y250720D01*
G01X1370886Y251114D02*
Y249690D01*
G01X1371836Y250720D02*
Y250084D01*
G01X1370886Y249690D02*
X1373225Y247351D01*
G01X1371836Y250084D02*
X1373619Y248301D01*
G01X1373225Y247351D02*
X1374649D01*
G01D02*
X1378036Y250738D01*
G01X1373619Y248301D02*
X1374255D01*
G01X1374649Y247351D02*
X1378036Y250738D01*
G01D02*
X1378670D01*
G01X1374255Y248301D02*
X1377642Y251688D01*
G01X1378036Y250738D02*
X1378670D01*
G01X1377642Y251688D02*
X1379064D01*
G01X1378036Y250738D02*
X1378670D01*
G01D02*
X1381283Y248125D01*
G01X1379064Y251688D02*
X1382233Y248519D01*
G01X1381283Y248125D02*
Y247235D01*
G01Y244985D02*
Y243277D01*
G01X1382233Y248519D02*
Y242827D01*
G01X1378802Y264320D02*
Y258498D01*
G01X1379752Y264321D02*
Y258892D01*
G01X1378802Y258498D02*
X1387012Y250288D01*
G01X1379752Y258892D02*
X1382472Y256172D01*
G01X1378802Y258498D02*
X1387012Y250288D01*
G01D02*
X1391473Y245827D01*
G01X1382472Y256172D02*
X1392423Y246221D01*
G01X1391473Y245827D02*
Y243255D01*
G01X1392423Y246221D02*
Y243637D01*
G01X1378802Y264320D02*
Y258498D01*
G01X1379752Y264321D02*
Y258892D01*
G01X1378802Y258498D02*
X1387012Y250288D01*
G01X1379752Y258892D02*
X1382472Y256172D01*
G01X1378802Y258498D02*
X1387012Y250288D01*
G01D02*
X1391473Y245827D01*
G01X1382472Y256172D02*
X1392423Y246221D01*
G01X1391473Y245827D02*
Y243255D01*
G01X1392423Y246221D02*
Y243637D01*
G01X1346055Y266682D02*
Y262725D01*
G01X1345105Y266658D02*
Y262331D01*
G01X1346055Y262725D02*
X1353668Y255112D01*
G01X1345105Y262331D02*
X1346640Y260796D01*
G01X1346055Y262725D02*
X1353668Y255112D01*
G01D02*
X1359673Y249107D01*
G01X1346640Y260796D02*
X1358723Y248713D01*
G01X1359673Y249107D02*
Y243387D01*
G01X1358723Y248713D02*
Y243505D01*
G01X1346055Y266682D02*
Y262725D01*
G01X1345105Y266658D02*
Y262331D01*
G01X1346055Y262725D02*
X1353668Y255112D01*
G01X1345105Y262331D02*
X1346640Y260796D01*
G01X1346055Y262725D02*
X1353668Y255112D01*
G01D02*
X1359673Y249107D01*
G01X1346640Y260796D02*
X1358723Y248713D01*
G01X1359673Y249107D02*
Y243387D01*
G01X1358723Y248713D02*
Y243505D01*
G01X1370573Y245927D02*
Y243487D01*
G01X1369623Y243405D02*
Y245533D01*
G01X1354843Y261657D02*
X1368828Y247672D01*
G01D02*
X1370573Y245927D01*
G01X1369623Y245533D02*
X1362848Y252308D01*
G01X1354843Y261657D02*
X1368828Y247672D01*
G01X1362848Y252308D02*
X1353893Y261263D01*
G01X1354843Y264270D02*
Y261657D01*
G01X1353893Y261263D02*
Y264270D01*
G01X1370573Y245927D02*
Y243487D01*
G01X1369623Y243405D02*
Y245533D01*
G01X1354843Y261657D02*
X1368828Y247672D01*
G01D02*
X1370573Y245927D01*
G01X1369623Y245533D02*
X1362848Y252308D01*
G01X1354843Y261657D02*
X1368828Y247672D01*
G01X1362848Y252308D02*
X1353893Y261263D01*
G01X1354843Y264270D02*
Y261657D01*
G01X1353893Y261263D02*
Y264270D01*
G01X1373010Y264264D02*
X1371834Y263088D01*
G01D02*
X1365651Y256905D01*
G01X1366331Y258929D02*
X1372060Y264658D01*
G01X1373010Y267173D02*
Y264264D01*
G01X1372060Y264658D02*
Y266779D01*
G01X1370143Y270040D02*
X1373010Y267173D01*
G01X1372060Y266779D02*
X1369749Y269090D01*
G01X1365040Y270040D02*
X1370143D01*
G01X1369749Y269090D02*
X1368834D01*
G01X1365040Y270040D02*
X1370143D01*
G01X1366584Y269090D02*
X1365434D01*
G01X1363678Y268678D02*
X1365040Y270040D01*
G01X1365434Y269090D02*
X1364628Y268284D01*
G01X1363678Y266400D02*
Y268678D01*
G01X1364628Y268284D02*
Y265911D01*
G01X1371834Y263088D02*
X1365651Y256905D01*
G01X1366331Y258929D02*
X1364701Y257299D01*
G01X1365651Y256905D02*
Y256269D01*
G01X1364701Y257299D02*
Y255875D01*
G01X1365651Y256269D02*
X1367434Y254486D01*
G01X1364701Y255875D02*
X1367040Y253536D01*
G01X1367434Y254486D02*
X1368070D01*
G01X1367040Y253536D02*
X1368464D01*
G01X1367434Y254486D02*
X1368070D01*
G01D02*
X1371148Y257564D01*
G01X1368464Y253536D02*
X1371542Y256614D01*
G01X1371148Y257564D02*
X1372570D01*
G01X1371542Y256614D02*
X1372176D01*
G01X1372570Y257564D02*
X1374914Y255220D01*
G01X1372176Y256614D02*
X1373964Y254826D01*
G01X1374914Y255220D02*
Y253798D01*
G01X1373964Y254826D02*
Y254192D01*
G01X1374914Y253798D02*
X1371836Y250720D01*
G01X1373964Y254192D02*
X1370886Y251114D01*
G01X1371836Y250720D02*
Y250084D01*
G01X1370886Y251114D02*
Y249690D01*
G01X1371836Y250084D02*
X1373619Y248301D01*
G01X1370886Y249690D02*
X1373225Y247351D01*
G01X1373619Y248301D02*
X1374255D01*
G01X1373225Y247351D02*
X1374649D01*
G01X1373619Y248301D02*
X1374255D01*
G01D02*
X1377642Y251688D01*
G01X1374649Y247351D02*
X1378036Y250738D01*
G01X1374255Y248301D02*
X1377642Y251688D01*
G01D02*
X1379064D01*
G01D02*
X1382233Y248519D01*
G01X1378036Y250738D02*
X1378670D01*
G01X1379064Y251688D02*
X1382233Y248519D01*
G01X1378670Y250738D02*
X1381283Y248125D01*
G01X1382233Y248519D02*
Y242827D01*
G01X1381283Y248125D02*
Y247235D01*
G01X1382233Y248519D02*
Y242827D01*
G01X1381283Y244985D02*
Y243277D01*
G01X1373010Y264264D02*
X1371834Y263088D01*
G01D02*
X1365651Y256905D01*
G01X1366331Y258929D02*
X1372060Y264658D01*
G01X1373010Y267173D02*
Y264264D01*
G01X1372060Y264658D02*
Y266779D01*
G01X1370143Y270040D02*
X1373010Y267173D01*
G01X1372060Y266779D02*
X1369749Y269090D01*
G01X1365040Y270040D02*
X1370143D01*
G01X1369749Y269090D02*
X1368834D01*
G01X1365040Y270040D02*
X1370143D01*
G01X1366584Y269090D02*
X1365434D01*
G01X1363678Y268678D02*
X1365040Y270040D01*
G01X1365434Y269090D02*
X1364628Y268284D01*
G01X1363678Y266400D02*
Y268678D01*
G01X1364628Y268284D02*
Y265911D01*
G01X1371834Y263088D02*
X1365651Y256905D01*
G01X1366331Y258929D02*
X1364701Y257299D01*
G01X1365651Y256905D02*
Y256269D01*
G01X1364701Y257299D02*
Y255875D01*
G01X1365651Y256269D02*
X1367434Y254486D01*
G01X1364701Y255875D02*
X1367040Y253536D01*
G01X1367434Y254486D02*
X1368070D01*
G01X1367040Y253536D02*
X1368464D01*
G01X1367434Y254486D02*
X1368070D01*
G01D02*
X1371148Y257564D01*
G01X1368464Y253536D02*
X1371542Y256614D01*
G01X1371148Y257564D02*
X1372570D01*
G01X1371542Y256614D02*
X1372176D01*
G01X1372570Y257564D02*
X1374914Y255220D01*
G01X1372176Y256614D02*
X1373964Y254826D01*
G01X1374914Y255220D02*
Y253798D01*
G01X1373964Y254826D02*
Y254192D01*
G01X1374914Y253798D02*
X1371836Y250720D01*
G01X1373964Y254192D02*
X1370886Y251114D01*
G01X1371836Y250720D02*
Y250084D01*
G01X1370886Y251114D02*
Y249690D01*
G01X1371836Y250084D02*
X1373619Y248301D01*
G01X1370886Y249690D02*
X1373225Y247351D01*
G01X1373619Y248301D02*
X1374255D01*
G01X1373225Y247351D02*
X1374649D01*
G01X1373619Y248301D02*
X1374255D01*
G01D02*
X1377642Y251688D01*
G01X1374649Y247351D02*
X1378036Y250738D01*
G01X1374255Y248301D02*
X1377642Y251688D01*
G01D02*
X1379064D01*
G01D02*
X1382233Y248519D01*
G01X1378036Y250738D02*
X1378670D01*
G01X1379064Y251688D02*
X1382233Y248519D01*
G01X1378670Y250738D02*
X1381283Y248125D01*
G01X1382233Y248519D02*
Y242827D01*
G01X1381283Y248125D02*
Y247235D01*
G01X1382233Y248519D02*
Y242827D01*
G01X1381283Y244985D02*
Y243277D01*
G01X1379752Y264321D02*
Y258892D01*
G01X1378802Y264320D02*
Y258498D01*
G01X1379752Y258892D02*
X1382472Y256172D01*
G01D02*
X1392423Y246221D01*
G01X1378802Y258498D02*
X1387012Y250288D01*
G01X1382472Y256172D02*
X1392423Y246221D01*
G01X1387012Y250288D02*
X1391473Y245827D01*
G01X1392423Y246221D02*
Y243637D01*
G01X1391473Y245827D02*
Y243255D01*
G01X1379752Y264321D02*
Y258892D01*
G01X1378802Y264320D02*
Y258498D01*
G01X1379752Y258892D02*
X1382472Y256172D01*
G01D02*
X1392423Y246221D01*
G01X1378802Y258498D02*
X1387012Y250288D01*
G01X1382472Y256172D02*
X1392423Y246221D01*
G01X1387012Y250288D02*
X1391473Y245827D01*
G01X1392423Y246221D02*
Y243637D01*
G01X1391473Y245827D02*
Y243255D01*
G01X1346806Y319765D02*
X1347754D01*
G01X1347755Y318815D02*
X1347200D01*
G01X1345800Y318759D02*
X1346806Y319765D01*
G01X1347200Y318815D02*
X1346750Y318365D01*
G01X1345800Y313809D02*
Y315159D01*
G01Y317409D02*
Y318759D01*
G01X1346750Y318365D02*
Y312140D01*
G01X1358810Y317341D02*
X1357897D01*
G01X1358928Y316391D02*
X1358291D01*
G01X1357897Y317341D02*
X1356490Y315934D01*
G01X1358291Y316391D02*
X1357440Y315540D01*
G01X1356490Y315934D02*
Y315044D01*
G01Y312794D02*
Y311926D01*
G01X1357440Y315540D02*
Y312320D01*
G01X1356490Y311926D02*
X1356974Y311442D01*
G01X1357440Y312320D02*
X1357930Y311830D01*
G01X1367457Y317370D02*
X1370620D01*
G01X1370065Y316420D02*
X1367851D01*
G01X1366060Y315973D02*
X1367457Y317370D01*
G01X1367851Y316420D02*
X1367010Y315579D01*
G01X1366060Y312300D02*
Y312803D01*
G01Y315053D02*
Y315973D01*
G01X1367010Y315579D02*
Y312694D01*
G01X1366840Y311520D02*
X1366060Y312300D01*
G01X1367010Y312694D02*
X1367536Y312168D01*
G01X1379412Y318255D02*
X1378821D01*
G01X1379546Y317305D02*
X1379215D01*
G01X1378821Y318255D02*
X1377800Y317234D01*
G01X1379215Y317305D02*
X1378750Y316840D01*
G01X1377800Y317234D02*
Y316349D01*
G01Y314099D02*
Y312856D01*
G01X1378750Y316840D02*
Y313250D01*
G01X1377800Y312856D02*
X1378814Y311842D01*
G01X1378750Y313250D02*
X1379200Y312800D01*
G01X1391682Y318100D02*
X1387816D01*
G01X1390734Y317150D02*
X1388210D01*
G01X1387816Y318100D02*
X1386810Y317094D01*
G01X1388210Y317150D02*
X1387760Y316700D01*
G01X1386810Y317094D02*
Y316057D01*
G01Y313807D02*
Y313286D01*
G01X1387760Y316700D02*
Y313680D01*
G01X1386810Y313286D02*
X1388036Y312060D01*
G01X1387760Y313680D02*
X1388430Y313010D01*
G01X1388036Y312060D02*
X1389991D01*
G01X1388430Y313010D02*
X1390385D01*
G01X1388036Y312060D02*
X1389991D01*
G01D02*
X1390310Y311741D01*
G01X1390385Y313010D02*
X1390945Y312450D01*
G01X1389991Y312060D02*
X1390310Y311741D01*
G01X1390945Y312450D02*
X1393097D01*
G01X1402023Y317822D02*
X1403078D01*
G01X1401943Y318772D02*
X1403472D01*
G01X1402023Y317822D02*
X1403078D01*
G01D02*
X1403928Y316972D01*
G01X1403472Y318772D02*
X1404878Y317366D01*
G01X1346750Y318365D02*
Y312140D01*
G01X1345800Y313809D02*
Y315159D01*
G01X1346750Y318365D02*
Y312140D01*
G01X1345800Y317409D02*
Y318759D01*
G01X1347200Y318815D02*
X1346750Y318365D01*
G01X1345800Y318759D02*
X1346806Y319765D01*
G01X1347755Y318815D02*
X1347200D01*
G01X1346806Y319765D02*
X1347754D01*
G01X1358928Y316391D02*
X1358291D01*
G01X1358810Y317341D02*
X1357897D01*
G01X1358291Y316391D02*
X1357440Y315540D01*
G01X1357897Y317341D02*
X1356490Y315934D01*
G01X1357440Y315540D02*
Y312320D01*
G01X1356490Y315934D02*
Y315044D01*
G01X1357440Y315540D02*
Y312320D01*
G01X1356490Y312794D02*
Y311926D01*
G01X1357440Y312320D02*
X1357930Y311830D01*
G01X1356490Y311926D02*
X1356974Y311442D01*
G01X1367010Y312694D02*
X1367536Y312168D01*
G01X1366840Y311520D02*
X1366060Y312300D01*
G01X1367010Y315579D02*
Y312694D01*
G01X1366060Y312300D02*
Y312803D01*
G01X1367010Y315579D02*
Y312694D01*
G01X1366060Y315053D02*
Y315973D01*
G01X1367851Y316420D02*
X1367010Y315579D01*
G01X1366060Y315973D02*
X1367457Y317370D01*
G01X1370065Y316420D02*
X1367851D01*
G01X1367457Y317370D02*
X1370620D01*
G01X1379546Y317305D02*
X1379215D01*
G01X1379412Y318255D02*
X1378821D01*
G01X1379215Y317305D02*
X1378750Y316840D01*
G01X1378821Y318255D02*
X1377800Y317234D01*
G01X1378750Y316840D02*
Y313250D01*
G01X1377800Y317234D02*
Y316349D01*
G01X1378750Y316840D02*
Y313250D01*
G01X1377800Y314099D02*
Y312856D01*
G01X1378750Y313250D02*
X1379200Y312800D01*
G01X1377800Y312856D02*
X1378814Y311842D01*
G01X1390734Y317150D02*
X1388210D01*
G01X1391682Y318100D02*
X1387816D01*
G01X1388210Y317150D02*
X1387760Y316700D01*
G01X1387816Y318100D02*
X1386810Y317094D01*
G01X1387760Y316700D02*
Y313680D01*
G01X1386810Y317094D02*
Y316057D01*
G01X1387760Y316700D02*
Y313680D01*
G01X1386810Y313807D02*
Y313286D01*
G01X1387760Y313680D02*
X1388430Y313010D01*
G01X1386810Y313286D02*
X1388036Y312060D01*
G01X1388430Y313010D02*
X1390385D01*
G01D02*
X1390945Y312450D01*
G01X1388036Y312060D02*
X1389991D01*
G01X1390385Y313010D02*
X1390945Y312450D01*
G01D02*
X1393097D01*
G01X1389991Y312060D02*
X1390310Y311741D01*
G01X1401943Y318772D02*
X1403472D01*
G01D02*
X1404878Y317366D01*
G01X1402023Y317822D02*
X1403078D01*
G01X1403472Y318772D02*
X1404878Y317366D01*
G01X1403078Y317822D02*
X1403928Y316972D01*
G01X1383089Y484623D02*
X1391593D01*
G01X1382563Y485573D02*
X1391441D01*
G01X1362516Y484748D02*
X1371890D01*
G01X1371876Y483798D02*
X1362988D01*
G01X1374090Y495648D02*
X1364788D01*
G01X1364716Y494698D02*
X1374090D01*
G01X1394390Y496848D02*
X1385094D01*
G01X1385488Y495898D02*
X1394198D01*
G01X1382563Y485573D02*
X1391441D01*
G01X1383089Y484623D02*
X1391593D01*
G01X1371876Y483798D02*
X1362988D01*
G01X1362516Y484748D02*
X1371890D01*
G01X1364716Y494698D02*
X1374090D01*
G01Y495648D02*
X1364788D01*
G01X1385488Y495898D02*
X1394198D01*
G01X1394390Y496848D02*
X1385094D01*
G01X1397391Y484473D02*
X1398725D01*
G01X1397741Y485423D02*
X1399010D01*
G01X1397391Y484473D02*
X1398725D01*
G01D02*
X1401907Y482381D01*
G01X1399010Y485423D02*
X1402430Y483176D01*
G01X1401907Y482381D02*
X1404547Y480647D01*
G01X1402430Y483176D02*
X1405334Y481268D01*
G01X1397391Y484473D02*
X1398725D01*
G01X1397741Y485423D02*
X1399010D01*
G01X1397391Y484473D02*
X1398725D01*
G01D02*
X1401907Y482381D01*
G01X1399010Y485423D02*
X1402430Y483176D01*
G01X1401907Y482381D02*
X1404547Y480647D01*
G01X1402430Y483176D02*
X1405334Y481268D01*
G01X1397741Y485423D02*
X1399010D01*
G01D02*
X1402430Y483176D01*
G01X1397391Y484473D02*
X1398725D01*
G01X1399010Y485423D02*
X1402430Y483176D01*
G01X1398725Y484473D02*
X1401907Y482381D01*
G01X1402430Y483176D02*
X1405334Y481268D01*
G01X1401907Y482381D02*
X1404547Y480647D01*
G01X1432334Y463180D02*
X1380030Y478399D01*
G01X1432198Y462230D02*
X1379395Y477594D01*
G01X1380030Y478399D02*
X1378908Y480369D01*
G01X1379395Y477594D02*
X1377958Y480117D01*
G01X1378908Y480369D02*
Y483536D01*
G01X1377958Y480117D02*
Y483142D01*
G01X1378908Y483536D02*
X1377683Y484761D01*
G01X1377958Y483142D02*
X1377289Y483811D01*
G01X1377683Y484761D02*
X1376317D01*
G01X1377289Y483811D02*
X1376417D01*
G01X1432198Y462230D02*
X1379395Y477594D01*
G01X1432334Y463180D02*
X1380030Y478399D01*
G01X1379395Y477594D02*
X1377958Y480117D01*
G01X1380030Y478399D02*
X1378908Y480369D01*
G01X1377958Y480117D02*
Y483142D01*
G01X1378908Y480369D02*
Y483536D01*
G01X1377958Y483142D02*
X1377289Y483811D01*
G01X1378908Y483536D02*
X1377683Y484761D01*
G01X1377289Y483811D02*
X1376417D01*
G01X1377683Y484761D02*
X1376317D01*
G01X1378491Y495735D02*
X1379783D01*
G01X1378492Y494785D02*
X1379389D01*
G01X1379783Y495735D02*
X1381250Y494268D01*
G01X1379389Y494785D02*
X1380300Y493874D01*
G01X1381250Y494268D02*
Y492214D01*
G01X1380300Y493874D02*
Y491820D01*
G01X1381250Y492214D02*
X1382280Y491184D01*
G01X1380300Y491820D02*
X1381886Y490234D01*
G01X1382280Y491184D02*
X1404682D01*
G01X1381886Y490234D02*
X1405076D01*
G01X1378492Y494785D02*
X1379389D01*
G01X1378491Y495735D02*
X1379783D01*
G01X1379389Y494785D02*
X1380300Y493874D01*
G01X1379783Y495735D02*
X1381250Y494268D01*
G01X1380300Y493874D02*
Y491820D01*
G01X1381250Y494268D02*
Y492214D01*
G01X1380300Y491820D02*
X1381886Y490234D01*
G01X1381250Y492214D02*
X1382280Y491184D01*
G01X1381886Y490234D02*
X1405076D01*
G01X1382280Y491184D02*
X1404682D01*
G01X1400016Y496848D02*
X1404754D01*
G01X1400016Y495898D02*
X1405148D01*
G01X1400016D02*
X1405148D01*
G01X1400016Y496848D02*
X1404754D01*
G01X1432334Y463180D02*
X1380030Y478399D01*
G01X1432198Y462230D02*
X1379395Y477594D01*
G01X1380030Y478399D02*
X1378908Y480369D01*
G01X1379395Y477594D02*
X1377958Y480117D01*
G01X1378908Y480369D02*
Y483536D01*
G01X1377958Y480117D02*
Y483142D01*
G01X1378908Y483536D02*
X1377683Y484761D01*
G01X1377958Y483142D02*
X1377289Y483811D01*
G01X1377683Y484761D02*
X1376317D01*
G01X1377289Y483811D02*
X1376417D01*
G01X1432198Y462230D02*
X1379395Y477594D01*
G01X1432334Y463180D02*
X1380030Y478399D01*
G01X1379395Y477594D02*
X1377958Y480117D01*
G01X1380030Y478399D02*
X1378908Y480369D01*
G01X1377958Y480117D02*
Y483142D01*
G01X1378908Y480369D02*
Y483536D01*
G01X1377958Y483142D02*
X1377289Y483811D01*
G01X1378908Y483536D02*
X1377683Y484761D01*
G01X1377289Y483811D02*
X1376417D01*
G01X1377683Y484761D02*
X1376317D01*
G01X1397741Y485423D02*
X1399010D01*
G01D02*
X1402430Y483176D01*
G01X1397391Y484473D02*
X1398725D01*
G01X1399010Y485423D02*
X1402430Y483176D01*
G01X1398725Y484473D02*
X1401907Y482381D01*
G01X1402430Y483176D02*
X1405334Y481268D01*
G01X1401907Y482381D02*
X1404547Y480647D01*
G01X1378491Y495735D02*
X1379783D01*
G01X1378492Y494785D02*
X1379389D01*
G01X1379783Y495735D02*
X1381250Y494268D01*
G01X1379389Y494785D02*
X1380300Y493874D01*
G01X1381250Y494268D02*
Y492214D01*
G01X1380300Y493874D02*
Y491820D01*
G01X1381250Y492214D02*
X1382280Y491184D01*
G01X1380300Y491820D02*
X1381886Y490234D01*
G01X1382280Y491184D02*
X1404682D01*
G01X1381886Y490234D02*
X1405076D01*
G01X1378492Y494785D02*
X1379389D01*
G01X1378491Y495735D02*
X1379783D01*
G01X1379389Y494785D02*
X1380300Y493874D01*
G01X1379783Y495735D02*
X1381250Y494268D01*
G01X1380300Y493874D02*
Y491820D01*
G01X1381250Y494268D02*
Y492214D01*
G01X1380300Y491820D02*
X1381886Y490234D01*
G01X1381250Y492214D02*
X1382280Y491184D01*
G01X1381886Y490234D02*
X1405076D01*
G01X1382280Y491184D02*
X1404682D01*
G01X1400016Y496848D02*
X1404754D01*
G01X1400016Y495898D02*
X1405148D01*
G01X1400016D02*
X1405148D01*
G01X1400016Y496848D02*
X1404754D01*
G01X1430700Y38500D02*
Y32700D01*
G01D02*
X1425150Y27150D01*
G01X1429750Y33094D02*
X1424756Y28100D01*
G01X1425150Y27150D02*
X1413750D01*
G01X1424756Y28100D02*
X1414144D01*
G01X1413750Y27150D02*
X1408571Y32329D01*
G01X1414144Y28100D02*
X1409521Y32723D01*
G01X1408571Y32329D02*
Y42666D01*
G01X1409521Y32723D02*
Y42666D01*
G01X1430700Y38500D02*
Y32700D01*
G01X1429750Y33094D02*
X1424756Y28100D01*
G01X1430700Y32700D02*
X1425150Y27150D01*
G01X1424756Y28100D02*
X1414144D01*
G01X1425150Y27150D02*
X1413750D01*
G01X1414144Y28100D02*
X1409521Y32723D01*
G01X1413750Y27150D02*
X1408571Y32329D01*
G01X1409521Y32723D02*
Y42666D01*
G01X1408571Y32329D02*
Y42666D01*
G01X1430700Y38500D02*
Y32700D01*
G01D02*
X1425150Y27150D01*
G01X1429750Y33094D02*
X1424756Y28100D01*
G01X1425150Y27150D02*
X1413750D01*
G01X1424756Y28100D02*
X1414144D01*
G01X1413750Y27150D02*
X1408571Y32329D01*
G01X1414144Y28100D02*
X1409521Y32723D01*
G01X1408571Y32329D02*
Y42666D01*
G01X1409521Y32723D02*
Y42666D01*
G01X1430700Y38500D02*
Y32700D01*
G01X1429750Y33094D02*
X1424756Y28100D01*
G01X1430700Y32700D02*
X1425150Y27150D01*
G01X1424756Y28100D02*
X1414144D01*
G01X1425150Y27150D02*
X1413750D01*
G01X1414144Y28100D02*
X1409521Y32723D01*
G01X1413750Y27150D02*
X1408571Y32329D01*
G01X1409521Y32723D02*
Y42666D01*
G01X1408571Y32329D02*
Y42666D01*
G01X1469689Y49000D02*
X1441200D01*
G01X1475906Y49950D02*
X1449933D01*
G01X1469689Y49000D02*
X1441200D01*
G01X1449933Y49950D02*
X1440806D01*
G01X1441200Y49000D02*
X1430700Y38500D01*
G01X1440806Y49950D02*
X1429750Y38894D01*
G01D02*
Y33094D01*
G01X1475906Y49950D02*
X1449933D01*
G01X1475906D02*
X1449933D01*
G01D02*
X1440806D01*
G01X1469689Y49000D02*
X1441200D01*
G01X1440806Y49950D02*
X1429750Y38894D01*
G01X1441200Y49000D02*
X1430700Y38500D01*
G01X1429750Y38894D02*
Y33094D01*
G01X1469689Y49000D02*
X1441200D01*
G01X1475906Y49950D02*
X1449933D01*
G01X1469689Y49000D02*
X1441200D01*
G01X1449933Y49950D02*
X1440806D01*
G01X1441200Y49000D02*
X1430700Y38500D01*
G01X1440806Y49950D02*
X1429750Y38894D01*
G01D02*
Y33094D01*
G01X1475906Y49950D02*
X1449933D01*
G01X1475906D02*
X1449933D01*
G01D02*
X1440806D01*
G01X1469689Y49000D02*
X1441200D01*
G01X1440806Y49950D02*
X1429750Y38894D01*
G01X1441200Y49000D02*
X1430700Y38500D01*
G01X1429750Y38894D02*
Y33094D01*
G01X1403928Y316972D02*
Y313480D01*
G01X1404878Y317366D02*
Y312413D01*
G01Y317366D02*
Y312413D01*
G01X1403928Y316972D02*
Y313480D01*
G01X1413060Y314140D02*
X1409859D01*
G01X1411970Y313190D02*
X1409465D01*
G01X1409859Y314140D02*
X1408709Y315290D01*
G01X1409465Y313190D02*
X1407759Y314896D01*
G01X1408709Y315290D02*
Y316854D01*
G01X1407759Y314896D02*
Y317248D01*
G01X1408709Y316854D02*
X1409819Y317964D01*
G01X1407759Y317248D02*
X1409425Y318914D01*
G01X1409819Y317964D02*
X1411656D01*
G01X1409425Y318914D02*
X1412268D01*
G01X1411970Y313190D02*
X1409465D01*
G01X1413060Y314140D02*
X1409859D01*
G01X1409465Y313190D02*
X1407759Y314896D01*
G01X1409859Y314140D02*
X1408709Y315290D01*
G01X1407759Y314896D02*
Y317248D01*
G01X1408709Y315290D02*
Y316854D01*
G01X1407759Y317248D02*
X1409425Y318914D01*
G01X1408709Y316854D02*
X1409819Y317964D01*
G01X1409425Y318914D02*
X1412268D01*
G01X1409819Y317964D02*
X1411656D01*
G01X1420456Y391561D02*
X1422204D01*
G01X1420709Y390611D02*
X1422535D01*
G01X1420456Y391561D02*
X1422204D01*
G01D02*
X1422811Y392042D01*
G01X1422535Y390611D02*
X1423566Y391427D01*
G01X1422811Y392042D02*
X1423561Y393534D01*
G01X1423566Y391427D02*
X1423660Y391614D01*
G01X1422811Y392042D02*
X1423561Y393534D01*
G01X1423660Y391615D02*
X1424557Y393400D01*
G01X1423561Y393534D02*
X1422535Y398666D01*
G01X1424557Y393400D02*
X1423504Y398666D01*
G01X1422535D02*
X1421223Y405224D01*
G01X1423504Y398666D02*
X1422191Y405229D01*
G01X1416725Y403967D02*
X1417710Y399040D01*
G01X1417694Y403967D02*
X1417983Y402523D01*
G01X1416725Y403967D02*
X1417710Y399040D01*
G01X1417983Y402523D02*
X1418688Y398999D01*
G01X1417710Y399040D02*
X1417602Y398666D01*
G01X1418688Y398999D02*
X1418592Y398666D01*
G01X1417710Y399040D02*
X1417602Y398666D01*
G01D02*
X1417057Y396771D01*
G01X1418592Y398666D02*
X1417983Y396553D01*
G01X1417602Y398666D02*
X1417057Y396771D01*
G01X1417983Y396553D02*
X1417920Y396334D01*
G01X1417057Y396771D02*
X1415133Y394279D01*
G01X1417920Y396334D02*
X1415600Y393329D01*
G01X1415133Y394279D02*
X1414471D01*
G01X1415600Y393329D02*
X1414513D01*
G01X1427717Y398666D02*
X1426415Y405176D01*
G01X1425446D02*
X1426748Y398666D01*
G01X1429297Y390768D02*
X1427717Y398666D01*
G01X1426748D02*
X1428302Y390898D01*
G01X1425049Y382133D02*
X1425169Y382376D01*
G01Y382377D02*
X1429297Y390768D01*
G01X1428302Y390898D02*
X1424316Y382796D01*
G01X1422266Y380400D02*
X1425049Y382133D01*
G01X1424316Y382796D02*
X1421994Y381350D01*
G01X1420525Y380400D02*
X1422266D01*
G01D02*
X1425049Y382133D01*
G01X1421994Y381350D02*
X1420525D01*
G01X1421209Y371565D02*
X1422830D01*
G01X1421180Y370615D02*
X1423339D01*
G01X1422830Y371565D02*
X1431085Y383947D01*
G01X1423339Y370615D02*
X1431980Y383576D01*
G01X1431085Y383947D02*
X1432542Y391232D01*
G01X1431980Y383576D02*
X1433511Y391232D01*
G01X1432542D02*
X1431055Y398666D01*
G01X1433511Y391232D02*
X1432024Y398666D01*
G01X1431055D02*
X1429552Y406178D01*
G01X1432024Y398666D02*
X1430521Y406178D01*
G01X1420709Y390611D02*
X1422535D01*
G01D02*
X1423566Y391427D01*
G01X1420456Y391561D02*
X1422204D01*
G01X1422535Y390611D02*
X1423566Y391427D01*
G01X1422204Y391561D02*
X1422811Y392042D01*
G01X1423566Y391427D02*
X1423660Y391614D01*
G01Y391615D02*
X1424557Y393400D01*
G01X1422811Y392042D02*
X1423561Y393534D01*
G01X1424557Y393400D02*
X1423504Y398666D01*
G01X1423561Y393534D02*
X1422535Y398666D01*
G01X1423504D02*
X1422191Y405229D01*
G01X1422535Y398666D02*
X1421223Y405224D01*
G01X1417694Y403967D02*
X1417983Y402523D01*
G01D02*
X1418688Y398999D01*
G01X1416725Y403967D02*
X1417710Y399040D01*
G01X1418688Y398999D02*
X1418592Y398666D01*
G01D02*
X1417983Y396553D01*
G01X1417710Y399040D02*
X1417602Y398666D01*
G01X1418592D02*
X1417983Y396553D01*
G01D02*
X1417920Y396334D01*
G01X1417602Y398666D02*
X1417057Y396771D01*
G01X1417920Y396334D02*
X1415600Y393329D01*
G01X1417057Y396771D02*
X1415133Y394279D01*
G01X1415600Y393329D02*
X1414513D01*
G01X1415133Y394279D02*
X1414471D01*
G01X1421994Y381350D02*
X1420525D01*
G01Y380400D02*
X1422266D01*
G01X1424316Y382796D02*
X1421994Y381350D01*
G01D02*
X1420525D01*
G01X1422266Y380400D02*
X1425049Y382133D01*
G01X1428302Y390898D02*
X1424316Y382796D01*
G01X1425049Y382133D02*
X1425169Y382376D01*
G01X1428302Y390898D02*
X1424316Y382796D01*
G01X1425169Y382377D02*
X1429297Y390768D01*
G01X1426748Y398666D02*
X1428302Y390898D01*
G01X1429297Y390768D02*
X1427717Y398666D01*
G01X1425446Y405176D02*
X1426748Y398666D01*
G01X1427717D02*
X1426415Y405176D01*
G01X1421180Y370615D02*
X1423339D01*
G01X1421209Y371565D02*
X1422830D01*
G01X1423339Y370615D02*
X1431980Y383576D01*
G01X1422830Y371565D02*
X1431085Y383947D01*
G01X1431980Y383576D02*
X1433511Y391232D01*
G01X1431085Y383947D02*
X1432542Y391232D01*
G01X1433511D02*
X1432024Y398666D01*
G01X1432542Y391232D02*
X1431055Y398666D01*
G01X1432024D02*
X1430521Y406178D01*
G01X1431055Y398666D02*
X1429552Y406178D01*
G01X1421209Y371565D02*
X1422830D01*
G01X1421180Y370615D02*
X1423339D01*
G01X1422830Y371565D02*
X1431085Y383947D01*
G01X1423339Y370615D02*
X1431980Y383576D01*
G01X1431085Y383947D02*
X1432542Y391232D01*
G01X1431980Y383576D02*
X1433511Y391232D01*
G01X1432542D02*
X1431055Y398666D01*
G01X1433511Y391232D02*
X1432024Y398666D01*
G01X1431055D02*
X1429552Y406178D01*
G01X1432024Y398666D02*
X1430521Y406178D01*
G01X1448000Y463180D02*
X1457666D01*
G01X1448000D02*
X1432334D01*
G01X1435500Y462230D02*
X1457666D01*
G01X1448000Y463180D02*
X1432334D01*
G01X1435500Y462230D02*
X1432198D01*
G01X1435500D02*
X1457666D01*
G01X1448000Y463180D02*
X1457666D01*
G01X1435500Y462230D02*
X1457666D01*
G01X1435500D02*
X1432198D01*
G01X1448000Y463180D02*
X1432334D01*
G01X1421223Y405224D02*
X1423241Y415898D01*
G01X1422191Y405229D02*
X1424207Y415888D01*
G01X1423241Y415898D02*
X1422725Y418958D01*
G01X1424207Y415888D02*
X1423689Y418958D01*
G01X1422725D02*
X1420423Y432611D01*
G01X1423689Y418958D02*
X1421398Y432544D01*
G01X1420423Y432611D02*
X1423120Y441177D01*
G01X1421398Y432544D02*
X1423957Y440669D01*
G01X1423120Y441177D02*
X1427724Y445780D01*
G01X1423957Y440669D02*
X1428118Y444830D01*
G01X1427724Y445780D02*
X1450589D01*
G01X1428118Y444830D02*
X1450453D01*
G01X1435050Y451225D02*
X1427689D01*
G01X1435050Y450275D02*
X1428012D01*
G01X1427689Y451225D02*
X1420461Y445683D01*
G01X1428012Y450275D02*
X1421267Y445103D01*
G01X1420461Y445683D02*
X1415863Y432333D01*
G01X1421267Y445103D02*
X1416846Y432267D01*
G01X1415863Y432333D02*
X1417983Y421735D01*
G01D02*
X1418538Y418960D01*
G01X1416846Y432267D02*
X1419507Y418960D01*
G01X1418538D02*
X1419131Y415997D01*
G01X1419507Y418960D02*
X1420100Y415997D01*
G01X1419131D02*
X1416725Y403967D01*
G01X1420100Y415997D02*
X1417694Y403967D01*
G01X1428382Y439375D02*
X1434950D01*
G01X1435050Y440325D02*
X1427988D01*
G01X1427544Y438537D02*
X1428382Y439375D01*
G01X1427988Y440325D02*
X1426755Y439093D01*
G01X1427027Y437446D02*
X1427544Y438537D01*
G01X1426755Y439093D02*
X1426098Y437705D01*
G01X1425624Y430490D02*
X1427014Y437438D01*
G01X1426098Y437705D02*
X1424655Y430490D01*
G01X1428551Y415855D02*
X1425624Y430490D01*
G01X1424655D02*
X1427582Y415855D01*
G01X1426415Y405176D02*
X1428551Y415855D01*
G01X1427582D02*
X1425446Y405176D01*
G01X1431738Y417107D02*
X1430321Y424183D01*
G01D02*
X1430158Y425002D01*
G01X1431595Y422663D02*
X1431253Y424370D01*
G01X1430321Y424183D02*
X1430158Y425002D01*
G01X1431253Y424370D02*
X1431127Y425002D01*
G01X1430158D02*
X1431034Y429384D01*
G01X1431127Y425002D02*
X1431929Y429013D01*
G01X1431034Y429384D02*
X1433473Y433041D01*
G01X1431929Y429013D02*
X1434038Y432175D01*
G01X1433473Y433041D02*
X1443127Y434725D01*
G01X1434038Y432175D02*
X1443210Y433775D01*
G01X1443127Y434725D02*
X1450550D01*
G01X1443210Y433775D02*
X1450550D01*
G01X1429552Y406178D02*
X1431738Y417107D01*
G01X1430521Y406178D02*
X1432707Y417107D01*
G01X1431738D02*
X1430321Y424183D01*
G01X1432707Y417107D02*
X1431595Y422663D01*
G01X1422191Y405229D02*
X1424207Y415888D01*
G01X1421223Y405224D02*
X1423241Y415898D01*
G01X1424207Y415888D02*
X1423689Y418958D01*
G01X1423241Y415898D02*
X1422725Y418958D01*
G01X1423689D02*
X1421398Y432544D01*
G01X1422725Y418958D02*
X1420423Y432611D01*
G01X1421398Y432544D02*
X1423957Y440669D01*
G01X1420423Y432611D02*
X1423120Y441177D01*
G01X1423957Y440669D02*
X1428118Y444830D01*
G01X1423120Y441177D02*
X1427724Y445780D01*
G01X1428118Y444830D02*
X1450453D01*
G01X1427724Y445780D02*
X1450589D01*
G01X1435050Y450275D02*
X1428012D01*
G01X1435050Y451225D02*
X1427689D01*
G01X1428012Y450275D02*
X1421267Y445103D01*
G01X1427689Y451225D02*
X1420461Y445683D01*
G01X1421267Y445103D02*
X1416846Y432267D01*
G01X1420461Y445683D02*
X1415863Y432333D01*
G01X1416846Y432267D02*
X1419507Y418960D01*
G01X1415863Y432333D02*
X1417983Y421735D01*
G01X1416846Y432267D02*
X1419507Y418960D01*
G01X1417983Y421735D02*
X1418538Y418960D01*
G01X1419507D02*
X1420100Y415997D01*
G01X1418538Y418960D02*
X1419131Y415997D01*
G01X1420100D02*
X1417694Y403967D01*
G01X1419131Y415997D02*
X1416725Y403967D01*
G01X1427582Y415855D02*
X1425446Y405176D01*
G01X1426415D02*
X1428551Y415855D01*
G01X1424655Y430490D02*
X1427582Y415855D01*
G01X1428551D02*
X1425624Y430490D01*
G01X1426098Y437705D02*
X1424655Y430490D01*
G01X1425624D02*
X1427014Y437438D01*
G01X1426755Y439093D02*
X1426098Y437705D01*
G01X1427027Y437446D02*
X1427544Y438537D01*
G01X1427988Y440325D02*
X1426755Y439093D01*
G01X1427544Y438537D02*
X1428382Y439375D01*
G01X1435050Y440325D02*
X1427988D01*
G01X1428382Y439375D02*
X1434950D01*
G01X1430521Y406178D02*
X1432707Y417107D01*
G01X1429552Y406178D02*
X1431738Y417107D01*
G01X1431595Y422663D02*
X1431253Y424370D01*
G01X1432707Y417107D02*
X1431595Y422663D01*
G01X1431738Y417107D02*
X1430321Y424183D01*
G01X1431595Y422663D02*
X1431253Y424370D01*
G01D02*
X1431127Y425002D01*
G01X1430321Y424183D02*
X1430158Y425002D01*
G01X1431127D02*
X1431929Y429013D01*
G01X1430158Y425002D02*
X1431034Y429384D01*
G01X1431929Y429013D02*
X1434038Y432175D01*
G01X1431034Y429384D02*
X1433473Y433041D01*
G01X1434038Y432175D02*
X1443210Y433775D01*
G01X1433473Y433041D02*
X1443127Y434725D01*
G01X1443210Y433775D02*
X1450550D01*
G01X1443127Y434725D02*
X1450550D01*
G01X1431738Y417107D02*
X1430321Y424183D01*
G01D02*
X1430158Y425002D01*
G01X1431595Y422663D02*
X1431253Y424370D01*
G01X1430321Y424183D02*
X1430158Y425002D01*
G01X1431253Y424370D02*
X1431127Y425002D01*
G01X1430158D02*
X1431034Y429384D01*
G01X1431127Y425002D02*
X1431929Y429013D01*
G01X1431034Y429384D02*
X1433473Y433041D01*
G01X1431929Y429013D02*
X1434038Y432175D01*
G01X1433473Y433041D02*
X1443127Y434725D01*
G01X1434038Y432175D02*
X1443210Y433775D01*
G01X1443127Y434725D02*
X1450550D01*
G01X1443210Y433775D02*
X1450550D01*
G01X1429552Y406178D02*
X1431738Y417107D01*
G01X1430521Y406178D02*
X1432707Y417107D01*
G01X1431738D02*
X1430321Y424183D01*
G01X1432707Y417107D02*
X1431595Y422663D01*
G01X1472100Y447500D02*
X1460637D01*
G01X1472100D02*
X1460637D01*
G01X1470768Y446550D02*
X1460826D01*
G01X1458271Y446520D02*
X1456412Y445750D01*
G01X1460637Y447500D02*
X1458271Y446520D01*
G01X1460826Y446550D02*
X1456601Y444800D01*
G01X1456412Y445750D02*
X1454950D01*
G01X1456601Y444800D02*
X1454999D01*
G01X1443788Y451200D02*
X1446980Y452522D01*
G01D02*
X1448300D01*
G01Y451572D02*
X1447169D01*
G01X1443788Y451200D02*
X1446980Y452522D01*
G01X1447169Y451572D02*
X1443977Y450250D01*
G01X1439400Y451200D02*
X1443788D01*
G01X1443977Y450250D02*
X1442169D01*
G01X1439400Y451200D02*
X1443788D01*
G01X1442169Y450250D02*
X1439500D01*
G01X1443788Y451200D02*
X1446980Y452522D01*
G01D02*
X1448300D01*
G01Y451572D02*
X1447169D01*
G01X1443788Y451200D02*
X1446980Y452522D01*
G01X1447169Y451572D02*
X1443977Y450250D01*
G01X1439400Y451200D02*
X1443788D01*
G01X1443977Y450250D02*
X1442169D01*
G01X1439400Y451200D02*
X1443788D01*
G01X1442169Y450250D02*
X1439500D01*
G01X1439592Y439300D02*
X1458100D01*
G01X1439500Y440250D02*
X1442646D01*
G01X1463800Y442334D02*
X1464704D01*
G01Y443284D02*
X1463406D01*
G01X1460766Y439300D02*
X1463800Y442334D01*
G01X1463406Y443284D02*
X1460372Y440250D01*
G01X1439592Y439300D02*
X1458100D01*
G01D02*
X1460766D01*
G01X1460372Y440250D02*
X1442646D01*
G01X1439592Y439300D02*
X1458100D01*
G01X1439500Y440250D02*
X1442646D01*
G01X1463800Y442334D02*
X1464704D01*
G01Y443284D02*
X1463406D01*
G01X1460766Y439300D02*
X1463800Y442334D01*
G01X1463406Y443284D02*
X1460372Y440250D01*
G01X1439592Y439300D02*
X1458100D01*
G01D02*
X1460766D01*
G01X1460372Y440250D02*
X1442646D01*
G01X1456019Y434881D02*
X1454819D01*
G01X1455043Y433931D02*
X1456208D01*
G01X1458656Y435973D02*
X1456019Y434881D01*
G01D02*
X1454819D01*
G01X1456208Y433931D02*
X1458845Y435023D01*
G01X1464697Y435973D02*
X1463347D01*
G01X1461081D02*
X1458656D01*
G01X1458845Y435023D02*
X1475523D01*
G01X1460826Y446550D02*
X1456601Y444800D01*
G01X1458271Y446520D02*
X1456412Y445750D01*
G01X1456601Y444800D02*
X1454999D01*
G01X1456412Y445750D02*
X1454950D01*
G01X1470768Y446550D02*
X1460826D01*
G01X1472100Y447500D02*
X1460637D01*
G01X1460826Y446550D02*
X1456601Y444800D01*
G01X1460637Y447500D02*
X1458271Y446520D01*
G01X1460826Y446550D02*
X1456601Y444800D01*
G01X1458271Y446520D02*
X1456412Y445750D01*
G01X1456601Y444800D02*
X1454999D01*
G01X1456412Y445750D02*
X1454950D01*
G01X1470768Y446550D02*
X1460826D01*
G01X1472100Y447500D02*
X1460637D01*
G01X1460826Y446550D02*
X1456601Y444800D01*
G01X1460637Y447500D02*
X1458271Y446520D01*
G01X1443977Y450250D02*
X1442169D01*
G01D02*
X1439500D01*
G01X1439400Y451200D02*
X1443788D01*
G01X1448300Y451572D02*
X1447169D01*
G01D02*
X1443977Y450250D01*
G01X1443788Y451200D02*
X1446980Y452522D01*
G01X1448300Y451572D02*
X1447169D01*
G01X1446980Y452522D02*
X1448300D01*
G01X1439500Y440250D02*
X1442646D01*
G01X1460372D02*
X1442646D01*
G01X1439592Y439300D02*
X1458100D01*
G01X1460372Y440250D02*
X1442646D01*
G01X1458100Y439300D02*
X1460766D01*
G01X1463406Y443284D02*
X1460372Y440250D01*
G01X1460766Y439300D02*
X1463800Y442334D01*
G01X1464704Y443284D02*
X1463406D01*
G01X1463800Y442334D02*
X1464704D01*
G01X1439500Y440250D02*
X1442646D01*
G01X1460372D02*
X1442646D01*
G01X1439592Y439300D02*
X1458100D01*
G01X1460372Y440250D02*
X1442646D01*
G01X1458100Y439300D02*
X1460766D01*
G01X1463406Y443284D02*
X1460372Y440250D01*
G01X1460766Y439300D02*
X1463800Y442334D01*
G01X1464704Y443284D02*
X1463406D01*
G01X1463800Y442334D02*
X1464704D01*
G01X1458845Y435023D02*
X1475523D01*
G01X1458845D02*
X1475523D01*
G01X1458845D02*
X1475523D01*
G01X1458845D02*
X1475523D01*
G01X1464697Y435973D02*
X1463347D01*
G01X1458845Y435023D02*
X1475523D01*
G01X1461081Y435973D02*
X1458656D01*
G01X1456208Y433931D02*
X1458845Y435023D01*
G01X1458656Y435973D02*
X1456019Y434881D01*
G01X1455043Y433931D02*
X1456208D01*
G01D02*
X1458845Y435023D01*
G01X1456019Y434881D02*
X1454819D01*
G01X1448000Y463180D02*
X1457666D01*
G01X1448000D02*
X1432334D01*
G01X1435500Y462230D02*
X1457666D01*
G01X1448000Y463180D02*
X1432334D01*
G01X1435500Y462230D02*
X1432198D01*
G01X1435500D02*
X1457666D01*
G01X1448000Y463180D02*
X1457666D01*
G01X1435500Y462230D02*
X1457666D01*
G01X1435500D02*
X1432198D01*
G01X1448000Y463180D02*
X1432334D01*
G01X1472100Y447500D02*
X1460637D01*
G01X1472100D02*
X1460637D01*
G01X1470768Y446550D02*
X1460826D01*
G01X1458271Y446520D02*
X1456412Y445750D01*
G01X1460637Y447500D02*
X1458271Y446520D01*
G01X1460826Y446550D02*
X1456601Y444800D01*
G01X1456412Y445750D02*
X1454950D01*
G01X1456601Y444800D02*
X1454999D01*
G01X1458845Y435023D02*
X1475523D01*
G01X1458845D02*
X1475523D01*
G01X1458845D02*
X1475523D01*
G01X1458845D02*
X1475523D01*
G01X1464697Y435973D02*
X1463347D01*
G01X1458845Y435023D02*
X1475523D01*
G01X1461081Y435973D02*
X1458656D01*
G01X1456208Y433931D02*
X1458845Y435023D01*
G01X1458656Y435973D02*
X1456019Y434881D01*
G01X1455043Y433931D02*
X1456208D01*
G01D02*
X1458845Y435023D01*
G01X1456019Y434881D02*
X1454819D01*
G01X1404547Y480647D02*
X1407007Y473820D01*
G01X1405334Y481268D02*
X1407736Y474602D01*
G01X1410808Y472742D02*
X1433671Y466256D01*
G01X1407007Y473820D02*
X1410808Y472742D01*
G01X1407736Y474602D02*
X1433716Y467231D01*
G01X1433671Y466256D02*
X1442352Y467861D01*
G01X1433716Y467231D02*
X1442371Y468831D01*
G01X1442352Y467861D02*
X1447411Y466718D01*
G01X1442371Y468831D02*
X1447432Y467688D01*
G01X1447411Y466718D02*
X1456074Y468277D01*
G01X1447432Y467688D02*
X1456079Y469244D01*
G01X1456074Y468277D02*
X1462970Y466961D01*
G01X1456079Y469244D02*
X1462947Y467933D01*
G01X1462970Y466961D02*
X1468706Y468339D01*
G01X1462947Y467933D02*
X1468593Y469289D01*
G01X1404547Y480647D02*
X1407007Y473820D01*
G01X1405334Y481268D02*
X1407736Y474602D01*
G01X1410808Y472742D02*
X1433671Y466256D01*
G01X1407007Y473820D02*
X1410808Y472742D01*
G01X1407736Y474602D02*
X1433716Y467231D01*
G01X1433671Y466256D02*
X1442352Y467861D01*
G01X1433716Y467231D02*
X1442371Y468831D01*
G01X1442352Y467861D02*
X1447411Y466718D01*
G01X1442371Y468831D02*
X1447432Y467688D01*
G01X1447411Y466718D02*
X1456074Y468277D01*
G01X1447432Y467688D02*
X1456079Y469244D01*
G01X1456074Y468277D02*
X1462970Y466961D01*
G01X1456079Y469244D02*
X1462947Y467933D01*
G01X1462970Y466961D02*
X1468706Y468339D01*
G01X1462947Y467933D02*
X1468593Y469289D01*
G01X1407736Y474602D02*
X1433716Y467231D01*
G01X1410808Y472742D02*
X1433671Y466256D01*
G01X1433716Y467231D02*
X1442371Y468831D01*
G01X1433671Y466256D02*
X1442352Y467861D01*
G01X1442371Y468831D02*
X1447432Y467688D01*
G01X1442352Y467861D02*
X1447411Y466718D01*
G01X1447432Y467688D02*
X1456079Y469244D01*
G01X1447411Y466718D02*
X1456074Y468277D01*
G01X1456079Y469244D02*
X1462947Y467933D01*
G01X1456074Y468277D02*
X1462970Y466961D01*
G01X1462947Y467933D02*
X1468593Y469289D01*
G01X1462970Y466961D02*
X1468706Y468339D01*
G01X1462947Y467933D02*
X1468593Y469289D01*
G01X1405334Y481268D02*
X1407736Y474602D01*
G01X1404547Y480647D02*
X1407007Y473820D01*
G01X1407736Y474602D02*
X1433716Y467231D01*
G01X1407007Y473820D02*
X1410808Y472742D01*
G01X1404682Y491184D02*
X1411877Y498379D01*
G01X1405076Y490234D02*
X1412354Y497512D01*
G01X1411877Y498379D02*
X1449951Y506920D01*
G01X1412354Y497512D02*
X1449941Y505944D01*
G01X1449951Y506920D02*
X1458872Y504734D01*
G01X1449941Y505944D02*
X1458388Y503874D01*
G01X1458872Y504734D02*
X1462506Y501100D01*
G01X1458388Y503874D02*
X1462112Y500150D01*
G01X1462506Y501100D02*
X1465600D01*
G01X1462112Y500150D02*
X1465206D01*
G01D02*
X1467721Y497635D01*
G01X1405076Y490234D02*
X1412354Y497512D01*
G01X1404682Y491184D02*
X1411877Y498379D01*
G01X1412354Y497512D02*
X1449941Y505944D01*
G01X1411877Y498379D02*
X1449951Y506920D01*
G01X1449941Y505944D02*
X1458388Y503874D01*
G01X1449951Y506920D02*
X1458872Y504734D01*
G01X1458388Y503874D02*
X1462112Y500150D01*
G01X1458872Y504734D02*
X1462506Y501100D01*
G01X1462112Y500150D02*
X1465206D01*
G01X1462506Y501100D02*
X1465600D01*
G01X1465206Y500150D02*
X1467721Y497635D01*
G01X1404754Y496848D02*
X1409892Y501986D01*
G01X1405148Y495898D02*
X1410369Y501119D01*
G01X1409892Y501986D02*
X1410161Y502047D01*
G01Y502046D02*
X1449991Y510981D01*
G01X1410369Y501119D02*
X1449981Y510005D01*
G01X1449991Y510981D02*
X1461202Y508234D01*
G01X1449981Y510005D02*
X1460718Y507374D01*
G01X1461202Y508234D02*
X1463986Y505450D01*
G01X1460718Y507374D02*
X1463592Y504500D01*
G01X1463986Y505450D02*
X1466749D01*
G01X1463592Y504500D02*
X1466355D01*
G01X1405148Y495898D02*
X1410369Y501119D01*
G01X1404754Y496848D02*
X1409892Y501986D01*
G01X1410369Y501119D02*
X1449981Y510005D01*
G01X1409892Y501986D02*
X1410161Y502047D01*
G01X1410369Y501119D02*
X1449981Y510005D01*
G01X1410161Y502046D02*
X1449991Y510981D01*
G01X1449981Y510005D02*
X1460718Y507374D01*
G01X1449991Y510981D02*
X1461202Y508234D01*
G01X1460718Y507374D02*
X1463592Y504500D01*
G01X1461202Y508234D02*
X1463986Y505450D01*
G01X1463592Y504500D02*
X1466355D01*
G01X1463986Y505450D02*
X1466749D01*
G01X1423456Y492544D02*
X1414420D01*
G01X1423452Y491594D02*
X1415012D01*
G01X1423526Y479648D02*
X1415266D01*
G01X1423483Y480598D02*
X1415127D01*
G01X1447428Y479852D02*
X1438557D01*
G01X1447442Y480802D02*
X1438698D01*
G01X1447391Y491473D02*
X1438591D01*
G01X1447541Y492423D02*
X1438141D01*
G01X1423452Y491594D02*
X1415012D01*
G01X1423456Y492544D02*
X1414420D01*
G01X1423483Y480598D02*
X1415127D01*
G01X1423526Y479648D02*
X1415266D01*
G01X1447442Y480802D02*
X1438698D01*
G01X1447428Y479852D02*
X1438557D01*
G01X1447541Y492423D02*
X1438141D01*
G01X1447391Y491473D02*
X1438591D01*
G01X1431637Y492598D02*
X1429566D01*
G01Y491648D02*
X1432031D01*
G01X1432421Y493382D02*
X1431637Y492598D01*
G01X1432031Y491648D02*
X1433371Y492988D01*
G01X1432421Y495531D02*
Y493382D01*
G01X1433371Y492988D02*
Y495137D01*
G01X1436540Y499650D02*
X1432421Y495531D01*
G01X1433371Y495137D02*
X1436934Y498700D01*
G01X1458208Y499650D02*
X1436540D01*
G01X1436934Y498700D02*
X1447168D01*
G01X1458208Y499650D02*
X1436540D01*
G01X1449418Y498700D02*
X1457814D01*
G01X1460890Y496968D02*
X1458208Y499650D01*
G01X1457814Y498700D02*
X1460496Y496018D01*
G01X1464245Y496968D02*
X1460890D01*
G01X1460496Y496018D02*
X1463851D01*
G01X1467843Y493370D02*
X1464245Y496968D01*
G01X1463851Y496018D02*
X1467449Y492420D01*
G01X1463851Y496018D02*
X1467449Y492420D01*
G01X1467843Y493370D02*
X1464245Y496968D01*
G01X1460496Y496018D02*
X1463851D01*
G01X1464245Y496968D02*
X1460890D01*
G01X1457814Y498700D02*
X1460496Y496018D01*
G01X1460890Y496968D02*
X1458208Y499650D01*
G01X1436934Y498700D02*
X1447168D01*
G01X1449418D02*
X1457814D01*
G01X1458208Y499650D02*
X1436540D01*
G01X1433371Y495137D02*
X1436934Y498700D01*
G01X1436540Y499650D02*
X1432421Y495531D01*
G01X1433371Y492988D02*
Y495137D01*
G01X1432421Y495531D02*
Y493382D01*
G01X1432031Y491648D02*
X1433371Y492988D01*
G01X1432421Y493382D02*
X1431637Y492598D01*
G01X1429566Y491648D02*
X1432031D01*
G01X1431637Y492598D02*
X1429566D01*
G01X1430958Y479648D02*
X1429739D01*
G01Y480598D02*
X1431352D01*
G01X1431641Y478965D02*
X1430958Y479648D01*
G01X1431352Y480598D02*
X1432591Y479359D01*
G01X1431641Y476265D02*
Y478965D01*
G01X1432591Y479359D02*
Y476757D01*
G01X1436323Y472955D02*
X1431641Y476265D01*
G01X1432591Y476757D02*
X1436701Y473852D01*
G01X1438283Y472592D02*
X1436325Y472955D01*
G01X1436323D02*
X1431641Y476265D01*
G01X1436701Y473852D02*
X1437044Y473788D01*
G01X1438283Y472592D02*
X1436325Y472955D01*
G01X1438283Y472592D02*
X1447723Y470844D01*
G01X1437044Y473788D02*
X1446392Y472057D01*
G01X1438283Y472592D02*
X1447723Y470844D01*
G01X1446392Y472057D02*
X1447709Y471813D01*
G01X1447723Y470844D02*
X1462866Y474099D01*
G01X1447709Y471813D02*
X1462764Y475049D01*
G01X1462866Y474099D02*
X1468822D01*
G01X1462764Y475049D02*
X1468822D01*
G01X1430958Y479648D02*
X1429739D01*
G01Y480598D02*
X1431352D01*
G01X1431641Y478965D02*
X1430958Y479648D01*
G01X1431352Y480598D02*
X1432591Y479359D01*
G01X1431641Y476265D02*
Y478965D01*
G01X1432591Y479359D02*
Y476757D01*
G01X1436323Y472955D02*
X1431641Y476265D01*
G01X1432591Y476757D02*
X1436701Y473852D01*
G01X1438283Y472592D02*
X1436325Y472955D01*
G01X1436323D02*
X1431641Y476265D01*
G01X1436701Y473852D02*
X1437044Y473788D01*
G01X1438283Y472592D02*
X1436325Y472955D01*
G01X1438283Y472592D02*
X1447723Y470844D01*
G01X1437044Y473788D02*
X1446392Y472057D01*
G01X1438283Y472592D02*
X1447723Y470844D01*
G01X1446392Y472057D02*
X1447709Y471813D01*
G01X1447723Y470844D02*
X1462866Y474099D01*
G01X1447709Y471813D02*
X1462764Y475049D01*
G01X1462866Y474099D02*
X1468822D01*
G01X1462764Y475049D02*
X1468822D01*
G01X1436701Y473852D02*
X1437044Y473788D01*
G01D02*
X1446392Y472057D01*
G01X1438283Y472592D02*
X1436325Y472955D01*
G01X1432591Y476757D02*
X1436701Y473852D01*
G01D02*
X1437044Y473788D01*
G01X1436323Y472955D02*
X1431641Y476265D01*
G01X1432591Y479359D02*
Y476757D01*
G01X1431641Y476265D02*
Y478965D01*
G01X1431352Y480598D02*
X1432591Y479359D01*
G01X1431641Y478965D02*
X1430958Y479648D01*
G01X1429739Y480598D02*
X1431352D01*
G01X1430958Y479648D02*
X1429739D01*
G01X1437044Y473788D02*
X1446392Y472057D01*
G01D02*
X1447709Y471813D01*
G01X1438283Y472592D02*
X1447723Y470844D01*
G01X1447709Y471813D02*
X1462764Y475049D01*
G01X1447723Y470844D02*
X1462866Y474099D01*
G01X1462764Y475049D02*
X1468822D01*
G01X1462866Y474099D02*
X1468822D01*
G01X1436701Y473852D02*
X1437044Y473788D01*
G01D02*
X1446392Y472057D01*
G01X1438283Y472592D02*
X1436325Y472955D01*
G01X1432591Y476757D02*
X1436701Y473852D01*
G01D02*
X1437044Y473788D01*
G01X1436323Y472955D02*
X1431641Y476265D01*
G01X1432591Y479359D02*
Y476757D01*
G01X1431641Y476265D02*
Y478965D01*
G01X1431352Y480598D02*
X1432591Y479359D01*
G01X1431641Y478965D02*
X1430958Y479648D01*
G01X1429739Y480598D02*
X1431352D01*
G01X1430958Y479648D02*
X1429739D01*
G01X1437044Y473788D02*
X1446392Y472057D01*
G01D02*
X1447709Y471813D01*
G01X1438283Y472592D02*
X1447723Y470844D01*
G01X1447709Y471813D02*
X1462764Y475049D01*
G01X1447723Y470844D02*
X1462866Y474099D01*
G01X1462764Y475049D02*
X1468822D01*
G01X1462866Y474099D02*
X1468822D01*
G01X1407736Y474602D02*
X1433716Y467231D01*
G01X1410808Y472742D02*
X1433671Y466256D01*
G01X1433716Y467231D02*
X1442371Y468831D01*
G01X1433671Y466256D02*
X1442352Y467861D01*
G01X1442371Y468831D02*
X1447432Y467688D01*
G01X1442352Y467861D02*
X1447411Y466718D01*
G01X1447432Y467688D02*
X1456079Y469244D01*
G01X1447411Y466718D02*
X1456074Y468277D01*
G01X1456079Y469244D02*
X1462947Y467933D01*
G01X1456074Y468277D02*
X1462970Y466961D01*
G01X1462947Y467933D02*
X1468593Y469289D01*
G01X1462970Y466961D02*
X1468706Y468339D01*
G01X1462947Y467933D02*
X1468593Y469289D01*
G01X1405334Y481268D02*
X1407736Y474602D01*
G01X1404547Y480647D02*
X1407007Y473820D01*
G01X1407736Y474602D02*
X1433716Y467231D01*
G01X1407007Y473820D02*
X1410808Y472742D01*
G01X1473246Y482312D02*
X1464759Y479923D01*
G01X1473246Y482312D02*
X1464759Y479923D01*
G01X1467570Y481702D02*
X1464626Y480873D01*
G01X1464759Y479923D02*
X1453414D01*
G01X1464626Y480873D02*
X1462948D01*
G01X1464759Y479923D02*
X1453414D01*
G01X1460648Y480873D02*
X1453264D01*
G01X1453533Y491615D02*
X1462441D01*
G01X1453199Y492565D02*
X1462835D01*
G01X1462441Y491615D02*
X1463695Y490361D01*
G01X1462835Y492565D02*
X1464645Y490755D01*
G01X1463695Y490361D02*
Y489026D01*
G01X1464645Y490755D02*
Y489420D01*
G01X1463695Y489026D02*
X1465199Y487522D01*
G01X1464645Y489420D02*
X1465593Y488472D01*
G01X1465199Y487522D02*
X1473566D01*
G01X1467570Y481702D02*
X1464626Y480873D01*
G01X1473246Y482312D02*
X1464759Y479923D01*
G01X1464626Y480873D02*
X1462948D01*
G01X1460648D02*
X1453264D01*
G01X1464759Y479923D02*
X1453414D01*
G01X1453199Y492565D02*
X1462835D01*
G01X1453533Y491615D02*
X1462441D01*
G01X1462835Y492565D02*
X1464645Y490755D01*
G01X1462441Y491615D02*
X1463695Y490361D01*
G01X1464645Y490755D02*
Y489420D01*
G01X1463695Y490361D02*
Y489026D01*
G01X1464645Y489420D02*
X1465593Y488472D01*
G01X1463695Y489026D02*
X1465199Y487522D01*
G01D02*
X1473566D01*
G01X1431637Y492598D02*
X1429566D01*
G01Y491648D02*
X1432031D01*
G01X1432421Y493382D02*
X1431637Y492598D01*
G01X1432031Y491648D02*
X1433371Y492988D01*
G01X1432421Y495531D02*
Y493382D01*
G01X1433371Y492988D02*
Y495137D01*
G01X1436540Y499650D02*
X1432421Y495531D01*
G01X1433371Y495137D02*
X1436934Y498700D01*
G01X1458208Y499650D02*
X1436540D01*
G01X1436934Y498700D02*
X1447168D01*
G01X1458208Y499650D02*
X1436540D01*
G01X1449418Y498700D02*
X1457814D01*
G01X1460890Y496968D02*
X1458208Y499650D01*
G01X1457814Y498700D02*
X1460496Y496018D01*
G01X1464245Y496968D02*
X1460890D01*
G01X1460496Y496018D02*
X1463851D01*
G01X1467843Y493370D02*
X1464245Y496968D01*
G01X1463851Y496018D02*
X1467449Y492420D01*
G01X1463851Y496018D02*
X1467449Y492420D01*
G01X1467843Y493370D02*
X1464245Y496968D01*
G01X1460496Y496018D02*
X1463851D01*
G01X1464245Y496968D02*
X1460890D01*
G01X1457814Y498700D02*
X1460496Y496018D01*
G01X1460890Y496968D02*
X1458208Y499650D01*
G01X1436934Y498700D02*
X1447168D01*
G01X1449418D02*
X1457814D01*
G01X1458208Y499650D02*
X1436540D01*
G01X1433371Y495137D02*
X1436934Y498700D01*
G01X1436540Y499650D02*
X1432421Y495531D01*
G01X1433371Y492988D02*
Y495137D01*
G01X1432421Y495531D02*
Y493382D01*
G01X1432031Y491648D02*
X1433371Y492988D01*
G01X1432421Y493382D02*
X1431637Y492598D01*
G01X1429566Y491648D02*
X1432031D01*
G01X1431637Y492598D02*
X1429566D01*
G01X1404682Y491184D02*
X1411877Y498379D01*
G01X1405076Y490234D02*
X1412354Y497512D01*
G01X1411877Y498379D02*
X1449951Y506920D01*
G01X1412354Y497512D02*
X1449941Y505944D01*
G01X1449951Y506920D02*
X1458872Y504734D01*
G01X1449941Y505944D02*
X1458388Y503874D01*
G01X1458872Y504734D02*
X1462506Y501100D01*
G01X1458388Y503874D02*
X1462112Y500150D01*
G01X1462506Y501100D02*
X1465600D01*
G01X1462112Y500150D02*
X1465206D01*
G01D02*
X1467721Y497635D01*
G01X1405076Y490234D02*
X1412354Y497512D01*
G01X1404682Y491184D02*
X1411877Y498379D01*
G01X1412354Y497512D02*
X1449941Y505944D01*
G01X1411877Y498379D02*
X1449951Y506920D01*
G01X1449941Y505944D02*
X1458388Y503874D01*
G01X1449951Y506920D02*
X1458872Y504734D01*
G01X1458388Y503874D02*
X1462112Y500150D01*
G01X1458872Y504734D02*
X1462506Y501100D01*
G01X1462112Y500150D02*
X1465206D01*
G01X1462506Y501100D02*
X1465600D01*
G01X1465206Y500150D02*
X1467721Y497635D01*
G01X1404754Y496848D02*
X1409892Y501986D01*
G01X1405148Y495898D02*
X1410369Y501119D01*
G01X1409892Y501986D02*
X1410161Y502047D01*
G01Y502046D02*
X1449991Y510981D01*
G01X1410369Y501119D02*
X1449981Y510005D01*
G01X1449991Y510981D02*
X1461202Y508234D01*
G01X1449981Y510005D02*
X1460718Y507374D01*
G01X1461202Y508234D02*
X1463986Y505450D01*
G01X1460718Y507374D02*
X1463592Y504500D01*
G01X1463986Y505450D02*
X1466749D01*
G01X1463592Y504500D02*
X1466355D01*
G01X1405148Y495898D02*
X1410369Y501119D01*
G01X1404754Y496848D02*
X1409892Y501986D01*
G01X1410369Y501119D02*
X1449981Y510005D01*
G01X1409892Y501986D02*
X1410161Y502047D01*
G01X1410369Y501119D02*
X1449981Y510005D01*
G01X1410161Y502046D02*
X1449991Y510981D01*
G01X1449981Y510005D02*
X1460718Y507374D01*
G01X1449991Y510981D02*
X1461202Y508234D01*
G01X1460718Y507374D02*
X1463592Y504500D01*
G01X1461202Y508234D02*
X1463986Y505450D01*
G01X1463592Y504500D02*
X1466355D01*
G01X1463986Y505450D02*
X1466749D01*
G01X1473246Y482312D02*
X1464759Y479923D01*
G01X1473246Y482312D02*
X1464759Y479923D01*
G01X1467570Y481702D02*
X1464626Y480873D01*
G01X1464759Y479923D02*
X1453414D01*
G01X1464626Y480873D02*
X1462948D01*
G01X1464759Y479923D02*
X1453414D01*
G01X1460648Y480873D02*
X1453264D01*
G01X1467570Y481702D02*
X1464626Y480873D01*
G01X1473246Y482312D02*
X1464759Y479923D01*
G01X1464626Y480873D02*
X1462948D01*
G01X1460648D02*
X1453264D01*
G01X1464759Y479923D02*
X1453414D01*
G01X1453199Y492565D02*
X1462835D01*
G01X1453533Y491615D02*
X1462441D01*
G01X1462835Y492565D02*
X1464645Y490755D01*
G01X1462441Y491615D02*
X1463695Y490361D01*
G01X1464645Y490755D02*
Y489420D01*
G01X1463695Y490361D02*
Y489026D01*
G01X1464645Y489420D02*
X1465593Y488472D01*
G01X1463695Y489026D02*
X1465199Y487522D01*
G01D02*
X1473566D01*
G01X1504800Y119100D02*
Y77500D01*
G01Y119100D02*
Y77500D01*
G01X1503850Y95309D02*
Y93959D01*
G01X1504800Y119100D02*
Y77500D01*
G01X1503850Y91709D02*
Y77894D01*
G01X1504800Y77500D02*
X1476300Y49000D01*
G01X1503850Y77894D02*
X1475906Y49950D01*
G01X1476300Y49000D02*
X1469689D01*
G01X1503850Y95309D02*
Y93959D01*
G01Y91709D02*
Y77894D01*
G01X1504800Y119100D02*
Y77500D01*
G01X1503850Y77894D02*
X1475906Y49950D01*
G01X1504800Y77500D02*
X1476300Y49000D01*
G01D02*
X1469689D01*
G01X1504800Y119100D02*
Y77500D01*
G01Y119100D02*
Y77500D01*
G01X1503850Y95309D02*
Y93959D01*
G01X1504800Y119100D02*
Y77500D01*
G01X1503850Y91709D02*
Y77894D01*
G01X1504800Y77500D02*
X1476300Y49000D01*
G01X1503850Y77894D02*
X1475906Y49950D01*
G01X1476300Y49000D02*
X1469689D01*
G01X1503850Y95309D02*
Y93959D01*
G01Y91709D02*
Y77894D01*
G01X1504800Y119100D02*
Y77500D01*
G01X1503850Y77894D02*
X1475906Y49950D01*
G01X1504800Y77500D02*
X1476300Y49000D01*
G01D02*
X1469689D01*
G01X1537800Y126000D02*
X1523000D01*
G01X1537800D02*
X1523000D01*
G01X1537800D02*
X1523000D01*
G01X1527847Y126950D02*
X1522606D01*
G01X1523000Y126000D02*
X1520251Y123251D01*
G01X1522606Y126950D02*
X1519857Y124201D01*
G01X1520251Y123251D02*
X1508951D01*
G01X1519857Y124201D02*
X1508557D01*
G01X1508951Y123251D02*
X1504800Y119100D01*
G01X1508557Y124201D02*
X1503850Y119494D01*
G01D02*
Y97559D01*
G01X1527847Y126950D02*
X1522606D01*
G01X1537800Y126000D02*
X1523000D01*
G01X1522606Y126950D02*
X1519857Y124201D01*
G01X1523000Y126000D02*
X1520251Y123251D01*
G01X1519857Y124201D02*
X1508557D01*
G01X1520251Y123251D02*
X1508951D01*
G01X1508557Y124201D02*
X1503850Y119494D01*
G01X1508951Y123251D02*
X1504800Y119100D01*
G01X1503850Y119494D02*
Y97559D01*
G01X1537800Y126000D02*
X1523000D01*
G01X1537800D02*
X1523000D01*
G01X1537800D02*
X1523000D01*
G01X1527847Y126950D02*
X1522606D01*
G01X1523000Y126000D02*
X1520251Y123251D01*
G01X1522606Y126950D02*
X1519857Y124201D01*
G01X1520251Y123251D02*
X1508951D01*
G01X1519857Y124201D02*
X1508557D01*
G01X1508951Y123251D02*
X1504800Y119100D01*
G01X1508557Y124201D02*
X1503850Y119494D01*
G01D02*
Y97559D01*
G01X1521531Y96551D02*
X1525030D01*
G01X1521731Y95601D02*
X1524408D01*
G01X1527847Y126950D02*
X1522606D01*
G01X1537800Y126000D02*
X1523000D01*
G01X1522606Y126950D02*
X1519857Y124201D01*
G01X1523000Y126000D02*
X1520251Y123251D01*
G01X1519857Y124201D02*
X1508557D01*
G01X1520251Y123251D02*
X1508951D01*
G01X1508557Y124201D02*
X1503850Y119494D01*
G01X1508951Y123251D02*
X1504800Y119100D01*
G01X1503850Y119494D02*
Y97559D01*
G01X1515360Y118718D02*
X1515997D01*
G01X1515360Y117768D02*
X1515997D01*
G01X1515360Y106907D02*
X1516120D01*
G01X1515360Y105957D02*
X1515972D01*
G01X1515360Y117768D02*
X1515997D01*
G01X1515360Y118718D02*
X1515997D01*
G01X1515360Y105957D02*
X1515972D01*
G01X1515360Y106907D02*
X1516120D01*
G01X1522124Y118847D02*
X1524591D01*
G01X1522146Y117897D02*
X1524385D01*
G01X1522146D02*
X1524385D01*
G01X1522124Y118847D02*
X1524591D01*
G01X1521731Y95601D02*
X1524408D01*
G01X1521531Y96551D02*
X1525030D01*
G01X1472100Y446550D02*
X1470768D01*
G01X1475129Y435973D02*
X1474195D01*
G01X1471929D02*
X1470579D01*
G01X1468313D02*
X1466963D01*
G01X1477550Y438394D02*
X1476265Y437109D01*
G01D02*
X1475129Y435973D01*
G01X1475523Y435023D02*
X1478500Y438000D01*
G01X1477550Y439713D02*
Y438394D01*
G01X1478500Y438000D02*
Y439713D01*
G01X1472100Y446550D02*
X1470768D01*
G01X1472100D02*
X1470768D01*
G01X1478500Y438000D02*
Y439713D01*
G01X1477550D02*
Y438394D01*
G01X1475523Y435023D02*
X1478500Y438000D01*
G01X1477550Y438394D02*
X1476265Y437109D01*
G01X1475523Y435023D02*
X1478500Y438000D01*
G01X1476265Y437109D02*
X1475129Y435973D01*
G01D02*
X1474195D01*
G01X1471929D02*
X1470579D01*
G01X1468313D02*
X1466963D01*
G01X1472100Y446550D02*
X1470768D01*
G01X1478500Y438000D02*
Y439713D01*
G01X1477550D02*
Y438394D01*
G01X1475523Y435023D02*
X1478500Y438000D01*
G01X1477550Y438394D02*
X1476265Y437109D01*
G01X1475523Y435023D02*
X1478500Y438000D01*
G01X1476265Y437109D02*
X1475129Y435973D01*
G01D02*
X1474195D01*
G01X1471929D02*
X1470579D01*
G01X1468313D02*
X1466963D01*
G01X1468706Y468339D02*
X1469343D01*
G01X1468706D02*
X1469343D01*
G01X1468593Y469289D02*
X1469343D01*
G01X1468706Y468339D02*
X1469343D01*
G01X1468706D02*
X1469343D01*
G01X1468593Y469289D02*
X1469343D01*
G01X1468593D02*
X1469343D01*
G01X1468706Y468339D02*
X1469343D01*
G01X1476600Y496750D02*
X1488903D01*
G01X1479303Y495800D02*
X1488903D01*
G01X1465600Y501100D02*
X1468115Y498585D01*
G01X1471829D02*
X1474765D01*
G01X1468115D02*
X1471829D01*
G01X1467721Y497635D02*
X1474371D01*
G01X1474765Y498585D02*
X1476600Y496750D01*
G01X1474371Y497635D02*
X1476206Y495800D01*
G01X1476600Y496750D02*
X1488903D01*
G01X1476206Y495800D02*
X1479303D01*
G01X1467721Y497635D02*
X1474371D01*
G01X1471829Y498585D02*
X1474765D01*
G01X1474371Y497635D02*
X1476206Y495800D01*
G01X1474765Y498585D02*
X1476600Y496750D01*
G01X1479303Y495800D02*
X1488903D01*
G01X1476206D02*
X1479303D01*
G01X1476600Y496750D02*
X1488903D01*
G01X1465600Y501100D02*
X1468115Y498585D01*
G01X1467721Y497635D02*
X1474371D01*
G01X1468115Y498585D02*
X1471829D01*
G01X1487200Y502388D02*
X1488992D01*
G01X1469811D02*
X1487200D01*
G01X1479300Y501438D02*
X1488598D01*
G01X1488992Y502388D02*
X1490060Y501320D01*
G01X1488598Y501438D02*
X1489666Y500370D01*
G01X1490060Y501320D02*
X1491873D01*
G01X1489666Y500370D02*
X1491873D01*
G01X1466749Y505450D02*
X1469811Y502388D01*
G01X1466355Y504500D02*
X1469417Y501438D01*
G01X1469811Y502388D02*
X1487200D01*
G01X1469417Y501438D02*
X1479300D01*
G01D02*
X1488598D01*
G01X1487200Y502388D02*
X1488992D01*
G01X1488598Y501438D02*
X1489666Y500370D01*
G01X1488992Y502388D02*
X1490060Y501320D01*
G01X1489666Y500370D02*
X1491873D01*
G01X1490060Y501320D02*
X1491873D01*
G01X1466355Y504500D02*
X1469417Y501438D01*
G01X1466749Y505450D02*
X1469811Y502388D01*
G01X1479300Y501438D02*
X1488598D01*
G01X1469417D02*
X1479300D01*
G01X1469811Y502388D02*
X1487200D01*
G01X1474488Y493370D02*
X1490283D01*
G01X1484200Y492420D02*
X1490283D01*
G01X1474488Y493370D02*
X1490283D01*
G01X1474488D02*
X1467843D01*
G01X1467449Y492420D02*
X1484200D01*
G01D02*
X1490283D01*
G01X1467449D02*
X1484200D01*
G01X1474488Y493370D02*
X1490283D01*
G01X1467449Y492420D02*
X1484200D01*
G01X1474488Y493370D02*
X1467843D01*
G01X1468593Y469289D02*
X1469343D01*
G01X1468706Y468339D02*
X1469343D01*
G01X1473246Y482312D02*
X1477056Y483385D01*
G01X1467570Y481702D02*
X1476927Y484335D01*
G01X1477056Y483385D02*
X1479054D01*
G01X1476927Y484335D02*
X1479054D01*
G01X1473566Y487522D02*
X1474094Y488050D01*
G01X1465593Y488472D02*
X1473172D01*
G01X1473566Y487522D02*
X1474094Y488050D01*
G01D02*
X1475483D01*
G01X1473172Y488472D02*
X1473700Y489000D01*
G01X1475483Y488050D02*
X1477353D01*
G01X1474094D02*
X1475483D01*
G01X1473700Y489000D02*
X1477353D01*
G01X1467570Y481702D02*
X1476927Y484335D01*
G01X1473246Y482312D02*
X1477056Y483385D01*
G01X1476927Y484335D02*
X1479054D01*
G01X1477056Y483385D02*
X1479054D01*
G01X1467570Y481702D02*
X1476927Y484335D01*
G01X1473700Y489000D02*
X1477353D01*
G01X1475483Y488050D02*
X1477353D01*
G01X1465593Y488472D02*
X1473172D01*
G01X1465593D02*
X1473172D01*
G01D02*
X1473700Y489000D01*
G01X1473566Y487522D02*
X1474094Y488050D01*
G01X1473172Y488472D02*
X1473700Y489000D01*
G01D02*
X1477353D01*
G01X1474094Y488050D02*
X1475483D01*
G01X1526463Y511047D02*
Y509058D01*
G01D02*
X1528400Y507121D01*
G01X1474488Y493370D02*
X1490283D01*
G01X1484200Y492420D02*
X1490283D01*
G01X1474488Y493370D02*
X1490283D01*
G01X1474488D02*
X1467843D01*
G01X1467449Y492420D02*
X1484200D01*
G01D02*
X1490283D01*
G01X1467449D02*
X1484200D01*
G01X1474488Y493370D02*
X1490283D01*
G01X1467449Y492420D02*
X1484200D01*
G01X1474488Y493370D02*
X1467843D01*
G01X1476600Y496750D02*
X1488903D01*
G01X1479303Y495800D02*
X1488903D01*
G01X1465600Y501100D02*
X1468115Y498585D01*
G01X1471829D02*
X1474765D01*
G01X1468115D02*
X1471829D01*
G01X1467721Y497635D02*
X1474371D01*
G01X1474765Y498585D02*
X1476600Y496750D01*
G01X1474371Y497635D02*
X1476206Y495800D01*
G01X1476600Y496750D02*
X1488903D01*
G01X1476206Y495800D02*
X1479303D01*
G01X1467721Y497635D02*
X1474371D01*
G01X1471829Y498585D02*
X1474765D01*
G01X1474371Y497635D02*
X1476206Y495800D01*
G01X1474765Y498585D02*
X1476600Y496750D01*
G01X1479303Y495800D02*
X1488903D01*
G01X1476206D02*
X1479303D01*
G01X1476600Y496750D02*
X1488903D01*
G01X1465600Y501100D02*
X1468115Y498585D01*
G01X1467721Y497635D02*
X1474371D01*
G01X1468115Y498585D02*
X1471829D01*
G01X1487200Y502388D02*
X1488992D01*
G01X1469811D02*
X1487200D01*
G01X1479300Y501438D02*
X1488598D01*
G01X1488992Y502388D02*
X1490060Y501320D01*
G01X1488598Y501438D02*
X1489666Y500370D01*
G01X1490060Y501320D02*
X1491873D01*
G01X1489666Y500370D02*
X1491873D01*
G01X1466749Y505450D02*
X1469811Y502388D01*
G01X1466355Y504500D02*
X1469417Y501438D01*
G01X1469811Y502388D02*
X1487200D01*
G01X1469417Y501438D02*
X1479300D01*
G01D02*
X1488598D01*
G01X1487200Y502388D02*
X1488992D01*
G01X1488598Y501438D02*
X1489666Y500370D01*
G01X1488992Y502388D02*
X1490060Y501320D01*
G01X1489666Y500370D02*
X1491873D01*
G01X1490060Y501320D02*
X1491873D01*
G01X1466355Y504500D02*
X1469417Y501438D01*
G01X1466749Y505450D02*
X1469811Y502388D01*
G01X1479300Y501438D02*
X1488598D01*
G01X1469417D02*
X1479300D01*
G01X1469811Y502388D02*
X1487200D01*
G01X1473246Y482312D02*
X1477056Y483385D01*
G01X1467570Y481702D02*
X1476927Y484335D01*
G01X1477056Y483385D02*
X1479054D01*
G01X1476927Y484335D02*
X1479054D01*
G01X1467570Y481702D02*
X1476927Y484335D01*
G01X1473246Y482312D02*
X1477056Y483385D01*
G01X1476927Y484335D02*
X1479054D01*
G01X1477056Y483385D02*
X1479054D01*
G01X1467570Y481702D02*
X1476927Y484335D01*
G01X1473700Y489000D02*
X1477353D01*
G01X1475483Y488050D02*
X1477353D01*
G01X1465593Y488472D02*
X1473172D01*
G01X1465593D02*
X1473172D01*
G01D02*
X1473700Y489000D01*
G01X1473566Y487522D02*
X1474094Y488050D01*
G01X1473172Y488472D02*
X1473700Y489000D01*
G01D02*
X1477353D01*
G01X1474094Y488050D02*
X1475483D01*
G01X1526463Y511047D02*
Y509058D01*
G01D02*
X1528400Y507121D01*
G01X1526463Y509058D02*
X1528400Y507121D01*
G01X1526463Y509058D02*
X1528400Y507121D01*
G01X1526463Y509058D02*
X1528400Y507121D01*
G01X1526463Y509058D02*
X1528400Y507121D01*
G01X1526463Y511047D02*
Y509058D01*
G01D02*
X1528400Y507121D01*
G01X1526463Y509058D02*
X1528400Y507121D01*
G01X1526463Y509058D02*
X1528400Y507121D01*
G01X1526463Y509058D02*
X1528400Y507121D01*
G01X1526463Y511047D02*
Y509058D01*
G01X1556750Y135250D02*
X1550850D01*
G01X1556275Y136200D02*
X1550456D01*
G01X1550850Y135250D02*
X1545071Y129471D01*
G01X1550456Y136200D02*
X1547758Y133502D01*
G01X1550850Y135250D02*
X1545071Y129471D01*
G01X1547758Y133502D02*
X1547122D01*
G01X1550850Y135250D02*
X1545071Y129471D01*
G01X1546167Y131911D02*
X1544677Y130421D01*
G01X1545071Y129471D02*
X1541271D01*
G01X1544677Y130421D02*
X1540877D01*
G01X1541271Y129471D02*
X1537800Y126000D01*
G01X1540877Y130421D02*
X1537406Y126950D01*
G01D02*
X1533697D01*
G01X1531447D02*
X1530097D01*
G01X1556275Y136200D02*
X1550456D01*
G01X1556750Y135250D02*
X1550850D01*
G01X1550456Y136200D02*
X1547758Y133502D01*
G01D02*
X1547122D01*
G01X1546167Y131911D02*
X1544677Y130421D01*
G01X1550850Y135250D02*
X1545071Y129471D01*
G01X1544677Y130421D02*
X1540877D01*
G01X1545071Y129471D02*
X1541271D01*
G01X1540877Y130421D02*
X1537406Y126950D01*
G01X1541271Y129471D02*
X1537800Y126000D01*
G01X1537406Y126950D02*
X1533697D01*
G01X1531447D02*
X1530097D01*
G01X1556750Y135250D02*
X1550850D01*
G01X1556275Y136200D02*
X1550456D01*
G01X1550850Y135250D02*
X1545071Y129471D01*
G01X1550456Y136200D02*
X1547758Y133502D01*
G01X1550850Y135250D02*
X1545071Y129471D01*
G01X1547758Y133502D02*
X1547122D01*
G01X1550850Y135250D02*
X1545071Y129471D01*
G01X1546167Y131911D02*
X1544677Y130421D01*
G01X1545071Y129471D02*
X1541271D01*
G01X1544677Y130421D02*
X1540877D01*
G01X1541271Y129471D02*
X1537800Y126000D01*
G01X1540877Y130421D02*
X1537406Y126950D01*
G01D02*
X1533697D01*
G01X1531447D02*
X1530097D01*
G01X1556275Y136200D02*
X1550456D01*
G01X1556750Y135250D02*
X1550850D01*
G01X1550456Y136200D02*
X1547758Y133502D01*
G01D02*
X1547122D01*
G01X1546167Y131911D02*
X1544677Y130421D01*
G01X1550850Y135250D02*
X1545071Y129471D01*
G01X1544677Y130421D02*
X1540877D01*
G01X1545071Y129471D02*
X1541271D01*
G01X1540877Y130421D02*
X1537406Y126950D01*
G01X1541271Y129471D02*
X1537800Y126000D01*
G01X1537406Y126950D02*
X1533697D01*
G01X1531447D02*
X1530097D01*
G01X1529850Y501212D02*
X1529375Y501687D01*
G01X1528400Y501318D02*
X1529456Y500262D01*
G01X1530857Y501212D02*
X1529850D01*
G01X1529456Y500262D02*
X1530963D01*
G01X1527413Y509452D02*
Y511305D01*
G01X1529350Y507515D02*
X1528350Y508515D01*
G01D02*
X1528351D01*
G01X1528368Y508532D02*
X1528333D01*
G01D02*
X1527413Y509452D01*
G01X1529350Y503826D02*
Y503915D01*
G01Y506165D02*
Y507515D01*
G01X1528400Y507121D02*
Y502500D01*
G01X1586771Y500628D02*
X1597816D01*
G01X1586771D02*
X1597816D01*
G01X1586771D02*
X1597816D01*
G01X1585223D02*
X1586771D01*
G01X1586687Y499678D02*
X1585337D01*
G01X1586687D02*
X1585337D01*
G01X1585223Y500628D02*
X1586771D01*
G01D02*
X1597816D01*
G01X1586687Y499678D02*
X1585337D01*
G01X1585223Y500628D02*
X1586771D01*
G01D02*
X1597816D01*
G01X1577802Y500643D02*
X1573387D01*
G01X1576075Y499693D02*
X1573387D01*
G01X1577802Y500643D02*
X1573387D01*
G01X1576075Y499693D02*
X1577658D01*
G01X1577802Y500643D02*
X1573387D01*
G01X1576075Y499693D02*
X1573387D01*
G01X1577802Y500643D02*
X1573387D01*
G01X1576075Y499693D02*
X1577658D01*
G01X1576075D02*
X1573387D01*
G01X1576075D02*
X1577658D01*
G01X1577802Y500643D02*
X1573387D01*
G01X1529850Y501212D02*
X1529375Y501687D01*
G01X1528400Y501318D02*
X1529456Y500262D01*
G01X1530857Y501212D02*
X1529850D01*
G01X1529456Y500262D02*
X1530963D01*
G01X1527413Y509452D02*
Y511305D01*
G01X1529350Y507515D02*
X1528350Y508515D01*
G01D02*
X1528351D01*
G01X1528368Y508532D02*
X1528333D01*
G01D02*
X1527413Y509452D01*
G01X1529350Y503826D02*
Y503915D01*
G01Y506165D02*
Y507515D01*
G01X1528400Y507121D02*
Y502500D01*
G01X1529456Y500262D02*
X1530963D01*
G01X1530857Y501212D02*
X1529850D01*
G01X1528400Y501318D02*
X1529456Y500262D01*
G01X1529850Y501212D02*
X1529375Y501687D01*
G01X1528400Y507121D02*
Y502500D01*
G01X1529350Y503826D02*
Y503915D01*
G01X1528400Y507121D02*
Y502500D01*
G01X1529350Y506165D02*
Y507515D01*
G01D02*
X1528350Y508515D01*
G01D02*
X1528351D01*
G01X1528368Y508532D02*
X1528333D01*
G01D02*
X1527413Y509452D01*
G01D02*
Y511305D01*
G01X1529456Y500262D02*
X1530963D01*
G01X1530857Y501212D02*
X1529850D01*
G01X1528400Y501318D02*
X1529456Y500262D01*
G01X1529850Y501212D02*
X1529375Y501687D01*
G01X1528400Y507121D02*
Y502500D01*
G01X1529350Y503826D02*
Y503915D01*
G01X1528400Y507121D02*
Y502500D01*
G01X1529350Y506165D02*
Y507515D01*
G01D02*
X1528350Y508515D01*
G01D02*
X1528351D01*
G01X1528368Y508532D02*
X1528333D01*
G01D02*
X1527413Y509452D01*
G01D02*
Y511305D01*
G01X1590118Y492358D02*
X1577718D01*
G01X1577744Y493308D02*
X1579094D01*
G01X1590118Y492358D02*
X1577718D01*
G01X1581344Y493308D02*
X1583671D01*
G01X1590118Y492358D02*
X1577718D01*
G01X1585921Y493308D02*
X1587815D01*
G01X1590118Y492358D02*
X1577718D01*
G01X1587815Y493308D02*
X1589724D01*
G01X1590118Y492358D02*
X1577718D01*
G01X1577744Y493308D02*
X1579094D01*
G01X1590118Y492358D02*
X1577718D01*
G01X1581344Y493308D02*
X1583671D01*
G01X1590118Y492358D02*
X1577718D01*
G01X1585921Y493308D02*
X1587815D01*
G01X1590118Y492358D02*
X1577718D01*
G01X1587815Y493308D02*
X1589724D01*
G01X1577744D02*
X1579094D01*
G01X1581344D02*
X1583671D01*
G01X1585921D02*
X1587815D01*
G01D02*
X1589724D01*
G01X1590118Y492358D02*
X1577718D01*
G01X1586771Y500628D02*
X1597816D01*
G01X1586771D02*
X1597816D01*
G01X1586771D02*
X1597816D01*
G01X1585223D02*
X1586771D01*
G01X1586687Y499678D02*
X1585337D01*
G01X1576454Y547056D02*
X1580745Y551347D01*
G01X1576454Y547056D02*
X1563860Y534462D01*
G01X1565671Y534929D02*
X1581417Y550675D01*
G01X1580745Y551347D02*
G02X1583451Y552467I2704J-2705D01*
G01X1581417Y550675D02*
G02X1583450Y551517I2033J-2032D01*
G01X1583451Y552467D02*
X1612808D01*
G01X1583450Y551517D02*
X1612807D01*
G01X1576454Y547056D02*
X1563860Y534462D01*
G01X1565671Y534929D02*
X1564532Y533790D01*
G01X1563860Y534462D02*
G02X1563542Y534330I-318J318D01*
G01X1564532Y533790D02*
G02X1563543Y533380I-990J990D01*
G01X1563542Y534330D02*
X1559479D01*
G01X1563543Y533380D02*
X1559479D01*
G01X1565671Y534929D02*
X1581417Y550675D01*
G01X1576454Y547056D02*
X1580745Y551347D01*
G01X1581417Y550675D02*
G02X1583450Y551517I2033J-2032D01*
G01X1580745Y551347D02*
G02X1583451Y552467I2704J-2705D01*
G01X1583450Y551517D02*
X1612807D01*
G01X1583451Y552467D02*
X1612808D01*
G01X1565671Y534929D02*
X1581417Y550675D01*
G01X1565671Y534929D02*
X1564532Y533790D01*
G01X1576454Y547056D02*
X1563860Y534462D01*
G01X1564532Y533790D02*
G02X1563543Y533380I-990J990D01*
G01X1563860Y534462D02*
G02X1563542Y534330I-318J318D01*
G01X1563543Y533380D02*
X1559479D01*
G01X1563542Y534330D02*
X1559479D01*
G01X1576454Y547056D02*
X1580745Y551347D01*
G01X1576454Y547056D02*
X1563860Y534462D01*
G01X1565671Y534929D02*
X1581417Y550675D01*
G01X1580745Y551347D02*
G02X1583451Y552467I2704J-2705D01*
G01X1581417Y550675D02*
G02X1583450Y551517I2033J-2032D01*
G01X1583451Y552467D02*
X1612808D01*
G01X1583450Y551517D02*
X1612807D01*
G01X1576454Y547056D02*
X1563860Y534462D01*
G01X1565671Y534929D02*
X1564532Y533790D01*
G01X1563860Y534462D02*
G02X1563542Y534330I-318J318D01*
G01X1564532Y533790D02*
G02X1563543Y533380I-990J990D01*
G01X1563542Y534330D02*
X1559479D01*
G01X1563543Y533380D02*
X1559479D01*
G01X1565671Y534929D02*
X1581417Y550675D01*
G01X1576454Y547056D02*
X1580745Y551347D01*
G01X1581417Y550675D02*
G02X1583450Y551517I2033J-2032D01*
G01X1580745Y551347D02*
G02X1583451Y552467I2704J-2705D01*
G01X1583450Y551517D02*
X1612807D01*
G01X1583451Y552467D02*
X1612808D01*
G01X1565671Y534929D02*
X1581417Y550675D01*
G01X1565671Y534929D02*
X1564532Y533790D01*
G01X1576454Y547056D02*
X1563860Y534462D01*
G01X1564532Y533790D02*
G02X1563543Y533380I-990J990D01*
G01X1563860Y534462D02*
G02X1563542Y534330I-318J318D01*
G01X1563543Y533380D02*
X1559479D01*
G01X1563542Y534330D02*
X1559479D01*
G01X1597816Y500628D02*
X1599810Y498634D01*
G01X1595851Y499678D02*
X1597422D01*
G01X1597816Y500628D02*
X1599810Y498634D01*
G01X1597422Y499678D02*
X1598860Y498240D01*
G01X1599810Y498634D02*
Y496386D01*
G01X1598860Y498240D02*
Y496060D01*
G01X1595851Y499678D02*
X1592537D01*
G01X1590287D02*
X1588937D01*
G01X1595851D02*
X1597422D01*
G01X1595851D02*
X1592537D01*
G01X1590287D02*
X1588937D01*
G01X1595851D02*
X1597422D01*
G01D02*
X1598860Y498240D01*
G01X1597816Y500628D02*
X1599810Y498634D01*
G01X1598860Y498240D02*
Y496060D01*
G01X1599810Y498634D02*
Y496386D01*
G01X1595851Y499678D02*
X1597422D01*
G01X1595851D02*
X1592537D01*
G01X1590287D02*
X1588937D01*
G01X1595851D02*
X1597422D01*
G01D02*
X1598860Y498240D01*
G01X1597816Y500628D02*
X1599810Y498634D01*
G01X1598860Y498240D02*
Y496060D01*
G01X1599810Y498634D02*
Y496386D01*
G01X1591410Y493650D02*
X1590118Y492358D01*
G01X1589724Y493308D02*
X1590460Y494044D01*
G01X1591410Y495360D02*
Y493650D01*
G01X1590460Y494044D02*
Y494540D01*
G01X1591410Y493650D02*
X1590118Y492358D01*
G01X1589724Y493308D02*
X1590460Y494044D01*
G01X1591410Y495360D02*
Y493650D01*
G01X1590460Y494044D02*
Y494540D01*
G01Y494044D02*
Y494540D01*
G01X1591410Y495360D02*
Y493650D01*
G01X1589724Y493308D02*
X1590460Y494044D01*
G01X1591410Y493650D02*
X1590118Y492358D01*
G01X1597816Y500628D02*
X1599810Y498634D01*
G01X1595851Y499678D02*
X1597422D01*
G01X1597816Y500628D02*
X1599810Y498634D01*
G01X1597422Y499678D02*
X1598860Y498240D01*
G01X1599810Y498634D02*
Y496386D01*
G01X1598860Y498240D02*
Y496060D01*
G01X1595851Y499678D02*
X1592537D01*
G01X1590287D02*
X1588937D01*
G01X1612808Y552467D02*
G02X1614183Y551897I-1J-1946D01*
G01X1612807Y551517D02*
G02X1613511Y551225I0J-996D01*
G01X1614183Y551897D02*
X1614575Y551505D01*
G01X1613511Y551225D02*
X1613903Y550833D01*
G01X1614575Y551505D02*
G03X1615107Y551285I532J532D01*
G01X1613903Y550833D02*
G03X1615106Y550335I1203J1204D01*
G01X1615107Y551285D02*
X1634963D01*
G01X1615106Y550335D02*
X1616456D01*
G01X1615107Y551285D02*
X1634963D01*
G01X1619606Y550335D02*
X1620956D01*
G01X1615107Y551285D02*
X1634963D01*
G01X1624106Y550335D02*
X1625456D01*
G01X1615107Y551285D02*
X1634963D01*
G01X1628606Y550335D02*
X1634962D01*
G01X1634963Y551285D02*
G02X1648614Y545630I-1J-19306D01*
G01X1634962Y550335D02*
G02X1647942Y544958I0J-18356D01*
G01X1648614Y545630D02*
X1653125Y541120D01*
G01X1647942Y544958D02*
X1652428Y540472D01*
G01X1612807Y551517D02*
G02X1613511Y551225I0J-996D01*
G01X1612808Y552467D02*
G02X1614183Y551897I-1J-1946D01*
G01X1613511Y551225D02*
X1613903Y550833D01*
G01X1614183Y551897D02*
X1614575Y551505D01*
G01X1613903Y550833D02*
G03X1615106Y550335I1203J1204D01*
G01X1614575Y551505D02*
G03X1615107Y551285I532J532D01*
G01X1615106Y550335D02*
X1616456D01*
G01X1619606D02*
X1620956D01*
G01X1624106D02*
X1625456D01*
G01X1628606D02*
X1634962D01*
G01X1615107Y551285D02*
X1634963D01*
G01X1634962Y550335D02*
G02X1647942Y544958I0J-18356D01*
G01X1634963Y551285D02*
G02X1648614Y545630I-1J-19306D01*
G01X1647942Y544958D02*
X1652428Y540472D01*
G01X1648614Y545630D02*
X1653125Y541120D01*
G01X1612808Y552467D02*
G02X1614183Y551897I-1J-1946D01*
G01X1612807Y551517D02*
G02X1613511Y551225I0J-996D01*
G01X1614183Y551897D02*
X1614575Y551505D01*
G01X1613511Y551225D02*
X1613903Y550833D01*
G01X1614575Y551505D02*
G03X1615107Y551285I532J532D01*
G01X1613903Y550833D02*
G03X1615106Y550335I1203J1204D01*
G01X1615107Y551285D02*
X1634963D01*
G01X1615106Y550335D02*
X1616456D01*
G01X1615107Y551285D02*
X1634963D01*
G01X1619606Y550335D02*
X1620956D01*
G01X1615107Y551285D02*
X1634963D01*
G01X1624106Y550335D02*
X1625456D01*
G01X1615107Y551285D02*
X1634963D01*
G01X1628606Y550335D02*
X1634962D01*
G01X1634963Y551285D02*
G02X1648614Y545630I-1J-19306D01*
G01X1634962Y550335D02*
G02X1647942Y544958I0J-18356D01*
G01X1648614Y545630D02*
X1653125Y541120D01*
G01X1647942Y544958D02*
X1652428Y540472D01*
G01X1612807Y551517D02*
G02X1613511Y551225I0J-996D01*
G01X1612808Y552467D02*
G02X1614183Y551897I-1J-1946D01*
G01X1613511Y551225D02*
X1613903Y550833D01*
G01X1614183Y551897D02*
X1614575Y551505D01*
G01X1613903Y550833D02*
G03X1615106Y550335I1203J1204D01*
G01X1614575Y551505D02*
G03X1615107Y551285I532J532D01*
G01X1615106Y550335D02*
X1616456D01*
G01X1619606D02*
X1620956D01*
G01X1624106D02*
X1625456D01*
G01X1628606D02*
X1634962D01*
G01X1615107Y551285D02*
X1634963D01*
G01X1634962Y550335D02*
G02X1647942Y544958I0J-18356D01*
G01X1634963Y551285D02*
G02X1648614Y545630I-1J-19306D01*
G01X1647942Y544958D02*
X1652428Y540472D01*
G01X1648614Y545630D02*
X1653125Y541120D01*
G01X1625544Y556725D02*
X1626889D01*
G01X1625544Y557675D02*
X1626889D01*
G01X1616259Y574055D02*
X1608617D01*
G01X1616319Y575005D02*
X1608617D01*
G01Y574055D02*
G03X1608115Y573847I0J-710D01*
G01X1608617Y575005D02*
G03X1607443Y574519I0J-1661D01*
G01X1608115Y573847D02*
X1604528Y570260D01*
G01X1607443Y574519D02*
X1603856Y570932D01*
G01X1604528Y570260D02*
G02X1603538Y569850I-990J990D01*
G01X1603856Y570932D02*
G02X1603538Y570800I-318J318D01*
G01Y569850D02*
X1602275D01*
G01X1603538Y570800D02*
X1602275D01*
G01X1612622Y556993D02*
X1613021D01*
G01X1613556Y557943D02*
X1612622D01*
G01X1611631Y557403D02*
G03X1612622Y556993I991J993D01*
G01Y557943D02*
G02X1612303Y558075I0J451D01*
G01X1610585Y558448D02*
X1611631Y557403D01*
G01X1612303Y558075D02*
X1611257Y559121D01*
G01X1610266Y558581D02*
G02X1610585Y558448I-1J-452D01*
G01X1611257Y559121D02*
G03X1610266Y559531I-991J-993D01*
G01X1607983Y558581D02*
X1610266D01*
G01Y559531D02*
X1609333D01*
G01X1607389Y580025D02*
X1606444D01*
G01X1607389Y580975D02*
X1606444D01*
G01X1625544Y557675D02*
X1626889D01*
G01X1625544Y556725D02*
X1626889D01*
G01X1616319Y575005D02*
X1608617D01*
G01X1616259Y574055D02*
X1608617D01*
G01Y575005D02*
G03X1607443Y574519I0J-1661D01*
G01X1608617Y574055D02*
G03X1608115Y573847I0J-710D01*
G01X1607443Y574519D02*
X1603856Y570932D01*
G01X1608115Y573847D02*
X1604528Y570260D01*
G01X1603856Y570932D02*
G02X1603538Y570800I-318J318D01*
G01X1604528Y570260D02*
G02X1603538Y569850I-990J990D01*
G01Y570800D02*
X1602275D01*
G01X1603538Y569850D02*
X1602275D01*
G01X1610266Y559531D02*
X1609333D01*
G01X1607983Y558581D02*
X1610266D01*
G01X1611257Y559121D02*
G03X1610266Y559531I-991J-993D01*
G01Y558581D02*
G02X1610585Y558448I-1J-452D01*
G01X1612303Y558075D02*
X1611257Y559121D01*
G01X1610585Y558448D02*
X1611631Y557403D01*
G01X1612622Y557943D02*
G02X1612303Y558075I0J451D01*
G01X1611631Y557403D02*
G03X1612622Y556993I991J993D01*
G01X1613556Y557943D02*
X1612622D01*
G01Y556993D02*
X1613021D01*
G01X1607389Y580975D02*
X1606444D01*
G01X1607389Y580025D02*
X1606444D01*
G01X1635386Y566538D02*
G02X1636405Y567084I168079J-312461D01*
G01X1635556Y567709D02*
G03X1634934Y567375I167989J-313588D01*
G01X1635231Y566454D02*
X1635386Y566538D01*
G01X1634931Y567373D02*
X1634778Y567290D01*
G01X1634938Y565962D02*
G02X1635231Y566454I560J0D01*
G01X1634778Y567290D02*
G03X1633988Y565962I720J-1327D01*
G01X1634938Y562945D02*
Y565962D01*
G01X1633988D02*
Y562944D01*
G01X1635070Y562627D02*
G02X1634938Y562945I318J318D01*
G01X1633988Y562944D02*
G03X1634398Y561955I1400J1D01*
G01X1635357Y562340D02*
X1635070Y562627D01*
G01X1634398Y561955D02*
X1634685Y561668D01*
G01X1635767Y561350D02*
G03X1635357Y562340I-1400J0D01*
G01X1634685Y561668D02*
G02X1634816Y561350I-319J-317D01*
G01X1635767Y558257D02*
Y561350D01*
G01X1634816D02*
Y560534D01*
G01X1635767Y558257D02*
Y561350D01*
G01X1634817Y560535D02*
Y558257D01*
G01X1634235Y556725D02*
G03X1635767Y558257I0J1532D01*
G01X1634817D02*
G02X1634235Y557675I-582J0D01*
G01X1633811Y556725D02*
X1634235D01*
G01Y557675D02*
X1633810D01*
G01X1634235D02*
X1633810D01*
G01X1633811Y556725D02*
X1634235D01*
G01X1634817Y558257D02*
G02X1634235Y557675I-582J0D01*
G01Y556725D02*
G03X1635767Y558257I0J1532D01*
G01X1634816Y561350D02*
Y560534D01*
G01X1634817Y560535D02*
Y558257D01*
G01X1635767D02*
Y561350D01*
G01X1634685Y561668D02*
G02X1634816Y561350I-319J-317D01*
G01X1635767D02*
G03X1635357Y562340I-1400J0D01*
G01X1634398Y561955D02*
X1634685Y561668D01*
G01X1635357Y562340D02*
X1635070Y562627D01*
G01X1633988Y562944D02*
G03X1634398Y561955I1400J1D01*
G01X1635070Y562627D02*
G02X1634938Y562945I318J318D01*
G01X1633988Y565962D02*
Y562944D01*
G01X1634938Y562945D02*
Y565962D01*
G01X1634778Y567290D02*
G03X1633988Y565962I720J-1327D01*
G01X1634938D02*
G02X1635231Y566454I560J0D01*
G01X1634931Y567373D02*
X1634778Y567290D01*
G01X1635231Y566454D02*
X1635386Y566538D01*
G01X1635556Y567709D02*
G03X1634934Y567375I167989J-313588D01*
G01X1635386Y566538D02*
G02X1636405Y567084I168079J-312461D01*
G01X1635910Y582022D02*
X1636247Y582203D01*
G01X1635801Y583043D02*
X1635797Y583041D01*
G01X1635910Y582022D02*
X1636247Y582203D01*
G01X1635797Y583040D02*
X1635462Y582860D01*
G01X1635804Y581944D02*
G02X1635910Y582022I317J-319D01*
G01X1635462Y582860D02*
G03X1635133Y582617I658J-1235D01*
G01X1635522Y581662D02*
X1635804Y581944D01*
G01X1635133Y582617D02*
X1634850Y582334D01*
G01X1635390Y581344D02*
G02X1635522Y581662I450J0D01*
G01X1634850Y582334D02*
G03X1634440Y581345I990J-990D01*
G01X1635390Y578726D02*
Y581344D01*
G01X1634440Y581345D02*
Y578725D01*
G01X1634980Y577736D02*
G03X1635390Y578726I-990J990D01*
G01X1634439D02*
G02X1634308Y578408I-450J-1D01*
G01X1631650Y574406D02*
X1634980Y577736D01*
G01X1634308Y578408D02*
X1630978Y575078D01*
G01X1630659Y573996D02*
G03X1631650Y574406I0J1403D01*
G01X1630978Y575078D02*
G02X1630659Y574946I-319J319D01*
G01X1623182Y573996D02*
X1630659D01*
G01Y574946D02*
X1627740D01*
G01X1623182Y573996D02*
X1630659D01*
G01X1624590Y574946D02*
X1623240D01*
G01X1630659D02*
X1627740D01*
G01X1624590D02*
X1623240D01*
G01X1623182Y573996D02*
X1630659D01*
G01X1630978Y575078D02*
G02X1630659Y574946I-319J319D01*
G01Y573996D02*
G03X1631650Y574406I0J1403D01*
G01X1634308Y578408D02*
X1630978Y575078D01*
G01X1631650Y574406D02*
X1634980Y577736D01*
G01X1634439Y578726D02*
G02X1634308Y578408I-450J-1D01*
G01X1634980Y577736D02*
G03X1635390Y578726I-990J990D01*
G01X1634440Y581345D02*
Y578725D01*
G01X1635390Y578726D02*
Y581344D01*
G01X1634850Y582334D02*
G03X1634440Y581345I990J-990D01*
G01X1635390Y581344D02*
G02X1635522Y581662I450J0D01*
G01X1635133Y582617D02*
X1634850Y582334D01*
G01X1635522Y581662D02*
X1635804Y581944D01*
G01X1635462Y582860D02*
G03X1635133Y582617I658J-1235D01*
G01X1635804Y581944D02*
G02X1635910Y582022I317J-319D01*
G01X1635801Y583043D02*
X1635797Y583041D01*
G01Y583040D02*
X1635462Y582860D01*
G01X1635910Y582022D02*
X1636247Y582203D01*
G01X1630659Y574946D02*
X1627740D01*
G01X1624590D02*
X1623240D01*
G01X1623182Y573996D02*
X1630659D01*
G01X1630978Y575078D02*
G02X1630659Y574946I-319J319D01*
G01Y573996D02*
G03X1631650Y574406I0J1403D01*
G01X1634308Y578408D02*
X1630978Y575078D01*
G01X1631650Y574406D02*
X1634980Y577736D01*
G01X1634439Y578726D02*
G02X1634308Y578408I-450J-1D01*
G01X1634980Y577736D02*
G03X1635390Y578726I-990J990D01*
G01X1634440Y581345D02*
Y578725D01*
G01X1635390Y578726D02*
Y581344D01*
G01X1634850Y582334D02*
G03X1634440Y581345I990J-990D01*
G01X1635390Y581344D02*
G02X1635522Y581662I450J0D01*
G01X1635133Y582617D02*
X1634850Y582334D01*
G01X1635522Y581662D02*
X1635804Y581944D01*
G01X1635462Y582860D02*
G03X1635133Y582617I658J-1235D01*
G01X1635804Y581944D02*
G02X1635910Y582022I317J-319D01*
G01X1635801Y583043D02*
X1635797Y583041D01*
G01Y583040D02*
X1635462Y582860D01*
G01X1635910Y582022D02*
X1636247Y582203D01*
G01X1626545Y566584D02*
X1627477Y567082D01*
G01X1627005Y567909D02*
X1625972Y567355D01*
G01X1622378Y562415D02*
X1626545Y566584D01*
G01X1625972Y567355D02*
X1621706Y563087D01*
G01X1622246Y562097D02*
G02X1622378Y562415I450J0D01*
G01X1621706Y563087D02*
G03X1621296Y562098I990J-990D01*
G01X1622246Y558142D02*
Y562097D01*
G01X1621296Y562098D02*
Y558142D01*
G01X1620846Y556742D02*
G03X1622246Y558142I0J1400D01*
G01X1621296D02*
G02X1620846Y557692I-450J0D01*
G01X1620228Y556742D02*
X1620846D01*
G01Y557692D02*
X1620194D01*
G01X1620846D02*
X1620194D01*
G01X1620228Y556742D02*
X1620846D01*
G01X1621296Y558142D02*
G02X1620846Y557692I-450J0D01*
G01Y556742D02*
G03X1622246Y558142I0J1400D01*
G01X1621296Y562098D02*
Y558142D01*
G01X1622246D02*
Y562097D01*
G01X1621706Y563087D02*
G03X1621296Y562098I990J-990D01*
G01X1622246Y562097D02*
G02X1622378Y562415I450J0D01*
G01X1625972Y567355D02*
X1621706Y563087D01*
G01X1622378Y562415D02*
X1626545Y566584D01*
G01X1627005Y567909D02*
X1625972Y567355D01*
G01X1626545Y566584D02*
X1627477Y567082D01*
G01X1614311Y580025D02*
X1619953D01*
G01X1614311Y580975D02*
X1615661D01*
G01X1614311Y580025D02*
X1619953D01*
G01X1618811Y580975D02*
X1619954D01*
G01X1619953Y580025D02*
G02X1620271Y579893I0J-450D01*
G01X1619954Y580975D02*
G02X1620943Y580565I-1J-1400D01*
G01X1620271Y579893D02*
X1620653Y579511D01*
G01X1620943Y580565D02*
X1621325Y580183D01*
G01X1620271Y579893D02*
X1620653Y579511D01*
G01X1621325Y580183D02*
X1621326D01*
G01X1620653Y579511D02*
G03X1621835Y579021I1182J1181D01*
G01X1621326Y580183D02*
G03X1621835Y579971I510J508D01*
G01Y579021D02*
X1623443D01*
G01X1621835Y579971D02*
X1623442D01*
G01X1623443Y579021D02*
G03X1624434Y579432I-1J1402D01*
G01X1623442Y579971D02*
G03X1623762Y580104I0J452D01*
G01X1624434Y579432D02*
X1626946Y581944D01*
G01X1623762Y580104D02*
X1626273Y582616D01*
G01X1626946Y581944D02*
G02X1627052Y582023I319J-318D01*
G01X1626273Y582616D02*
G02X1626604Y582862I992J-989D01*
G01X1627052Y582023D02*
X1627387Y582201D01*
G01D02*
X1627391Y582203D01*
G01X1626604Y582862D02*
X1626941Y583041D01*
G01X1627052Y582023D02*
X1627387Y582201D01*
G01D02*
X1627391Y582203D01*
G01X1626941Y583041D02*
X1626942D01*
G01X1614311Y580975D02*
X1615661D01*
G01X1618811D02*
X1619954D01*
G01X1614311Y580025D02*
X1619953D01*
G01X1619954Y580975D02*
G02X1620943Y580565I-1J-1400D01*
G01X1619953Y580025D02*
G02X1620271Y579893I0J-450D01*
G01X1620943Y580565D02*
X1621325Y580183D01*
G01D02*
X1621326D01*
G01X1620271Y579893D02*
X1620653Y579511D01*
G01X1621326Y580183D02*
G03X1621835Y579971I510J508D01*
G01X1620653Y579511D02*
G03X1621835Y579021I1182J1181D01*
G01Y579971D02*
X1623442D01*
G01X1621835Y579021D02*
X1623443D01*
G01X1623442Y579971D02*
G03X1623762Y580104I0J452D01*
G01X1623443Y579021D02*
G03X1624434Y579432I-1J1402D01*
G01X1623762Y580104D02*
X1626273Y582616D01*
G01X1624434Y579432D02*
X1626946Y581944D01*
G01X1626273Y582616D02*
G02X1626604Y582862I992J-989D01*
G01X1626946Y581944D02*
G02X1627052Y582023I319J-318D01*
G01X1626604Y582862D02*
X1626941Y583041D01*
G01D02*
X1626942D01*
G01X1627052Y582023D02*
X1627387Y582201D01*
G01X1626604Y582862D02*
X1626941Y583041D01*
G01D02*
X1626942D01*
G01X1627387Y582201D02*
X1627391Y582203D01*
G01X1615195Y587685D02*
X1612969D01*
G01X1615195D02*
X1612969D01*
G01X1620971Y589095D02*
X1623592D01*
G01X1620951Y588145D02*
X1623593D01*
G01X1623592Y589095D02*
G03X1623935Y589237I0J484D01*
G01X1623593Y588145D02*
G03X1624607Y588565I0J1434D01*
G01X1623935Y589237D02*
X1624075Y589377D01*
G01X1624607Y588565D02*
X1624747Y588705D01*
G01X1624075Y589377D02*
G02X1625066Y589788I992J-991D01*
G01X1624747Y588705D02*
G02X1625067Y588838I320J-319D01*
G01X1625066Y589788D02*
X1629149D01*
G01X1625067Y588838D02*
X1629149D01*
G01Y589788D02*
G03X1629468Y589920I0J451D01*
G01X1629149Y588838D02*
G03X1630140Y589248I0J1403D01*
G01X1629468Y589920D02*
X1630423Y590875D01*
G01X1632650Y593102D02*
X1634351Y594803D01*
G01X1630140Y589248D02*
X1635024Y594131D01*
G01X1634351Y594803D02*
G03X1634482Y595121I-319J317D01*
G01X1635024Y594131D02*
G03X1635433Y595121I-991J989D01*
G01X1634483Y595120D02*
Y596348D01*
G01X1635433Y595121D02*
Y596347D01*
G01X1634483Y596348D02*
G02X1634893Y597337I1400J-1D01*
G01X1635433Y596347D02*
G02X1635565Y596665I450J0D01*
G01X1634893Y597337D02*
X1635133Y597577D01*
G01X1635565Y596665D02*
X1635804Y596904D01*
G01X1635133Y597577D02*
G02X1635462Y597820I987J-992D01*
G01X1635804Y596904D02*
G02X1635910Y596982I317J-319D01*
G01X1635462Y597820D02*
X1635797Y598000D01*
G01Y598001D02*
X1635801Y598003D01*
G01X1635910Y596982D02*
X1636247Y597163D01*
G01X1614255Y588635D02*
X1612969D01*
G01X1614255D02*
X1612969D01*
G01X1614538Y600775D02*
X1613799D01*
G01Y601725D02*
X1614538D01*
G01X1614545Y600775D02*
G02X1614538I-4J1402D01*
G01Y601725D02*
G03X1614754Y601780I0J452D01*
G01X1606039Y594275D02*
X1604369D01*
G01Y595225D02*
X1606039D01*
G01X1604792Y605975D02*
X1604319D01*
G01X1604792Y606925D02*
X1604319D01*
G01X1620951Y588145D02*
X1623593D01*
G01X1620971Y589095D02*
X1623592D01*
G01X1623593Y588145D02*
G03X1624607Y588565I0J1434D01*
G01X1623592Y589095D02*
G03X1623935Y589237I0J484D01*
G01X1624607Y588565D02*
X1624747Y588705D01*
G01X1623935Y589237D02*
X1624075Y589377D01*
G01X1624747Y588705D02*
G02X1625067Y588838I320J-319D01*
G01X1624075Y589377D02*
G02X1625066Y589788I992J-991D01*
G01X1625067Y588838D02*
X1629149D01*
G01X1625066Y589788D02*
X1629149D01*
G01Y588838D02*
G03X1630140Y589248I0J1403D01*
G01X1629149Y589788D02*
G03X1629468Y589920I0J451D01*
G01X1630140Y589248D02*
X1635024Y594131D01*
G01X1629468Y589920D02*
X1630423Y590875D01*
G01X1630140Y589248D02*
X1635024Y594131D01*
G01X1632650Y593102D02*
X1634351Y594803D01*
G01X1635024Y594131D02*
G03X1635433Y595121I-991J989D01*
G01X1634351Y594803D02*
G03X1634482Y595121I-319J317D01*
G01X1635433D02*
Y596347D01*
G01X1634483Y595120D02*
Y596348D01*
G01X1635433Y596347D02*
G02X1635565Y596665I450J0D01*
G01X1634483Y596348D02*
G02X1634893Y597337I1400J-1D01*
G01X1635565Y596665D02*
X1635804Y596904D01*
G01X1634893Y597337D02*
X1635133Y597577D01*
G01X1635804Y596904D02*
G02X1635910Y596982I317J-319D01*
G01X1635133Y597577D02*
G02X1635462Y597820I987J-992D01*
G01X1635910Y596982D02*
X1636247Y597163D01*
G01X1635462Y597820D02*
X1635797Y598000D01*
G01X1635910Y596982D02*
X1636247Y597163D01*
G01X1635797Y598001D02*
X1635801Y598003D01*
G01X1620971Y589095D02*
X1623592D01*
G01X1620951Y588145D02*
X1623593D01*
G01X1623592Y589095D02*
G03X1623935Y589237I0J484D01*
G01X1623593Y588145D02*
G03X1624607Y588565I0J1434D01*
G01X1623935Y589237D02*
X1624075Y589377D01*
G01X1624607Y588565D02*
X1624747Y588705D01*
G01X1624075Y589377D02*
G02X1625066Y589788I992J-991D01*
G01X1624747Y588705D02*
G02X1625067Y588838I320J-319D01*
G01X1625066Y589788D02*
X1629149D01*
G01X1625067Y588838D02*
X1629149D01*
G01Y589788D02*
G03X1629468Y589920I0J451D01*
G01X1629149Y588838D02*
G03X1630140Y589248I0J1403D01*
G01X1629468Y589920D02*
X1630423Y590875D01*
G01X1632650Y593102D02*
X1634351Y594803D01*
G01X1630140Y589248D02*
X1635024Y594131D01*
G01X1634351Y594803D02*
G03X1634482Y595121I-319J317D01*
G01X1635024Y594131D02*
G03X1635433Y595121I-991J989D01*
G01X1634483Y595120D02*
Y596348D01*
G01X1635433Y595121D02*
Y596347D01*
G01X1634483Y596348D02*
G02X1634893Y597337I1400J-1D01*
G01X1635433Y596347D02*
G02X1635565Y596665I450J0D01*
G01X1634893Y597337D02*
X1635133Y597577D01*
G01X1635565Y596665D02*
X1635804Y596904D01*
G01X1635133Y597577D02*
G02X1635462Y597820I987J-992D01*
G01X1635804Y596904D02*
G02X1635910Y596982I317J-319D01*
G01X1635462Y597820D02*
X1635797Y598000D01*
G01Y598001D02*
X1635801Y598003D01*
G01X1635910Y596982D02*
X1636247Y597163D01*
G01X1620961Y600775D02*
X1621477D01*
G01X1620961Y601725D02*
X1621476D01*
G01X1621477Y600775D02*
G03X1622468Y601186I-1J1402D01*
G01X1621476Y601725D02*
G03X1621796Y601858I0J452D01*
G01X1622468Y601186D02*
X1626196Y604914D01*
G01X1621796Y601858D02*
X1625524Y605586D01*
G01X1626196Y604914D02*
G02X1626514Y605046I318J-318D01*
G01X1625524Y605586D02*
G02X1626513Y605996I990J-990D01*
G01X1626514Y605046D02*
X1629913D01*
G01X1626513Y605996D02*
X1629914D01*
G01X1629913Y605046D02*
G03X1630903Y605456I0J1400D01*
G01X1629914Y605996D02*
G03X1630231Y606128I-1J450D01*
G01X1630903Y605456D02*
X1633431Y607984D01*
G01X1630231Y606128D02*
X1632759Y608656D01*
G01X1633431Y607984D02*
G03X1633841Y608974I-990J990D01*
G01X1632759Y608656D02*
G03X1632890Y608974I-319J317D01*
G01X1633841D02*
Y609716D01*
G01X1632891Y608973D02*
Y609717D01*
G01X1633841Y609716D02*
G02X1633973Y610034I450J0D01*
G01X1632891Y609717D02*
G02X1633301Y610706I1400J-1D01*
G01X1633973Y610034D02*
X1635804Y611865D01*
G01X1633301Y610706D02*
X1635133Y612538D01*
G01X1635804Y611865D02*
G02X1635910Y611943I317J-319D01*
G01X1635133Y612538D02*
G02X1635462Y612781I987J-992D01*
G01X1635910Y611943D02*
X1636247Y612124D01*
G01X1635462Y612781D02*
X1635797Y612961D01*
G01X1635910Y611943D02*
X1636247Y612124D01*
G01X1635797Y612962D02*
X1635801Y612964D01*
G01X1620961Y601725D02*
X1621476D01*
G01X1620961Y600775D02*
X1621477D01*
G01X1621476Y601725D02*
G03X1621796Y601858I0J452D01*
G01X1621477Y600775D02*
G03X1622468Y601186I-1J1402D01*
G01X1621796Y601858D02*
X1625524Y605586D01*
G01X1622468Y601186D02*
X1626196Y604914D01*
G01X1625524Y605586D02*
G02X1626513Y605996I990J-990D01*
G01X1626196Y604914D02*
G02X1626514Y605046I318J-318D01*
G01X1626513Y605996D02*
X1629914D01*
G01X1626514Y605046D02*
X1629913D01*
G01X1629914Y605996D02*
G03X1630231Y606128I-1J450D01*
G01X1629913Y605046D02*
G03X1630903Y605456I0J1400D01*
G01X1630231Y606128D02*
X1632759Y608656D01*
G01X1630903Y605456D02*
X1633431Y607984D01*
G01X1632759Y608656D02*
G03X1632890Y608974I-319J317D01*
G01X1633431Y607984D02*
G03X1633841Y608974I-990J990D01*
G01X1632891Y608973D02*
Y609717D01*
G01X1633841Y608974D02*
Y609716D01*
G01X1632891Y609717D02*
G02X1633301Y610706I1400J-1D01*
G01X1633841Y609716D02*
G02X1633973Y610034I450J0D01*
G01X1633301Y610706D02*
X1635133Y612538D01*
G01X1633973Y610034D02*
X1635804Y611865D01*
G01X1635133Y612538D02*
G02X1635462Y612781I987J-992D01*
G01X1635804Y611865D02*
G02X1635910Y611943I317J-319D01*
G01X1635462Y612781D02*
X1635797Y612961D01*
G01Y612962D02*
X1635801Y612964D01*
G01X1635910Y611943D02*
X1636247Y612124D01*
G01X1620961Y601725D02*
X1621476D01*
G01X1620961Y600775D02*
X1621477D01*
G01X1621476Y601725D02*
G03X1621796Y601858I0J452D01*
G01X1621477Y600775D02*
G03X1622468Y601186I-1J1402D01*
G01X1621796Y601858D02*
X1625524Y605586D01*
G01X1622468Y601186D02*
X1626196Y604914D01*
G01X1625524Y605586D02*
G02X1626513Y605996I990J-990D01*
G01X1626196Y604914D02*
G02X1626514Y605046I318J-318D01*
G01X1626513Y605996D02*
X1629914D01*
G01X1626514Y605046D02*
X1629913D01*
G01X1629914Y605996D02*
G03X1630231Y606128I-1J450D01*
G01X1629913Y605046D02*
G03X1630903Y605456I0J1400D01*
G01X1630231Y606128D02*
X1632759Y608656D01*
G01X1630903Y605456D02*
X1633431Y607984D01*
G01X1632759Y608656D02*
G03X1632890Y608974I-319J317D01*
G01X1633431Y607984D02*
G03X1633841Y608974I-990J990D01*
G01X1632891Y608973D02*
Y609717D01*
G01X1633841Y608974D02*
Y609716D01*
G01X1632891Y609717D02*
G02X1633301Y610706I1400J-1D01*
G01X1633841Y609716D02*
G02X1633973Y610034I450J0D01*
G01X1633301Y610706D02*
X1635133Y612538D01*
G01X1633973Y610034D02*
X1635804Y611865D01*
G01X1635133Y612538D02*
G02X1635462Y612781I987J-992D01*
G01X1635804Y611865D02*
G02X1635910Y611943I317J-319D01*
G01X1635462Y612781D02*
X1635797Y612961D01*
G01Y612962D02*
X1635801Y612964D01*
G01X1635910Y611943D02*
X1636247Y612124D01*
G01X1612337Y594150D02*
X1623540D01*
G01X1612756Y595100D02*
X1619040D01*
G01X1612337Y594150D02*
X1623540D01*
G01X1622190Y595100D02*
X1623540D01*
G01Y594150D02*
G03X1624654Y594611I1J1573D01*
G01X1623540Y595100D02*
G03X1623981Y595283I0J623D01*
G01X1624654Y594611D02*
X1626943Y596902D01*
G01X1623981Y595283D02*
X1626271Y597574D01*
G01X1626945Y596903D02*
G02X1627052Y596983I320J-317D01*
G01X1626271Y597574D02*
G02X1626605Y597822I993J-989D01*
G01X1627052Y596983D02*
X1627388Y597161D01*
G01X1626605Y597822D02*
X1626941Y598001D01*
G01X1627052Y596983D02*
X1627388Y597161D01*
G01X1626941Y598001D02*
X1626942D01*
G01X1612756Y595100D02*
X1619040D01*
G01X1622190D02*
X1623540D01*
G01X1612337Y594150D02*
X1623540D01*
G01Y595100D02*
G03X1623981Y595283I0J623D01*
G01X1623540Y594150D02*
G03X1624654Y594611I1J1573D01*
G01X1623981Y595283D02*
X1626271Y597574D01*
G01X1624654Y594611D02*
X1626943Y596902D01*
G01X1626271Y597574D02*
G02X1626605Y597822I993J-989D01*
G01X1626945Y596903D02*
G02X1627052Y596983I320J-317D01*
G01X1626605Y597822D02*
X1626941Y598001D01*
G01D02*
X1626942D01*
G01X1627052Y596983D02*
X1627388Y597161D01*
G01X1627391Y612124D02*
X1627387Y612122D01*
G01D02*
X1627052Y611944D01*
G01X1626942Y612962D02*
X1626941D01*
G01X1627391Y612124D02*
X1627387Y612122D01*
G01D02*
X1627052Y611944D01*
G01X1626941Y612962D02*
X1626604Y612783D01*
G01X1627052Y611944D02*
G03X1626946Y611865I213J-397D01*
G01X1626604Y612783D02*
G03X1626273Y612537I661J-1235D01*
G01X1626946Y611865D02*
X1623991Y608910D01*
G01X1626273Y612537D02*
X1623319Y609582D01*
G01X1623991Y608910D02*
G02X1623001Y608500I-990J990D01*
G01X1623319Y609582D02*
G02X1623002Y609450I-318J318D01*
G01X1623001Y608500D02*
X1616135D01*
G01X1623002Y609450D02*
X1620636D01*
G01X1623001Y608500D02*
X1616135D01*
G01X1617486Y609450D02*
X1616136D01*
G01X1616135Y608500D02*
G03X1615818Y608368I1J-450D01*
G01X1616136Y609450D02*
G03X1615146Y609040I0J-1400D01*
G01X1615818Y608368D02*
X1613757Y606307D01*
G01X1615146Y609040D02*
X1613085Y606979D01*
G01X1613757Y606307D02*
G02X1612768Y605897I-990J990D01*
G01X1613085Y606979D02*
G02X1612767Y606847I-318J318D01*
G01X1612768Y605897D02*
X1611783D01*
G01X1612767Y606847D02*
X1611939D01*
G01X1626942Y612962D02*
X1626941D01*
G01D02*
X1626604Y612783D01*
G01X1627391Y612124D02*
X1627387Y612122D01*
G01X1626942Y612962D02*
X1626941D01*
G01D02*
X1626604Y612783D01*
G01X1627387Y612122D02*
X1627052Y611944D01*
G01X1626604Y612783D02*
G03X1626273Y612537I661J-1235D01*
G01X1627052Y611944D02*
G03X1626946Y611865I213J-397D01*
G01X1626273Y612537D02*
X1623319Y609582D01*
G01X1626946Y611865D02*
X1623991Y608910D01*
G01X1623319Y609582D02*
G02X1623002Y609450I-318J318D01*
G01X1623991Y608910D02*
G02X1623001Y608500I-990J990D01*
G01X1623002Y609450D02*
X1620636D01*
G01X1617486D02*
X1616136D01*
G01X1623001Y608500D02*
X1616135D01*
G01X1616136Y609450D02*
G03X1615146Y609040I0J-1400D01*
G01X1616135Y608500D02*
G03X1615818Y608368I1J-450D01*
G01X1615146Y609040D02*
X1613085Y606979D01*
G01X1615818Y608368D02*
X1613757Y606307D01*
G01X1613085Y606979D02*
G02X1612767Y606847I-318J318D01*
G01X1613757Y606307D02*
G02X1612768Y605897I-990J990D01*
G01X1612767Y606847D02*
X1611939D01*
G01X1612768Y605897D02*
X1611783D01*
G01X1614538Y601725D02*
G03X1614754Y601780I0J452D01*
G01X1614545Y600775D02*
G02X1614538I-4J1402D01*
G01X1613799Y601725D02*
X1614538D01*
G01Y600775D02*
X1613799D01*
G01X1604369Y595225D02*
X1606039D01*
G01Y594275D02*
X1604369D01*
G01X1604792Y606925D02*
X1604319D01*
G01X1604792Y605975D02*
X1604319D01*
G01X1653125Y541120D02*
X1653518Y540667D01*
G01X1652428Y540472D02*
X1652799Y540044D01*
G01X1653518Y540667D02*
G02X1654031Y539854I-2420J-2095D01*
G01D02*
G02X1654300Y538569I-2932J-1284D01*
G01X1652799Y540044D02*
G02X1653160Y539473I-1700J-1474D01*
G01X1653518Y540667D02*
G02X1654031Y539854I-2420J-2095D01*
G01D02*
G02X1654300Y538569I-2932J-1284D01*
G01X1653160Y539473D02*
G02X1653349Y538569I-2061J-903D01*
G01X1654300D02*
Y532291D01*
G01X1653350Y538570D02*
Y532291D01*
G01X1654300D02*
G03X1655019Y531572I719J0D01*
G01X1653350Y532291D02*
G03X1655019Y530622I1669J0D01*
G01Y531572D02*
X1667392D01*
G01X1655019Y530622D02*
X1667392D01*
G01Y531572D02*
G03X1668590Y532068I0J1695D01*
G01X1667392Y530622D02*
G03X1669262Y531396I0J2646D01*
G01X1668590Y532068D02*
X1674047Y537525D01*
G01X1669262Y531396D02*
X1674719Y536853D01*
G01X1674047Y537525D02*
G02X1675838Y538267I1791J-1791D01*
G01X1674719Y536853D02*
G02X1675838Y537317I1119J-1117D01*
G01Y538267D02*
X1679486D01*
G01X1675838Y537317D02*
X1679487D01*
G01X1679486Y538267D02*
G03X1679855Y538420I0J521D01*
G01X1679487Y537317D02*
G03X1680527Y537748I-1J1472D01*
G01X1679855Y538420D02*
X1683966Y542532D01*
G01X1680527Y537748D02*
X1682387Y539609D01*
G01X1683966Y542533D02*
X1688077Y546646D01*
G01X1684615Y541836D02*
X1685569Y542791D01*
G01X1683966Y542533D02*
X1688077Y546646D01*
G01X1687796Y545019D02*
X1688750Y545974D01*
G01X1688077Y546646D02*
G03X1688210Y546965I-319J320D01*
G01X1688750Y545974D02*
G03X1689160Y546965I-993J991D01*
G01X1688210D02*
Y559834D01*
G01X1689160Y546965D02*
Y559834D01*
G01X1688210D02*
G02X1691026Y562650I2816J0D01*
G01X1689160Y559834D02*
G02X1691026Y561700I1866J0D01*
G01Y562650D02*
X1702220D01*
G01X1691026Y561700D02*
X1696876D01*
G01X1691026Y562650D02*
X1702220D01*
G01X1700026Y561700D02*
X1702219D01*
G01X1702220Y562650D02*
G02X1703542Y562102I-1J-1871D01*
G01X1702219Y561700D02*
G02X1702870Y561430I0J-921D01*
G01X1703542Y562102D02*
X1703812Y561832D01*
G01X1702870Y561430D02*
X1703140Y561160D01*
G01X1703812Y561832D02*
G03X1704131Y561700I319J319D01*
G01X1703140Y561160D02*
G03X1704131Y560750I991J993D01*
G01Y561700D02*
X1710696D01*
G01X1704131Y560750D02*
X1710696D01*
G01Y561700D02*
G02X1711972Y561172I1J-1804D01*
G01X1710696Y560750D02*
G02X1711300Y560500I0J-854D01*
G01X1711972Y561172D02*
G02X1712450Y560016I-1155J-1154D01*
G01X1711300Y560500D02*
G02X1711500Y560017I-483J-483D01*
G01X1652428Y540472D02*
X1652799Y540044D01*
G01X1653125Y541120D02*
X1653518Y540667D01*
G01X1652799Y540044D02*
G02X1653160Y539473I-1700J-1474D01*
G01D02*
G02X1653349Y538569I-2061J-903D01*
G01X1653518Y540667D02*
G02X1654031Y539854I-2420J-2095D01*
G01X1652799Y540044D02*
G02X1653160Y539473I-1700J-1474D01*
G01D02*
G02X1653349Y538569I-2061J-903D01*
G01X1654031Y539854D02*
G02X1654300Y538569I-2932J-1284D01*
G01X1653350Y538570D02*
Y532291D01*
G01X1654300Y538569D02*
Y532291D01*
G01X1653350D02*
G03X1655019Y530622I1669J0D01*
G01X1654300Y532291D02*
G03X1655019Y531572I719J0D01*
G01Y530622D02*
X1667392D01*
G01X1655019Y531572D02*
X1667392D01*
G01Y530622D02*
G03X1669262Y531396I0J2646D01*
G01X1667392Y531572D02*
G03X1668590Y532068I0J1695D01*
G01X1669262Y531396D02*
X1674719Y536853D01*
G01X1668590Y532068D02*
X1674047Y537525D01*
G01X1674719Y536853D02*
G02X1675838Y537317I1119J-1117D01*
G01X1674047Y537525D02*
G02X1675838Y538267I1791J-1791D01*
G01Y537317D02*
X1679487D01*
G01X1675838Y538267D02*
X1679486D01*
G01X1679487Y537317D02*
G03X1680527Y537748I-1J1472D01*
G01X1679486Y538267D02*
G03X1679855Y538420I0J521D01*
G01X1680527Y537748D02*
X1682387Y539609D01*
G01X1679855Y538420D02*
X1683966Y542532D01*
G01X1684615Y541836D02*
X1685569Y542791D01*
G01X1687796Y545019D02*
X1688750Y545974D01*
G01X1683966Y542533D02*
X1688077Y546646D01*
G01X1688750Y545974D02*
G03X1689160Y546965I-993J991D01*
G01X1688077Y546646D02*
G03X1688210Y546965I-319J320D01*
G01X1689160D02*
Y559834D01*
G01X1688210Y546965D02*
Y559834D01*
G01X1689160D02*
G02X1691026Y561700I1866J0D01*
G01X1688210Y559834D02*
G02X1691026Y562650I2816J0D01*
G01Y561700D02*
X1696876D01*
G01X1700026D02*
X1702219D01*
G01X1691026Y562650D02*
X1702220D01*
G01X1702219Y561700D02*
G02X1702870Y561430I0J-921D01*
G01X1702220Y562650D02*
G02X1703542Y562102I-1J-1871D01*
G01X1702870Y561430D02*
X1703140Y561160D01*
G01X1703542Y562102D02*
X1703812Y561832D01*
G01X1703140Y561160D02*
G03X1704131Y560750I991J993D01*
G01X1703812Y561832D02*
G03X1704131Y561700I319J319D01*
G01Y560750D02*
X1710696D01*
G01X1704131Y561700D02*
X1710696D01*
G01Y560750D02*
G02X1711300Y560500I0J-854D01*
G01X1710696Y561700D02*
G02X1711972Y561172I1J-1804D01*
G01X1711300Y560500D02*
G02X1711500Y560017I-483J-483D01*
G01X1711972Y561172D02*
G02X1712450Y560016I-1155J-1154D01*
G01X1653125Y541120D02*
X1653518Y540667D01*
G01X1652428Y540472D02*
X1652799Y540044D01*
G01X1653518Y540667D02*
G02X1654031Y539854I-2420J-2095D01*
G01D02*
G02X1654300Y538569I-2932J-1284D01*
G01X1652799Y540044D02*
G02X1653160Y539473I-1700J-1474D01*
G01X1653518Y540667D02*
G02X1654031Y539854I-2420J-2095D01*
G01D02*
G02X1654300Y538569I-2932J-1284D01*
G01X1653160Y539473D02*
G02X1653349Y538569I-2061J-903D01*
G01X1654300D02*
Y532291D01*
G01X1653350Y538570D02*
Y532291D01*
G01X1654300D02*
G03X1655019Y531572I719J0D01*
G01X1653350Y532291D02*
G03X1655019Y530622I1669J0D01*
G01Y531572D02*
X1667392D01*
G01X1655019Y530622D02*
X1667392D01*
G01Y531572D02*
G03X1668590Y532068I0J1695D01*
G01X1667392Y530622D02*
G03X1669262Y531396I0J2646D01*
G01X1668590Y532068D02*
X1674047Y537525D01*
G01X1669262Y531396D02*
X1674719Y536853D01*
G01X1674047Y537525D02*
G02X1675838Y538267I1791J-1791D01*
G01X1674719Y536853D02*
G02X1675838Y537317I1119J-1117D01*
G01Y538267D02*
X1679486D01*
G01X1675838Y537317D02*
X1679487D01*
G01X1679486Y538267D02*
G03X1679855Y538420I0J521D01*
G01X1679487Y537317D02*
G03X1680527Y537748I-1J1472D01*
G01X1679855Y538420D02*
X1683966Y542532D01*
G01X1680527Y537748D02*
X1682387Y539609D01*
G01X1683966Y542533D02*
X1688077Y546646D01*
G01X1684615Y541836D02*
X1685569Y542791D01*
G01X1683966Y542533D02*
X1688077Y546646D01*
G01X1687796Y545019D02*
X1688750Y545974D01*
G01X1688077Y546646D02*
G03X1688210Y546965I-319J320D01*
G01X1688750Y545974D02*
G03X1689160Y546965I-993J991D01*
G01X1688210D02*
Y559834D01*
G01X1689160Y546965D02*
Y559834D01*
G01X1688210D02*
G02X1691026Y562650I2816J0D01*
G01X1689160Y559834D02*
G02X1691026Y561700I1866J0D01*
G01Y562650D02*
X1702220D01*
G01X1691026Y561700D02*
X1696876D01*
G01X1691026Y562650D02*
X1702220D01*
G01X1700026Y561700D02*
X1702219D01*
G01X1702220Y562650D02*
G02X1703542Y562102I-1J-1871D01*
G01X1702219Y561700D02*
G02X1702870Y561430I0J-921D01*
G01X1703542Y562102D02*
X1703812Y561832D01*
G01X1702870Y561430D02*
X1703140Y561160D01*
G01X1703812Y561832D02*
G03X1704131Y561700I319J319D01*
G01X1703140Y561160D02*
G03X1704131Y560750I991J993D01*
G01Y561700D02*
X1710696D01*
G01X1704131Y560750D02*
X1710696D01*
G01Y561700D02*
G02X1711972Y561172I1J-1804D01*
G01X1710696Y560750D02*
G02X1711300Y560500I0J-854D01*
G01X1711972Y561172D02*
G02X1712450Y560016I-1155J-1154D01*
G01X1711300Y560500D02*
G02X1711500Y560017I-483J-483D01*
G01X1652428Y540472D02*
X1652799Y540044D01*
G01X1653125Y541120D02*
X1653518Y540667D01*
G01X1652799Y540044D02*
G02X1653160Y539473I-1700J-1474D01*
G01D02*
G02X1653349Y538569I-2061J-903D01*
G01X1653518Y540667D02*
G02X1654031Y539854I-2420J-2095D01*
G01X1652799Y540044D02*
G02X1653160Y539473I-1700J-1474D01*
G01D02*
G02X1653349Y538569I-2061J-903D01*
G01X1654031Y539854D02*
G02X1654300Y538569I-2932J-1284D01*
G01X1653350Y538570D02*
Y532291D01*
G01X1654300Y538569D02*
Y532291D01*
G01X1653350D02*
G03X1655019Y530622I1669J0D01*
G01X1654300Y532291D02*
G03X1655019Y531572I719J0D01*
G01Y530622D02*
X1667392D01*
G01X1655019Y531572D02*
X1667392D01*
G01Y530622D02*
G03X1669262Y531396I0J2646D01*
G01X1667392Y531572D02*
G03X1668590Y532068I0J1695D01*
G01X1669262Y531396D02*
X1674719Y536853D01*
G01X1668590Y532068D02*
X1674047Y537525D01*
G01X1674719Y536853D02*
G02X1675838Y537317I1119J-1117D01*
G01X1674047Y537525D02*
G02X1675838Y538267I1791J-1791D01*
G01Y537317D02*
X1679487D01*
G01X1675838Y538267D02*
X1679486D01*
G01X1679487Y537317D02*
G03X1680527Y537748I-1J1472D01*
G01X1679486Y538267D02*
G03X1679855Y538420I0J521D01*
G01X1680527Y537748D02*
X1682387Y539609D01*
G01X1679855Y538420D02*
X1683966Y542532D01*
G01X1684615Y541836D02*
X1685569Y542791D01*
G01X1687796Y545019D02*
X1688750Y545974D01*
G01X1683966Y542533D02*
X1688077Y546646D01*
G01X1688750Y545974D02*
G03X1689160Y546965I-993J991D01*
G01X1688077Y546646D02*
G03X1688210Y546965I-319J320D01*
G01X1689160D02*
Y559834D01*
G01X1688210Y546965D02*
Y559834D01*
G01X1689160D02*
G02X1691026Y561700I1866J0D01*
G01X1688210Y559834D02*
G02X1691026Y562650I2816J0D01*
G01Y561700D02*
X1696876D01*
G01X1700026D02*
X1702219D01*
G01X1691026Y562650D02*
X1702220D01*
G01X1702219Y561700D02*
G02X1702870Y561430I0J-921D01*
G01X1702220Y562650D02*
G02X1703542Y562102I-1J-1871D01*
G01X1702870Y561430D02*
X1703140Y561160D01*
G01X1703542Y562102D02*
X1703812Y561832D01*
G01X1703140Y561160D02*
G03X1704131Y560750I991J993D01*
G01X1703812Y561832D02*
G03X1704131Y561700I319J319D01*
G01Y560750D02*
X1710696D01*
G01X1704131Y561700D02*
X1710696D01*
G01Y560750D02*
G02X1711300Y560500I0J-854D01*
G01X1710696Y561700D02*
G02X1711972Y561172I1J-1804D01*
G01X1711300Y560500D02*
G02X1711500Y560017I-483J-483D01*
G01X1711972Y561172D02*
G02X1712450Y560016I-1155J-1154D01*
G01X1711626Y553417D02*
Y543229D01*
G01X1711625Y543230D02*
G02X1711494Y542912I-450J-1D01*
G01X1712576Y543230D02*
G02X1712166Y542240I-1400J0D01*
G01X1711494Y542912D02*
X1709640Y541058D01*
G01X1712166Y542240D02*
X1710312Y540386D01*
G01X1709640Y541058D02*
G03X1709230Y540069I990J-990D01*
G01X1710312Y540386D02*
G03X1710180Y540068I318J-318D01*
G01X1709230Y540069D02*
Y539002D01*
G01X1710180Y540068D02*
Y539002D01*
G01X1711626Y553417D02*
Y543229D01*
G01X1712576Y543230D02*
G02X1712166Y542240I-1400J0D01*
G01X1711625Y543230D02*
G02X1711494Y542912I-450J-1D01*
G01X1712166Y542240D02*
X1710312Y540386D01*
G01X1711494Y542912D02*
X1709640Y541058D01*
G01X1710312Y540386D02*
G03X1710180Y540068I318J-318D01*
G01X1709640Y541058D02*
G03X1709230Y540069I990J-990D01*
G01X1710180Y540068D02*
Y539002D01*
G01X1709230Y540069D02*
Y539002D01*
G01X1694306Y557787D02*
X1695043D01*
G01X1694753Y556837D02*
X1694306D01*
G01X1692109Y555590D02*
G02X1694306Y557787I2197J0D01*
G01Y556837D02*
G03X1693059Y555590I0J-1247D01*
G01X1692109Y542183D02*
Y555590D01*
G01X1693059D02*
Y555033D01*
G01X1692109Y542183D02*
Y555590D01*
G01X1693059Y551883D02*
Y550533D01*
G01X1692109Y542183D02*
Y555590D01*
G01X1693059Y547383D02*
Y546033D01*
G01X1692109Y542183D02*
Y555590D01*
G01X1693059Y542883D02*
Y542185D01*
G01X1692535Y541158D02*
G02X1692109Y542183I1025J1027D01*
G01X1693059Y542185D02*
G03X1693207Y541831I501J2D01*
G01X1694083Y539610D02*
X1692535Y541158D01*
G01X1693207Y541831D02*
X1693617Y541420D01*
G01X1694083Y539610D02*
X1692535Y541158D01*
G01X1693617Y541420D02*
X1694755Y540282D01*
G01X1694230Y539255D02*
G03X1694083Y539610I-502J0D01*
G01X1694755Y540282D02*
G02X1695180Y539255I-1028J-1027D01*
G01X1694230Y539023D02*
Y539255D01*
G01X1695180D02*
Y538519D01*
G01Y539255D02*
Y538519D01*
G01X1694230Y539023D02*
Y539255D01*
G01X1694755Y540282D02*
G02X1695180Y539255I-1028J-1027D01*
G01X1694230D02*
G03X1694083Y539610I-502J0D01*
G01X1693207Y541831D02*
X1693617Y541420D01*
G01D02*
X1694755Y540282D01*
G01X1694083Y539610D02*
X1692535Y541158D01*
G01X1693059Y542185D02*
G03X1693207Y541831I501J2D01*
G01X1692535Y541158D02*
G02X1692109Y542183I1025J1027D01*
G01X1693059Y555590D02*
Y555033D01*
G01Y551883D02*
Y550533D01*
G01Y547383D02*
Y546033D01*
G01Y542883D02*
Y542185D01*
G01X1692109Y542183D02*
Y555590D01*
G01X1694306Y556837D02*
G03X1693059Y555590I0J-1247D01*
G01X1692109D02*
G02X1694306Y557787I2197J0D01*
G01X1694753Y556837D02*
X1694306D01*
G01Y557787D02*
X1695043D01*
G01X1703861Y547734D02*
Y547133D01*
G01X1702911D02*
Y547733D01*
G01X1704008Y548087D02*
G03X1703862Y547733I354J-353D01*
G01X1702911D02*
G02X1703336Y548759I1450J0D01*
G01X1705698Y549776D02*
X1705159Y549238D01*
G01D02*
X1704008Y548087D01*
G01X1703336Y548759D02*
X1705025Y550448D01*
G01X1706121Y550800D02*
G02X1705698Y549776I-1450J0D01*
G01X1705025Y550448D02*
G03X1705171Y550801I-354J353D01*
G01X1706121Y556147D02*
Y550800D01*
G01X1705171Y550801D02*
Y552385D01*
G01X1706121Y556147D02*
Y550800D01*
G01X1705171Y555535D02*
Y556147D01*
G01X1704411Y557857D02*
G02X1706121Y556147I0J-1710D01*
G01X1705171D02*
G03X1704411Y556907I-760J0D01*
G01X1700947Y557857D02*
X1704411D01*
G01Y556907D02*
X1701584D01*
G01X1704411D02*
X1701584D01*
G01X1700947Y557857D02*
X1704411D01*
G01X1705171Y556147D02*
G03X1704411Y556907I-760J0D01*
G01Y557857D02*
G02X1706121Y556147I0J-1710D01*
G01X1705171Y550801D02*
Y552385D01*
G01Y555535D02*
Y556147D01*
G01X1706121D02*
Y550800D01*
G01X1705025Y550448D02*
G03X1705171Y550801I-354J353D01*
G01X1706121Y550800D02*
G02X1705698Y549776I-1450J0D01*
G01X1703336Y548759D02*
X1705025Y550448D01*
G01X1705698Y549776D02*
X1705159Y549238D01*
G01X1703336Y548759D02*
X1705025Y550448D01*
G01X1705159Y549238D02*
X1704008Y548087D01*
G01X1702911Y547733D02*
G02X1703336Y548759I1450J0D01*
G01X1704008Y548087D02*
G03X1703862Y547733I354J-353D01*
G01X1702911Y547133D02*
Y547733D01*
G01X1703861Y547734D02*
Y547133D01*
G01X1682475Y554168D02*
Y553375D01*
G01X1681525Y554168D02*
Y552981D01*
G01X1682475Y553375D02*
X1682975Y552875D01*
G01X1681525Y552981D02*
X1682025Y552481D01*
G01X1682975Y552875D02*
Y551044D01*
G01X1682025Y552481D02*
Y551044D01*
G01X1661728Y551500D02*
Y553921D01*
G01X1660778Y551500D02*
Y553915D01*
G01X1672577Y553870D02*
Y551546D01*
G01X1671627Y553666D02*
Y551940D01*
G01X1672577Y553870D02*
Y551546D01*
G01X1672575Y551544D02*
Y551044D01*
G01X1671625Y551938D02*
Y551044D01*
G01X1653119Y579775D02*
X1654539D01*
G01X1653119Y580725D02*
X1654539D01*
G01X1681525Y554168D02*
Y552981D01*
G01X1682475Y554168D02*
Y553375D01*
G01X1681525Y552981D02*
X1682025Y552481D01*
G01X1682475Y553375D02*
X1682975Y552875D01*
G01X1682025Y552481D02*
Y551044D01*
G01X1682975Y552875D02*
Y551044D01*
G01X1660778Y551500D02*
Y553915D01*
G01X1661728Y551500D02*
Y553921D01*
G01X1671627Y553666D02*
Y551940D01*
G01X1671625Y551938D02*
Y551044D01*
G01X1672577Y553870D02*
Y551546D01*
G01X1671625Y551938D02*
Y551044D01*
G01X1672575Y551544D02*
Y551044D01*
G01X1653119Y580725D02*
X1654539D01*
G01X1653119Y579775D02*
X1654539D01*
G01X1682713Y567316D02*
X1683005Y567474D01*
G01X1682439Y568249D02*
X1682261Y568153D01*
G01X1682476Y566919D02*
G02X1682713Y567316I451J0D01*
G01X1682261Y568153D02*
G03X1681525Y566919I665J-1233D01*
G01X1682475Y561132D02*
Y566920D01*
G01X1681525Y566919D02*
Y561132D01*
G01Y566919D02*
Y561132D01*
G01X1682475D02*
Y566920D01*
G01X1682261Y568153D02*
G03X1681525Y566919I665J-1233D01*
G01X1682476D02*
G02X1682713Y567316I451J0D01*
G01X1682439Y568249D02*
X1682261Y568153D01*
G01X1682713Y567316D02*
X1683005Y567474D01*
G01X1661725Y560382D02*
Y560666D01*
G01X1660775Y560382D02*
Y560667D01*
G01X1661725Y560666D02*
G02X1661858Y560986I452J0D01*
G01X1660775Y560667D02*
G02X1661186Y561658I1402J-1D01*
G01X1661858Y560986D02*
X1662813Y561941D01*
G01X1661186Y561658D02*
X1664034Y564506D01*
G01X1665040Y564168D02*
X1666648Y565776D01*
G01X1664033Y564506D02*
X1665976Y566448D01*
G01X1666648Y565776D02*
G03X1667073Y566802I-1025J1026D01*
G01X1665976Y566448D02*
G03X1666122Y566802I-354J353D01*
G01X1667073D02*
Y570013D01*
G01X1666123Y566801D02*
Y570012D01*
G01X1667074D02*
G02X1667220Y570366I500J1D01*
G01X1666123Y570012D02*
G02X1666548Y571038I1450J0D01*
G01X1667220Y570366D02*
X1668095Y571241D01*
G01X1670322Y573468D02*
X1671277Y574423D01*
G01X1666548Y571038D02*
X1670605Y575095D01*
G01X1671277Y574423D02*
G02X1671630Y574570I354J-353D01*
G01X1670605Y575095D02*
G02X1671631Y575520I1026J-1025D01*
G01X1671630Y574570D02*
X1673066D01*
G01X1676216D02*
X1677064D01*
G01X1671631Y575520D02*
X1677064D01*
G01Y574570D02*
G03X1678055Y574980I0J1403D01*
G01X1677064Y575520D02*
G03X1677383Y575652I0J451D01*
G01X1678055Y574980D02*
X1681917Y578842D01*
G01X1677383Y575652D02*
X1681245Y579514D01*
G01X1681917Y578842D02*
G03X1682327Y579833I-993J991D01*
G01X1681245Y579514D02*
G03X1681377Y579833I-319J319D01*
G01X1682327D02*
Y581057D01*
G01X1681377Y579833D02*
Y581058D01*
G01X1682327Y581057D02*
G02X1682547Y581588I751J0D01*
G01X1681377Y581058D02*
G02X1681875Y582260I1701J-1D01*
G01X1682547Y581588D02*
X1682736Y581777D01*
G01X1681875Y582260D02*
X1682064Y582450D01*
G01X1682736Y581777D02*
G02X1682843Y581856I320J-321D01*
G01X1682064Y582450D02*
G02X1682395Y582694I990J-996D01*
G01X1682843Y581856D02*
X1683259Y582079D01*
G01X1683262Y582081D02*
X1683447Y582180D01*
G01X1682395Y582694D02*
X1682809Y582916D01*
G01X1682843Y581856D02*
X1683259Y582079D01*
G01X1683262Y582081D02*
X1683447Y582180D01*
G01X1682815Y582921D02*
X1683000Y583019D01*
G01X1660775Y560382D02*
Y560667D01*
G01X1661725Y560382D02*
Y560666D01*
G01X1660775Y560667D02*
G02X1661186Y561658I1402J-1D01*
G01X1661725Y560666D02*
G02X1661858Y560986I452J0D01*
G01X1661186Y561658D02*
X1664034Y564506D01*
G01X1661858Y560986D02*
X1662813Y561941D01*
G01X1664033Y564506D02*
X1665976Y566448D01*
G01X1665040Y564168D02*
X1666648Y565776D01*
G01X1665976Y566448D02*
G03X1666122Y566802I-354J353D01*
G01X1666648Y565776D02*
G03X1667073Y566802I-1025J1026D01*
G01X1666123Y566801D02*
Y570012D01*
G01X1667073Y566802D02*
Y570013D01*
G01X1666123Y570012D02*
G02X1666548Y571038I1450J0D01*
G01X1667074Y570012D02*
G02X1667220Y570366I500J1D01*
G01X1666548Y571038D02*
X1670605Y575095D01*
G01X1667220Y570366D02*
X1668095Y571241D01*
G01X1666548Y571038D02*
X1670605Y575095D01*
G01X1670322Y573468D02*
X1671277Y574423D01*
G01X1670605Y575095D02*
G02X1671631Y575520I1026J-1025D01*
G01X1671277Y574423D02*
G02X1671630Y574570I354J-353D01*
G01X1671631Y575520D02*
X1677064D01*
G01X1671630Y574570D02*
X1673066D01*
G01X1671631Y575520D02*
X1677064D01*
G01X1676216Y574570D02*
X1677064D01*
G01Y575520D02*
G03X1677383Y575652I0J451D01*
G01X1677064Y574570D02*
G03X1678055Y574980I0J1403D01*
G01X1677383Y575652D02*
X1681245Y579514D01*
G01X1678055Y574980D02*
X1681917Y578842D01*
G01X1681245Y579514D02*
G03X1681377Y579833I-319J319D01*
G01X1681917Y578842D02*
G03X1682327Y579833I-993J991D01*
G01X1681377D02*
Y581058D01*
G01X1682327Y579833D02*
Y581057D01*
G01X1681377Y581058D02*
G02X1681875Y582260I1701J-1D01*
G01X1682327Y581057D02*
G02X1682547Y581588I751J0D01*
G01X1681875Y582260D02*
X1682064Y582450D01*
G01X1682547Y581588D02*
X1682736Y581777D01*
G01X1682064Y582450D02*
G02X1682395Y582694I990J-996D01*
G01X1682736Y581777D02*
G02X1682843Y581856I320J-321D01*
G01X1682395Y582694D02*
X1682809Y582916D01*
G01X1682815Y582921D02*
X1683000Y583019D01*
G01X1682843Y581856D02*
X1683259Y582079D01*
G01X1682395Y582694D02*
X1682809Y582916D01*
G01X1682815Y582921D02*
X1683000Y583019D01*
G01X1683262Y582081D02*
X1683447Y582180D01*
G01X1674146Y567474D02*
X1673854Y567316D01*
G01X1673580Y568249D02*
X1673403Y568153D01*
G01X1673854Y567316D02*
G03X1673617Y566919I214J-397D01*
G01X1673403Y568153D02*
G03X1672667Y566918I665J-1233D01*
G01X1673617Y566919D02*
Y564136D01*
G01X1672667Y566918D02*
Y564137D01*
G01X1673617Y564136D02*
G02X1673193Y563112I-1450J1D01*
G01X1672667Y564137D02*
G02X1672521Y563784I-500J0D01*
G01X1673193Y563112D02*
X1672621Y562540D01*
G01X1672521Y563784D02*
X1671948Y563212D01*
G01X1672621Y562540D02*
G03X1672475Y562187I354J-353D01*
G01X1671948Y563212D02*
G03X1671525Y562188I1027J-1024D01*
G01X1672475Y562187D02*
Y560732D01*
G01X1671525Y562188D02*
Y560732D01*
G01X1673580Y568249D02*
X1673403Y568153D01*
G01X1674146Y567474D02*
X1673854Y567316D01*
G01X1673403Y568153D02*
G03X1672667Y566918I665J-1233D01*
G01X1673854Y567316D02*
G03X1673617Y566919I214J-397D01*
G01X1672667Y566918D02*
Y564137D01*
G01X1673617Y566919D02*
Y564136D01*
G01X1672667Y564137D02*
G02X1672521Y563784I-500J0D01*
G01X1673617Y564136D02*
G02X1673193Y563112I-1450J1D01*
G01X1672521Y563784D02*
X1671948Y563212D01*
G01X1673193Y563112D02*
X1672621Y562540D01*
G01X1671948Y563212D02*
G03X1671525Y562188I1027J-1024D01*
G01X1672621Y562540D02*
G03X1672475Y562187I354J-353D01*
G01X1671525Y562188D02*
Y560732D01*
G01X1672475Y562187D02*
Y560732D01*
G01X1660960Y579775D02*
X1667436D01*
G01X1660961Y580725D02*
X1662311D01*
G01X1660960Y579775D02*
X1667436D01*
G01X1665461Y580725D02*
X1667437D01*
G01X1667436Y579775D02*
G02X1667756Y579642I0J-452D01*
G01X1667437Y580725D02*
G02X1668428Y580314I-1J-1402D01*
G01X1667756Y579642D02*
X1668114Y579284D01*
G01X1668428Y580314D02*
X1668786Y579956D01*
G01X1668114Y579284D02*
G03X1669105Y578873I992J991D01*
G01X1668786Y579956D02*
G03X1669106Y579823I320J319D01*
G01X1669105Y578873D02*
X1670540D01*
G01X1669106Y579823D02*
X1670539D01*
G01X1670540Y578873D02*
G03X1671529Y579283I-1J1400D01*
G01X1670539Y579823D02*
G03X1670857Y579955I0J450D01*
G01X1671529Y579283D02*
X1673874Y581628D01*
G01X1670857Y579955D02*
X1671514Y580612D01*
G01X1671529Y579283D02*
X1673874Y581628D01*
G01X1671514Y580612D02*
X1673200Y582299D01*
G01X1673874Y581628D02*
G02X1673981Y581708I320J-317D01*
G01X1673200Y582299D02*
G02X1673533Y582547I994J-987D01*
G01X1673981Y581708D02*
X1674693Y582086D01*
G01X1673533Y582547D02*
X1674247Y582926D01*
G01X1660961Y580725D02*
X1662311D01*
G01X1665461D02*
X1667437D01*
G01X1660960Y579775D02*
X1667436D01*
G01X1667437Y580725D02*
G02X1668428Y580314I-1J-1402D01*
G01X1667436Y579775D02*
G02X1667756Y579642I0J-452D01*
G01X1668428Y580314D02*
X1668786Y579956D01*
G01X1667756Y579642D02*
X1668114Y579284D01*
G01X1668786Y579956D02*
G03X1669106Y579823I320J319D01*
G01X1668114Y579284D02*
G03X1669105Y578873I992J991D01*
G01X1669106Y579823D02*
X1670539D01*
G01X1669105Y578873D02*
X1670540D01*
G01X1670539Y579823D02*
G03X1670857Y579955I0J450D01*
G01X1670540Y578873D02*
G03X1671529Y579283I-1J1400D01*
G01X1670857Y579955D02*
X1671514Y580612D01*
G01D02*
X1673200Y582299D01*
G01X1671529Y579283D02*
X1673874Y581628D01*
G01X1673200Y582299D02*
G02X1673533Y582547I994J-987D01*
G01X1673874Y581628D02*
G02X1673981Y581708I320J-317D01*
G01X1673533Y582547D02*
X1674247Y582926D01*
G01X1673981Y581708D02*
X1674693Y582086D01*
G01X1683045Y598003D02*
X1683041Y598001D01*
G01Y598000D02*
X1682706Y597820D01*
G01X1683491Y597163D02*
X1683154Y596982D01*
G01X1682706Y597820D02*
G03X1682377Y597577I658J-1235D01*
G01X1683154Y596982D02*
G03X1683048Y596904I211J-397D01*
G01X1682377Y597577D02*
X1681043Y596243D01*
G01X1683048Y596904D02*
X1681715Y595571D01*
G01X1681043Y596243D02*
G03X1680633Y595254I990J-990D01*
G01X1681715Y595571D02*
G03X1681583Y595253I318J-318D01*
G01X1680633Y595254D02*
Y593026D01*
G01X1681583Y595253D02*
Y593027D01*
G01X1680632D02*
G02X1680501Y592709I-450J-1D01*
G01X1681583Y593027D02*
G02X1681173Y592037I-1400J0D01*
G01X1680501Y592709D02*
X1678453Y590661D01*
G01X1681173Y592037D02*
X1679125Y589989D01*
G01X1678453Y590661D02*
G02X1678136Y590529I-318J318D01*
G01X1679125Y589989D02*
G02X1678135Y589579I-990J990D01*
G01X1678136Y590529D02*
X1676505D01*
G01X1673355D02*
X1672005D01*
G01X1678135Y589579D02*
X1672006D01*
G01X1672005Y590529D02*
G03X1671016Y590119I1J-1400D01*
G01X1672006Y589579D02*
G03X1671688Y589447I0J-450D01*
G01X1671016Y590119D02*
X1670254Y589357D01*
G01X1671688Y589447D02*
X1670926Y588685D01*
G01X1670254Y589357D02*
G02X1669936Y589225I-318J318D01*
G01X1670926Y588685D02*
G02X1669936Y588275I-990J990D01*
G01Y589225D02*
X1669141D01*
G01X1669936Y588275D02*
X1669141D01*
G01X1661130Y589223D02*
X1662717D01*
G01X1661130Y588273D02*
X1662721D01*
G01X1661130D02*
X1662721D01*
G01X1661130Y589223D02*
X1662717D01*
G01X1662539Y603775D02*
X1658819D01*
G01X1662539Y604725D02*
X1658819D01*
G01X1654475Y595338D02*
X1652949D01*
G01Y596288D02*
X1654601D01*
G01X1651319Y611275D02*
X1654539D01*
G01X1651319Y612225D02*
X1654539D01*
G01X1683491Y597163D02*
X1683154Y596982D01*
G01X1683045Y598003D02*
X1683041Y598001D01*
G01X1683491Y597163D02*
X1683154Y596982D01*
G01X1683041Y598000D02*
X1682706Y597820D01*
G01X1683154Y596982D02*
G03X1683048Y596904I211J-397D01*
G01X1682706Y597820D02*
G03X1682377Y597577I658J-1235D01*
G01X1683048Y596904D02*
X1681715Y595571D01*
G01X1682377Y597577D02*
X1681043Y596243D01*
G01X1681715Y595571D02*
G03X1681583Y595253I318J-318D01*
G01X1681043Y596243D02*
G03X1680633Y595254I990J-990D01*
G01X1681583Y595253D02*
Y593027D01*
G01X1680633Y595254D02*
Y593026D01*
G01X1681583Y593027D02*
G02X1681173Y592037I-1400J0D01*
G01X1680632Y593027D02*
G02X1680501Y592709I-450J-1D01*
G01X1681173Y592037D02*
X1679125Y589989D01*
G01X1680501Y592709D02*
X1678453Y590661D01*
G01X1679125Y589989D02*
G02X1678135Y589579I-990J990D01*
G01X1678453Y590661D02*
G02X1678136Y590529I-318J318D01*
G01X1678135Y589579D02*
X1672006D01*
G01X1678136Y590529D02*
X1676505D01*
G01X1678135Y589579D02*
X1672006D01*
G01X1673355Y590529D02*
X1672005D01*
G01X1672006Y589579D02*
G03X1671688Y589447I0J-450D01*
G01X1672005Y590529D02*
G03X1671016Y590119I1J-1400D01*
G01X1671688Y589447D02*
X1670926Y588685D01*
G01X1671016Y590119D02*
X1670254Y589357D01*
G01X1670926Y588685D02*
G02X1669936Y588275I-990J990D01*
G01X1670254Y589357D02*
G02X1669936Y589225I-318J318D01*
G01Y588275D02*
X1669141D01*
G01X1669936Y589225D02*
X1669141D01*
G01X1683155Y611941D02*
X1683492Y612122D01*
G01X1683046Y612962D02*
X1683042Y612960D01*
G01X1683155Y611941D02*
X1683492Y612122D01*
G01X1683042Y612960D02*
X1682704Y612778D01*
G01X1683155Y611941D02*
X1683492Y612122D01*
G01X1682704Y612778D02*
X1682703D01*
G01X1683050Y611863D02*
G02X1683155Y611941I318J-318D01*
G01X1682703Y612778D02*
G03X1682378Y612535I667J-1231D01*
G01X1682070Y610883D02*
X1683050Y611863D01*
G01X1682378Y612535D02*
X1681398Y611555D01*
G01X1681938Y610565D02*
G02X1682070Y610883I450J0D01*
G01X1681398Y611555D02*
G03X1680988Y610566I990J-990D01*
G01X1681938Y609737D02*
Y610565D01*
G01X1680988Y610566D02*
Y609737D01*
G01X1681480Y608632D02*
G03X1681938Y609737I-1104J1105D01*
G01X1680988D02*
G02X1680808Y609304I-611J0D01*
G01X1677139Y604291D02*
X1681480Y608632D01*
G01X1680808Y609304D02*
X1676467Y604963D01*
G01X1675712Y603700D02*
G03X1677139Y604291I0J2018D01*
G01X1676467Y604963D02*
G02X1675712Y604650I-755J754D01*
G01X1668886Y603700D02*
X1675712D01*
G01Y604650D02*
X1673536D01*
G01X1668886Y603700D02*
X1675712D01*
G01X1670386Y604650D02*
X1669036D01*
G01X1675712D02*
X1673536D01*
G01X1670386D02*
X1669036D01*
G01X1668886Y603700D02*
X1675712D01*
G01X1676467Y604963D02*
G02X1675712Y604650I-755J754D01*
G01Y603700D02*
G03X1677139Y604291I0J2018D01*
G01X1680808Y609304D02*
X1676467Y604963D01*
G01X1677139Y604291D02*
X1681480Y608632D01*
G01X1680988Y609737D02*
G02X1680808Y609304I-611J0D01*
G01X1681480Y608632D02*
G03X1681938Y609737I-1104J1105D01*
G01X1680988Y610566D02*
Y609737D01*
G01X1681938D02*
Y610565D01*
G01X1681398Y611555D02*
G03X1680988Y610566I990J-990D01*
G01X1681938Y610565D02*
G02X1682070Y610883I450J0D01*
G01X1682378Y612535D02*
X1681398Y611555D01*
G01X1682070Y610883D02*
X1683050Y611863D01*
G01X1682703Y612778D02*
G03X1682378Y612535I667J-1231D01*
G01X1683050Y611863D02*
G02X1683155Y611941I318J-318D01*
G01X1683046Y612962D02*
X1683042Y612960D01*
G01D02*
X1682704Y612778D01*
G01D02*
X1682703D01*
G01X1683155Y611941D02*
X1683492Y612122D01*
G01X1674296Y596983D02*
X1674631Y597161D01*
G01D02*
X1674635Y597163D01*
G01X1674186Y598001D02*
X1674185D01*
G01X1674296Y596983D02*
X1674631Y597161D01*
G01D02*
X1674635Y597163D01*
G01X1674185Y598001D02*
X1673848Y597822D01*
G01X1674190Y596904D02*
G02X1674296Y596983I319J-318D01*
G01X1673848Y597822D02*
G03X1673517Y597576I661J-1235D01*
G01X1671902Y594616D02*
X1674190Y596904D01*
G01X1673517Y597576D02*
X1671230Y595288D01*
G01X1670912Y594206D02*
G03X1671902Y594616I0J1400D01*
G01X1671230Y595288D02*
G02X1670913Y595156I-318J318D01*
G01X1669301Y594206D02*
X1670912D01*
G01X1670913Y595156D02*
X1669301D01*
G01X1668311Y594616D02*
G03X1669301Y594206I990J990D01*
G01Y595156D02*
G02X1668983Y595288I0J450D01*
G01X1667809Y595118D02*
X1668311Y594616D01*
G01X1668983Y595288D02*
X1668481Y595790D01*
G01X1667491Y595250D02*
G02X1667809Y595118I0J-450D01*
G01X1668481Y595790D02*
G03X1667492Y596200I-990J-990D01*
G01X1660936Y595250D02*
X1667491D01*
G01X1667492Y596200D02*
X1665486D01*
G01X1660936Y595250D02*
X1667491D01*
G01X1662336Y596200D02*
X1660986D01*
G01X1667492D02*
X1665486D01*
G01X1662336D02*
X1660986D01*
G01X1660936Y595250D02*
X1667491D01*
G01X1668481Y595790D02*
G03X1667492Y596200I-990J-990D01*
G01X1667491Y595250D02*
G02X1667809Y595118I0J-450D01*
G01X1668983Y595288D02*
X1668481Y595790D01*
G01X1667809Y595118D02*
X1668311Y594616D01*
G01X1669301Y595156D02*
G02X1668983Y595288I0J450D01*
G01X1668311Y594616D02*
G03X1669301Y594206I990J990D01*
G01X1670913Y595156D02*
X1669301D01*
G01Y594206D02*
X1670912D01*
G01X1671230Y595288D02*
G02X1670913Y595156I-318J318D01*
G01X1670912Y594206D02*
G03X1671902Y594616I0J1400D01*
G01X1673517Y597576D02*
X1671230Y595288D01*
G01X1671902Y594616D02*
X1674190Y596904D01*
G01X1673848Y597822D02*
G03X1673517Y597576I661J-1235D01*
G01X1674190Y596904D02*
G02X1674296Y596983I319J-318D01*
G01X1674186Y598001D02*
X1674185D01*
G01D02*
X1673848Y597822D01*
G01X1674296Y596983D02*
X1674631Y597161D01*
G01X1674186Y598001D02*
X1674185D01*
G01D02*
X1673848Y597822D01*
G01X1674631Y597161D02*
X1674635Y597163D01*
G01X1674401Y611999D02*
X1674635Y612124D01*
G01X1674186Y612962D02*
X1674185D01*
G01X1674401Y611999D02*
X1674635Y612124D01*
G01X1674185Y612962D02*
X1673972Y612848D01*
G01X1674315Y611931D02*
G02X1674401Y611999I320J-316D01*
G01X1673972Y612848D02*
G03X1673642Y612603I660J-1234D01*
G01X1671892Y609509D02*
X1674314Y611931D01*
G01X1673642Y612603D02*
X1671220Y610181D01*
G01X1670903Y609099D02*
G03X1671892Y609509I-1J1400D01*
G01X1671220Y610181D02*
G02X1670902Y610049I-318J318D01*
G01X1669398Y609099D02*
X1670903D01*
G01X1670902Y610049D02*
X1669399D01*
G01X1668409Y609509D02*
G03X1669398Y609099I990J990D01*
G01X1669399Y610049D02*
G02X1669081Y610181I0J450D01*
G01X1666775Y611143D02*
X1668409Y609509D01*
G01X1669081Y610181D02*
X1667447Y611815D01*
G01X1666458Y611275D02*
G02X1666775Y611143I-1J-450D01*
G01X1667447Y611815D02*
G03X1666457Y612225I-990J-990D01*
G01X1660961Y611275D02*
X1666458D01*
G01X1666457Y612225D02*
X1665461D01*
G01X1660961Y611275D02*
X1666458D01*
G01X1662311Y612225D02*
X1660961D01*
G01X1666457D02*
X1665461D01*
G01X1662311D02*
X1660961D01*
G01Y611275D02*
X1666458D01*
G01X1667447Y611815D02*
G03X1666457Y612225I-990J-990D01*
G01X1666458Y611275D02*
G02X1666775Y611143I-1J-450D01*
G01X1669081Y610181D02*
X1667447Y611815D01*
G01X1666775Y611143D02*
X1668409Y609509D01*
G01X1669399Y610049D02*
G02X1669081Y610181I0J450D01*
G01X1668409Y609509D02*
G03X1669398Y609099I990J990D01*
G01X1670902Y610049D02*
X1669399D01*
G01X1669398Y609099D02*
X1670903D01*
G01X1671220Y610181D02*
G02X1670902Y610049I-318J318D01*
G01X1670903Y609099D02*
G03X1671892Y609509I-1J1400D01*
G01X1673642Y612603D02*
X1671220Y610181D01*
G01X1671892Y609509D02*
X1674314Y611931D01*
G01X1673972Y612848D02*
G03X1673642Y612603I660J-1234D01*
G01X1674315Y611931D02*
G02X1674401Y611999I320J-316D01*
G01X1674186Y612962D02*
X1674185D01*
G01D02*
X1673972Y612848D01*
G01X1674401Y611999D02*
X1674635Y612124D01*
G01X1662539Y604725D02*
X1658819D01*
G01X1662539Y603775D02*
X1658819D01*
G01X1652949Y596288D02*
X1654601D01*
G01X1654475Y595338D02*
X1652949D01*
G01X1651319Y612225D02*
X1654539D01*
G01X1651319Y611275D02*
X1654539D01*
G01X1760823Y208622D02*
Y209533D01*
G01X1761773Y209020D02*
Y209679D01*
G01X1748114Y208565D02*
Y209642D01*
G01X1749064Y208565D02*
Y209570D01*
G01X1735375Y208769D02*
Y209740D01*
G01X1736325Y208769D02*
Y209472D01*
G01X1773050Y208821D02*
Y209906D01*
G01X1761773Y209020D02*
Y209679D01*
G01X1760823Y208622D02*
Y209533D01*
G01X1749064Y208565D02*
Y209570D01*
G01X1748114Y208565D02*
Y209642D01*
G01X1736325Y208769D02*
Y209472D01*
G01X1735375Y208769D02*
Y209740D01*
G01X1760665Y197293D02*
Y198866D01*
G01X1761615Y197393D02*
Y198472D01*
G01X1760665Y198866D02*
X1760962Y199163D01*
G01X1761615Y198472D02*
X1761912Y198769D01*
G01X1760962Y199163D02*
Y200393D01*
G01X1761912Y198769D02*
Y200273D01*
G01X1747981Y200077D02*
Y197293D01*
G01X1748931Y199944D02*
Y197378D01*
G01X1735489Y199647D02*
Y196875D01*
G01X1736439Y199645D02*
Y196778D01*
G01X1773310Y200073D02*
Y197335D01*
G01X1761615Y197393D02*
Y198472D01*
G01X1760665Y197293D02*
Y198866D01*
G01X1761615Y198472D02*
X1761912Y198769D01*
G01X1760665Y198866D02*
X1760962Y199163D01*
G01X1761912Y198769D02*
Y200273D01*
G01X1760962Y199163D02*
Y200393D01*
G01X1748931Y199944D02*
Y197378D01*
G01X1747981Y200077D02*
Y197293D01*
G01X1736439Y199645D02*
Y196778D01*
G01X1735489Y199647D02*
Y196875D01*
G01X1773050Y208821D02*
Y209906D01*
G01X1773310Y200073D02*
Y197335D01*
G01X1770975Y460155D02*
Y461867D01*
G01X1770025Y460155D02*
Y461574D01*
G01X1770975Y461867D02*
X1769750Y463667D01*
G01X1770025Y461574D02*
X1769052Y463003D01*
G01X1769750Y463667D02*
X1759600Y471338D01*
G01X1769052Y463003D02*
X1758834Y470725D01*
G01X1745975Y460155D02*
Y461845D01*
G01X1745025Y460155D02*
Y461573D01*
G01X1745975Y461845D02*
X1745027Y463374D01*
G01X1745024Y461574D02*
X1744311Y462724D01*
G01X1745027Y463374D02*
X1740506Y466816D01*
G01X1744311Y462724D02*
X1739731Y466211D01*
G01X1758475Y460155D02*
Y461829D01*
G01X1757525Y460155D02*
Y461574D01*
G01X1758475Y461829D02*
X1757526Y463472D01*
G01X1757525Y461574D02*
X1756803Y462823D01*
G01X1757526Y463472D02*
X1754590Y465618D01*
G01X1756803Y462823D02*
X1753762Y465046D01*
G01X1770025Y460155D02*
Y461574D01*
G01X1770975Y460155D02*
Y461867D01*
G01X1770025Y461574D02*
X1769052Y463003D01*
G01X1770975Y461867D02*
X1769750Y463667D01*
G01X1769052Y463003D02*
X1758834Y470725D01*
G01X1769750Y463667D02*
X1759600Y471338D01*
G01X1745025Y460155D02*
Y461573D01*
G01X1745975Y460155D02*
Y461845D01*
G01X1745024Y461574D02*
X1744311Y462724D01*
G01X1745975Y461845D02*
X1745027Y463374D01*
G01X1744311Y462724D02*
X1739731Y466211D01*
G01X1745027Y463374D02*
X1740506Y466816D01*
G01X1757525Y460155D02*
Y461574D01*
G01X1758475Y460155D02*
Y461829D01*
G01X1757525Y461574D02*
X1756803Y462823D01*
G01X1758475Y461829D02*
X1757526Y463472D01*
G01X1756803Y462823D02*
X1753762Y465046D01*
G01X1757526Y463472D02*
X1754590Y465618D01*
G01X1771218Y453848D02*
Y450981D01*
G01X1770268Y453362D02*
Y450858D01*
G01X1746105Y453735D02*
Y450897D01*
G01X1745155Y453475D02*
Y450914D01*
G01X1758670Y453800D02*
Y450930D01*
G01X1757720Y453410D02*
Y450950D01*
G01X1770268Y453362D02*
Y450858D01*
G01X1771218Y453848D02*
Y450981D01*
G01X1745155Y453475D02*
Y450914D01*
G01X1746105Y453735D02*
Y450897D01*
G01X1757720Y453410D02*
Y450950D01*
G01X1758670Y453800D02*
Y450930D01*
G01X1759600Y471338D02*
X1758208Y474406D01*
G01X1758834Y470725D02*
X1757213Y474299D01*
G01X1758208Y474406D02*
X1760249Y483874D01*
G01X1757213Y474299D02*
X1759257Y483785D01*
G01X1760249Y483874D02*
X1756550Y492826D01*
G01X1759257Y483785D02*
X1755600Y492637D01*
G01X1756550Y492826D02*
Y495956D01*
G01X1755600Y492637D02*
Y495956D01*
G01X1740506Y466816D02*
X1730394Y490351D01*
G01X1739731Y466211D02*
X1729392Y490275D01*
G01X1730394Y490351D02*
X1731614Y495051D01*
G01X1729392Y490275D02*
X1730664Y495173D01*
G01X1731614Y495051D02*
Y499635D01*
G01X1730664Y495173D02*
Y499635D01*
G01X1754590Y465618D02*
X1750836Y479250D01*
G01X1753762Y465046D02*
X1749970Y478814D01*
G01X1750836Y479250D02*
X1746159Y485224D01*
G01X1749970Y478814D02*
X1745260Y484831D01*
G01X1746159Y485224D02*
X1745191Y491235D01*
G01X1745260Y484831D02*
X1744221Y491281D01*
G01X1745191Y491235D02*
X1746100Y494715D01*
G01X1744221Y491281D02*
X1745150Y494838D01*
G01X1746100Y494715D02*
Y495950D01*
G01X1745150Y494838D02*
Y495950D01*
G01X1758834Y470725D02*
X1757213Y474299D01*
G01X1759600Y471338D02*
X1758208Y474406D01*
G01X1757213Y474299D02*
X1759257Y483785D01*
G01X1758208Y474406D02*
X1760249Y483874D01*
G01X1759257Y483785D02*
X1755600Y492637D01*
G01X1760249Y483874D02*
X1756550Y492826D01*
G01X1755600Y492637D02*
Y495956D01*
G01X1756550Y492826D02*
Y495956D01*
G01X1739731Y466211D02*
X1729392Y490275D01*
G01X1740506Y466816D02*
X1730394Y490351D01*
G01X1729392Y490275D02*
X1730664Y495173D01*
G01X1730394Y490351D02*
X1731614Y495051D01*
G01X1730664Y495173D02*
Y499635D01*
G01X1731614Y495051D02*
Y499635D01*
G01X1753762Y465046D02*
X1749970Y478814D01*
G01X1754590Y465618D02*
X1750836Y479250D01*
G01X1749970Y478814D02*
X1745260Y484831D01*
G01X1750836Y479250D02*
X1746159Y485224D01*
G01X1745260Y484831D02*
X1744221Y491281D01*
G01X1746159Y485224D02*
X1745191Y491235D01*
G01X1744221Y491281D02*
X1745150Y494838D01*
G01X1745191Y491235D02*
X1746100Y494715D01*
G01X1745150Y494838D02*
Y495950D01*
G01X1746100Y494715D02*
Y495950D01*
G01X1782870Y463539D02*
X1772190Y470647D01*
G01X1782182Y462855D02*
X1771491Y469971D01*
G01X1772190Y470647D02*
X1770672Y473100D01*
G01X1771491Y469971D02*
X1769648Y472949D01*
G01X1770672Y473100D02*
X1771819Y477390D01*
G01X1769648Y472949D02*
X1770815Y477313D01*
G01X1771819Y477390D02*
X1768300Y485396D01*
G01X1770815Y477313D02*
X1767350Y485196D01*
G01X1768300Y485396D02*
Y486905D01*
G01X1767350Y485196D02*
Y486905D01*
G01X1782182Y462855D02*
X1771491Y469971D01*
G01X1782870Y463539D02*
X1772190Y470647D01*
G01X1771491Y469971D02*
X1769648Y472949D01*
G01X1772190Y470647D02*
X1770672Y473100D01*
G01X1769648Y472949D02*
X1770815Y477313D01*
G01X1770672Y473100D02*
X1771819Y477390D01*
G01X1770815Y477313D02*
X1767350Y485196D01*
G01X1771819Y477390D02*
X1768300Y485396D01*
G01X1767350Y485196D02*
Y486905D01*
G01X1768300Y485396D02*
Y486905D01*
G01X1712576Y553417D02*
Y543230D01*
G01Y553417D02*
Y543230D01*
G01X1774000Y208821D02*
Y209458D01*
G01X1774260Y200333D02*
Y197291D01*
G01X1823625Y208921D02*
Y210221D01*
G01X1824575Y208921D02*
Y210200D01*
G01X1811083Y209021D02*
Y210617D01*
G01X1812033Y210139D02*
Y209063D01*
G01X1798725Y209121D02*
Y210200D01*
G01X1799675Y209121D02*
Y210380D01*
G01X1785825Y208521D02*
Y209731D01*
G01X1786775Y208521D02*
Y209481D01*
G01X1774000Y208821D02*
Y209458D01*
G01X1824575Y208921D02*
Y210200D01*
G01X1823625Y208921D02*
Y210221D01*
G01X1812033Y210139D02*
Y209063D01*
G01X1811083Y209021D02*
Y210617D01*
G01X1799675Y209121D02*
Y210380D01*
G01X1798725Y209121D02*
Y210200D01*
G01X1786775Y208521D02*
Y209481D01*
G01X1785825Y208521D02*
Y209731D01*
G01X1774260Y200333D02*
Y197291D01*
G01X1823707Y200351D02*
Y197291D01*
G01X1824657Y200433D02*
Y197291D01*
G01X1811066Y200533D02*
Y197291D01*
G01X1812016Y200474D02*
Y197291D01*
G01X1798670Y200633D02*
Y197495D01*
G01X1799620Y200578D02*
Y197291D01*
G01X1785866Y199992D02*
Y197291D01*
G01X1786816Y200033D02*
Y197291D01*
G01X1824657Y200433D02*
Y197291D01*
G01X1823707Y200351D02*
Y197291D01*
G01X1812016Y200474D02*
Y197291D01*
G01X1811066Y200533D02*
Y197291D01*
G01X1799620Y200578D02*
Y197291D01*
G01X1798670Y200633D02*
Y197495D01*
G01X1786816Y200033D02*
Y197291D01*
G01X1785866Y199992D02*
Y197291D01*
G01X1783975Y460155D02*
Y461859D01*
G01X1783025Y460155D02*
Y461574D01*
G01X1783975Y461859D02*
X1782870Y463539D01*
G01X1783025Y461574D02*
X1782182Y462855D01*
G01X1783025Y460155D02*
Y461574D01*
G01X1783975Y460155D02*
Y461859D01*
G01X1783025Y461574D02*
X1782182Y462855D01*
G01X1783975Y461859D02*
X1782870Y463539D01*
G01X1796475Y460155D02*
Y461807D01*
G01X1795525Y460155D02*
Y461574D01*
G01X1796475Y461807D02*
X1795348Y463969D01*
G01X1795525Y461574D02*
X1794606Y463337D01*
G01X1795348Y463969D02*
X1792645Y465984D01*
G01X1794606Y463337D02*
X1791908Y465348D01*
G01X1808975Y460155D02*
Y461878D01*
G01X1808025Y460155D02*
Y461574D01*
G01X1808975Y461878D02*
X1807196Y464380D01*
G01X1808025Y461574D02*
X1806528Y463680D01*
G01X1807196Y464380D02*
X1800145Y468920D01*
G01X1806528Y463680D02*
X1799344Y468305D01*
G01X1821475Y460155D02*
Y461814D01*
G01X1820525Y460155D02*
Y461574D01*
G01X1821475Y461814D02*
X1820635Y463375D01*
G01X1820525Y461574D02*
X1819905Y462726D01*
G01X1820635Y463376D02*
X1814266Y467829D01*
G01X1819905Y462726D02*
X1816814Y464887D01*
G01X1820635Y463376D02*
X1814266Y467829D01*
G01X1834475Y460155D02*
Y461878D01*
G01X1833525Y460155D02*
Y461574D01*
G01X1834475Y461878D02*
X1833031Y463908D01*
G01X1833525Y461574D02*
X1832381Y463182D01*
G01X1833031Y463908D02*
X1828745Y466293D01*
G01X1832381Y463182D02*
X1828031Y465602D01*
G01X1795525Y460155D02*
Y461574D01*
G01X1796475Y460155D02*
Y461807D01*
G01X1795525Y461574D02*
X1794606Y463337D01*
G01X1796475Y461807D02*
X1795348Y463969D01*
G01X1794606Y463337D02*
X1791908Y465348D01*
G01X1795348Y463969D02*
X1792645Y465984D01*
G01X1808025Y460155D02*
Y461574D01*
G01X1808975Y460155D02*
Y461878D01*
G01X1808025Y461574D02*
X1806528Y463680D01*
G01X1808975Y461878D02*
X1807196Y464380D01*
G01X1806528Y463680D02*
X1799344Y468305D01*
G01X1807196Y464380D02*
X1800145Y468920D01*
G01X1820525Y460155D02*
Y461574D01*
G01X1821475Y460155D02*
Y461814D01*
G01X1820525Y461574D02*
X1819905Y462726D01*
G01X1821475Y461814D02*
X1820635Y463375D01*
G01X1819905Y462726D02*
X1816814Y464887D01*
G01X1820635Y463376D02*
X1814266Y467829D01*
G01X1833525Y460155D02*
Y461574D01*
G01X1834475Y460155D02*
Y461878D01*
G01X1833525Y461574D02*
X1832381Y463182D01*
G01X1834475Y461878D02*
X1833031Y463908D01*
G01X1832381Y463182D02*
X1828031Y465602D01*
G01X1833031Y463908D02*
X1828745Y466293D01*
G01X1783939Y453569D02*
Y450858D01*
G01X1782989Y453641D02*
Y450858D01*
G01X1796538Y453668D02*
Y450858D01*
G01X1795588Y453542D02*
Y450858D01*
G01X1809085Y453715D02*
Y450909D01*
G01X1808135Y453495D02*
Y450859D01*
G01X1821648Y453778D02*
Y450945D01*
G01X1820698Y453432D02*
Y450893D01*
G01X1834470Y453600D02*
Y451050D01*
G01X1833520Y453610D02*
Y451050D01*
G01X1782989Y453641D02*
Y450858D01*
G01X1783939Y453569D02*
Y450858D01*
G01X1795588Y453542D02*
Y450858D01*
G01X1796538Y453668D02*
Y450858D01*
G01X1808135Y453495D02*
Y450859D01*
G01X1809085Y453715D02*
Y450909D01*
G01X1820698Y453432D02*
Y450893D01*
G01X1821648Y453778D02*
Y450945D01*
G01X1833520Y453610D02*
Y451050D01*
G01X1834470Y453600D02*
Y451050D01*
G01X1792645Y465984D02*
X1786534Y477328D01*
G01X1791908Y465348D02*
X1785514Y477218D01*
G01X1786534Y477328D02*
X1787316Y480057D01*
G01X1785514Y477218D02*
X1786333Y480078D01*
G01X1787316Y480057D02*
X1786466Y483589D01*
G01X1786333Y480078D02*
X1785480Y483622D01*
G01X1786466Y483589D02*
X1787500Y486904D01*
G01X1785480Y483622D02*
X1786550Y487049D01*
G01X1787500Y486904D02*
Y488480D01*
G01X1786550Y487049D02*
Y488480D01*
G01X1800145Y468920D02*
X1798374Y474422D01*
G01X1799344Y468305D02*
X1797366Y474453D01*
G01X1798374Y474422D02*
X1800802Y480631D01*
G01X1797366Y474453D02*
X1799798Y480675D01*
G01X1800802Y480631D02*
X1799100Y486425D01*
G01X1799798Y480675D02*
X1798150Y486288D01*
G01X1799100Y486425D02*
Y488480D01*
G01X1798150Y486288D02*
Y488480D01*
G01X1816814Y464888D02*
X1813539Y467177D01*
G01X1814266Y467829D02*
X1810209Y475234D01*
G01X1813539Y467177D02*
X1809313Y474892D01*
G01X1810209Y475234D02*
X1808491Y482624D01*
G01X1809313Y474892D02*
X1807505Y482669D01*
G01X1808491Y482624D02*
X1809950Y487032D01*
G01X1807505Y482669D02*
X1809000Y487186D01*
G01X1809950Y487032D02*
Y488280D01*
G01X1809000Y487186D02*
Y488280D01*
G01X1828745Y466293D02*
X1827634Y468452D01*
G01X1828031Y465602D02*
X1826887Y467826D01*
G01X1827634Y468452D02*
X1823605Y471522D01*
G01X1826887Y467826D02*
X1822766Y470966D01*
G01X1823605Y471522D02*
X1820898Y482040D01*
G01X1822766Y470967D02*
X1819914Y482050D01*
G01X1820898Y482040D02*
X1822100Y486335D01*
G01X1819914Y482050D02*
X1821150Y486466D01*
G01X1822100Y486335D02*
Y488480D01*
G01X1821150Y486466D02*
Y488480D01*
G01X1791908Y465348D02*
X1785514Y477218D01*
G01X1792645Y465984D02*
X1786534Y477328D01*
G01X1785514Y477218D02*
X1786333Y480078D01*
G01X1786534Y477328D02*
X1787316Y480057D01*
G01X1786333Y480078D02*
X1785480Y483622D01*
G01X1787316Y480057D02*
X1786466Y483589D01*
G01X1785480Y483622D02*
X1786550Y487049D01*
G01X1786466Y483589D02*
X1787500Y486904D01*
G01X1786550Y487049D02*
Y488480D01*
G01X1787500Y486904D02*
Y488480D01*
G01X1799344Y468305D02*
X1797366Y474453D01*
G01X1800145Y468920D02*
X1798374Y474422D01*
G01X1797366Y474453D02*
X1799798Y480675D01*
G01X1798374Y474422D02*
X1800802Y480631D01*
G01X1799798Y480675D02*
X1798150Y486288D01*
G01X1800802Y480631D02*
X1799100Y486425D01*
G01X1798150Y486288D02*
Y488480D01*
G01X1799100Y486425D02*
Y488480D01*
G01X1816814Y464888D02*
X1813539Y467177D01*
G01D02*
X1809313Y474892D01*
G01X1814266Y467829D02*
X1810209Y475234D01*
G01X1809313Y474892D02*
X1807505Y482669D01*
G01X1810209Y475234D02*
X1808491Y482624D01*
G01X1807505Y482669D02*
X1809000Y487186D01*
G01X1808491Y482624D02*
X1809950Y487032D01*
G01X1809000Y487186D02*
Y488280D01*
G01X1809950Y487032D02*
Y488280D01*
G01X1828031Y465602D02*
X1826887Y467826D01*
G01X1828745Y466293D02*
X1827634Y468452D01*
G01X1826887Y467826D02*
X1822766Y470966D01*
G01X1827634Y468452D02*
X1823605Y471522D01*
G01X1822766Y470967D02*
X1819914Y482050D01*
G01X1823605Y471522D02*
X1820898Y482040D01*
G01X1819914Y482050D02*
X1821150Y486466D01*
G01X1820898Y482040D02*
X1822100Y486335D01*
G01X1821150Y486466D02*
Y488480D01*
G01X1822100Y486335D02*
Y488480D01*
G01X1856970Y255840D02*
Y254910D01*
G01X1856020Y255000D02*
Y256113D01*
G01X1857435Y256583D02*
X1856970Y255840D01*
G01X1856020Y256113D02*
X1856745Y257273D01*
G01X1858203Y257063D02*
X1857435Y256583D01*
G01X1856745Y257273D02*
X1857834Y257953D01*
G01X1859490Y257360D02*
X1858203Y257063D01*
G01X1857834Y257953D02*
X1859487Y258336D01*
G01X1865369Y256002D02*
X1862998Y256550D01*
G01X1860805Y257056D02*
X1859490Y257360D01*
G01X1859487Y258336D02*
X1865746Y256890D01*
G01X1870510Y252669D02*
X1865369Y256002D01*
G01X1865746Y256890D02*
X1870912Y253541D01*
G01X1876267Y250961D02*
X1870510Y252669D01*
G01X1870912Y253541D02*
X1876883Y251770D01*
G01X1882097Y241631D02*
X1876267Y250961D01*
G01X1876883Y251770D02*
X1882787Y242321D01*
G01X1886744Y238729D02*
X1885151Y239724D01*
G01X1883242Y240916D02*
X1882097Y241631D01*
G01X1882787Y242321D02*
X1887113Y239620D01*
G01X1893833Y237092D02*
X1890252Y237919D01*
G01X1888059Y238425D02*
X1886744Y238729D01*
G01X1887113Y239620D02*
X1893833Y238068D01*
G01X1896429Y237691D02*
X1893833Y237092D01*
G01Y238068D02*
X1896429Y238666D01*
G01X1899368Y237013D02*
X1896429Y237691D01*
G01Y238666D02*
X1901838Y237419D01*
G01X1896429Y238666D02*
X1901838Y237419D01*
G01X1896429Y238666D02*
X1901838Y237419D01*
G01X1896429Y238666D02*
X1901838Y237419D01*
G01X1899368Y237013D02*
X1896429Y237691D01*
G01X1893833Y238068D02*
X1896429Y238666D01*
G01Y237691D02*
X1893833Y237092D01*
G01X1887113Y239620D02*
X1893833Y238068D01*
G01Y237092D02*
X1890252Y237919D01*
G01X1887113Y239620D02*
X1893833Y238068D01*
G01X1888059Y238425D02*
X1886744Y238729D01*
G01X1882787Y242321D02*
X1887113Y239620D01*
G01X1886744Y238729D02*
X1885151Y239724D01*
G01X1882787Y242321D02*
X1887113Y239620D01*
G01X1883242Y240916D02*
X1882097Y241631D01*
G01X1876883Y251770D02*
X1882787Y242321D01*
G01X1882097Y241631D02*
X1876267Y250961D01*
G01X1870912Y253541D02*
X1876883Y251770D01*
G01X1876267Y250961D02*
X1870510Y252669D01*
G01X1865746Y256890D02*
X1870912Y253541D01*
G01X1870510Y252669D02*
X1865369Y256002D01*
G01X1859487Y258336D02*
X1865746Y256890D01*
G01X1865369Y256002D02*
X1862998Y256550D01*
G01X1859487Y258336D02*
X1865746Y256890D01*
G01X1860805Y257056D02*
X1859490Y257360D01*
G01X1857834Y257953D02*
X1859487Y258336D01*
G01X1859490Y257360D02*
X1858203Y257063D01*
G01X1856745Y257273D02*
X1857834Y257953D01*
G01X1858203Y257063D02*
X1857435Y256583D01*
G01X1856020Y256113D02*
X1856745Y257273D01*
G01X1857435Y256583D02*
X1856970Y255840D01*
G01X1856020Y255000D02*
Y256113D01*
G01X1856970Y255840D02*
Y254910D01*
G01X1848542Y255685D02*
Y254846D01*
G01X1847592Y254575D02*
Y255958D01*
G01X1851535Y260475D02*
X1850820Y259330D01*
G01X1849627Y257422D02*
X1848542Y255685D01*
G01X1847592Y255958D02*
X1850937Y261313D01*
G01X1859945Y262417D02*
X1858550Y262095D01*
G01X1856358Y261589D02*
X1855043Y261285D01*
G01X1852850Y260779D02*
X1851535Y260475D01*
G01X1850937Y261313D02*
X1859945Y263392D01*
G01X1865498Y261135D02*
X1859945Y262417D01*
G01Y263393D02*
X1865875Y262024D01*
G01X1871773Y257069D02*
X1865498Y261135D01*
G01X1865875Y262024D02*
X1872175Y257941D01*
G01X1879518Y254771D02*
X1871773Y257069D01*
G01X1872175Y257941D02*
X1880134Y255580D01*
G01X1885883Y244583D02*
X1879518Y254771D01*
G01X1880134Y255580D02*
X1886573Y245272D01*
G01X1888534Y242924D02*
X1885883Y244583D01*
G01X1886573Y245272D02*
X1888903Y243814D01*
G01X1894102Y241640D02*
X1888534Y242924D01*
G01X1888903Y243814D02*
X1894102Y242615D01*
G01X1896857Y242275D02*
X1894102Y241640D01*
G01Y242615D02*
X1896856Y243250D01*
G01X1902855Y240900D02*
X1896857Y242275D01*
G01X1896856Y243250D02*
X1903223Y241791D01*
G01X1896856Y243250D02*
X1903223Y241791D01*
G01X1902855Y240900D02*
X1896857Y242275D01*
G01X1894102Y242615D02*
X1896856Y243250D01*
G01X1896857Y242275D02*
X1894102Y241640D01*
G01X1888903Y243814D02*
X1894102Y242615D01*
G01Y241640D02*
X1888534Y242924D01*
G01X1886573Y245272D02*
X1888903Y243814D01*
G01X1888534Y242924D02*
X1885883Y244583D01*
G01X1880134Y255580D02*
X1886573Y245272D01*
G01X1885883Y244583D02*
X1879518Y254771D01*
G01X1872175Y257941D02*
X1880134Y255580D01*
G01X1879518Y254771D02*
X1871773Y257069D01*
G01X1865875Y262024D02*
X1872175Y257941D01*
G01X1871773Y257069D02*
X1865498Y261135D01*
G01X1859945Y263393D02*
X1865875Y262024D01*
G01X1865498Y261135D02*
X1859945Y262417D01*
G01X1850937Y261313D02*
X1859945Y263392D01*
G01Y262417D02*
X1858550Y262095D01*
G01X1850937Y261313D02*
X1859945Y263392D01*
G01X1856358Y261589D02*
X1855043Y261285D01*
G01X1850937Y261313D02*
X1859945Y263392D01*
G01X1852850Y260779D02*
X1851535Y260475D01*
G01X1847592Y255958D02*
X1850937Y261313D01*
G01X1851535Y260475D02*
X1850820Y259330D01*
G01X1847592Y255958D02*
X1850937Y261313D01*
G01X1849627Y257422D02*
X1848542Y255685D01*
G01X1847592Y254575D02*
Y255958D01*
G01X1848542Y255685D02*
Y254846D01*
G01X1896429Y238666D02*
X1901838Y237419D01*
G01X1896429Y238666D02*
X1901838Y237419D01*
G01X1896429Y238666D02*
X1901838Y237419D01*
G01X1899368Y237013D02*
X1896429Y237691D01*
G01X1893833Y238068D02*
X1896429Y238666D01*
G01Y237691D02*
X1893833Y237092D01*
G01X1887113Y239620D02*
X1893833Y238068D01*
G01Y237092D02*
X1890252Y237919D01*
G01X1887113Y239620D02*
X1893833Y238068D01*
G01X1888059Y238425D02*
X1886744Y238729D01*
G01X1882787Y242321D02*
X1887113Y239620D01*
G01X1886744Y238729D02*
X1885151Y239724D01*
G01X1882787Y242321D02*
X1887113Y239620D01*
G01X1883242Y240916D02*
X1882097Y241631D01*
G01X1876883Y251770D02*
X1882787Y242321D01*
G01X1882097Y241631D02*
X1876267Y250961D01*
G01X1870912Y253541D02*
X1876883Y251770D01*
G01X1876267Y250961D02*
X1870510Y252669D01*
G01X1865746Y256890D02*
X1870912Y253541D01*
G01X1870510Y252669D02*
X1865369Y256002D01*
G01X1859487Y258336D02*
X1865746Y256890D01*
G01X1865369Y256002D02*
X1862998Y256550D01*
G01X1859487Y258336D02*
X1865746Y256890D01*
G01X1860805Y257056D02*
X1859490Y257360D01*
G01X1857834Y257953D02*
X1859487Y258336D01*
G01X1859490Y257360D02*
X1858203Y257063D01*
G01X1856745Y257273D02*
X1857834Y257953D01*
G01X1858203Y257063D02*
X1857435Y256583D01*
G01X1856020Y256113D02*
X1856745Y257273D01*
G01X1857435Y256583D02*
X1856970Y255840D01*
G01X1856020Y255000D02*
Y256113D01*
G01X1856970Y255840D02*
Y254910D01*
G01X1853949Y490550D02*
X1853169D01*
G01X1853999Y489600D02*
X1853169D01*
G01X1853999D02*
X1853169D01*
G01X1853949Y490550D02*
X1853169D01*
G01X1871052Y490659D02*
X1867841D01*
G01X1868009Y489709D02*
X1871053D01*
G01X1876641Y490659D02*
X1877600D01*
G01X1876709Y489709D02*
X1877994D01*
G01X1876641Y490659D02*
X1877600D01*
G01D02*
X1878050Y491109D01*
G01X1877994Y489709D02*
X1879000Y490715D01*
G01X1878050Y491109D02*
Y495394D01*
G01X1879000Y490715D02*
Y495000D01*
G01X1878050Y495394D02*
X1881456Y498800D01*
G01X1879000Y495000D02*
X1881850Y497850D01*
G01X1881456Y498800D02*
X1897678D01*
G01X1881850Y497850D02*
X1898072D01*
G01X1871052Y490659D02*
X1867841D01*
G01X1868009Y489709D02*
X1871053D01*
G01X1876641Y490659D02*
X1877600D01*
G01X1876709Y489709D02*
X1877994D01*
G01X1876641Y490659D02*
X1877600D01*
G01D02*
X1878050Y491109D01*
G01X1877994Y489709D02*
X1879000Y490715D01*
G01X1878050Y491109D02*
Y495394D01*
G01X1879000Y490715D02*
Y495000D01*
G01X1878050Y495394D02*
X1881456Y498800D01*
G01X1879000Y495000D02*
X1881850Y497850D01*
G01X1881456Y498800D02*
X1897678D01*
G01X1881850Y497850D02*
X1898072D01*
G01X1871052Y490659D02*
X1867841D01*
G01X1868009Y489709D02*
X1871053D01*
G01X1876641Y490659D02*
X1877600D01*
G01X1876709Y489709D02*
X1877994D01*
G01X1876641Y490659D02*
X1877600D01*
G01D02*
X1878050Y491109D01*
G01X1877994Y489709D02*
X1879000Y490715D01*
G01X1878050Y491109D02*
Y495394D01*
G01X1879000Y490715D02*
Y495000D01*
G01X1878050Y495394D02*
X1881456Y498800D01*
G01X1879000Y495000D02*
X1881850Y497850D01*
G01X1881456Y498800D02*
X1897678D01*
G01X1881850Y497850D02*
X1898072D01*
G01X1876709Y489709D02*
X1877994D01*
G01D02*
X1879000Y490715D01*
G01X1876641Y490659D02*
X1877600D01*
G01X1877994Y489709D02*
X1879000Y490715D01*
G01X1877600Y490659D02*
X1878050Y491109D01*
G01X1879000Y490715D02*
Y495000D01*
G01X1878050Y491109D02*
Y495394D01*
G01X1879000Y495000D02*
X1881850Y497850D01*
G01X1878050Y495394D02*
X1881456Y498800D01*
G01X1881850Y497850D02*
X1898072D01*
G01X1881456Y498800D02*
X1897678D01*
G01X1868009Y489709D02*
X1871053D01*
G01X1871052Y490659D02*
X1867841D01*
G01X1876709Y489709D02*
X1877994D01*
G01D02*
X1879000Y490715D01*
G01X1876641Y490659D02*
X1877600D01*
G01X1877994Y489709D02*
X1879000Y490715D01*
G01X1877600Y490659D02*
X1878050Y491109D01*
G01X1879000Y490715D02*
Y495000D01*
G01X1878050Y491109D02*
Y495394D01*
G01X1879000Y495000D02*
X1881850Y497850D01*
G01X1878050Y495394D02*
X1881456Y498800D01*
G01X1881850Y497850D02*
X1898072D01*
G01X1881456Y498800D02*
X1897678D01*
G01X1868009Y489709D02*
X1871053D01*
G01X1871052Y490659D02*
X1867841D01*
G01X1876709Y489709D02*
X1877994D01*
G01D02*
X1879000Y490715D01*
G01X1876641Y490659D02*
X1877600D01*
G01X1877994Y489709D02*
X1879000Y490715D01*
G01X1877600Y490659D02*
X1878050Y491109D01*
G01X1879000Y490715D02*
Y495000D01*
G01X1878050Y491109D02*
Y495394D01*
G01X1879000Y495000D02*
X1881850Y497850D01*
G01X1878050Y495394D02*
X1881456Y498800D01*
G01X1881850Y497850D02*
X1898072D01*
G01X1881456Y498800D02*
X1897678D01*
G01X1868009Y489709D02*
X1871053D01*
G01X1871052Y490659D02*
X1867841D01*
G01X1955398Y216300D02*
X1955842D01*
G01X1955760Y217250D02*
X1955140D01*
G01X1952601Y214660D02*
X1955398Y216300D01*
G01D02*
X1955842D01*
G01X1955140Y217250D02*
X1952199Y215527D01*
G01X1941747Y210850D02*
X1952601Y214660D01*
G01X1952199Y215527D02*
X1951063Y215128D01*
G01X1941747Y210850D02*
X1952601Y214660D01*
G01X1948940Y214383D02*
X1947666Y213936D01*
G01X1941747Y210850D02*
X1952601Y214660D01*
G01X1945543Y213190D02*
X1944269Y212743D01*
G01X1941747Y210850D02*
X1952601Y214660D01*
G01X1942146Y211998D02*
X1941584Y211800D01*
G01X1935397Y210850D02*
X1941747D01*
G01X1941584Y211800D02*
X1940234D01*
G01X1935397Y210850D02*
X1941747D01*
G01X1937984Y211800D02*
X1935534D01*
G01X1933199Y211494D02*
X1935397Y210850D01*
G01X1935534Y211800D02*
X1933700Y212338D01*
G01X1931994Y212699D02*
X1930804Y213889D01*
G01X1931994Y212699D02*
X1933199Y211494D01*
G01X1933700Y212338D02*
X1931635Y214403D01*
G01X1930804Y213889D02*
X1929364Y218214D01*
G01X1931635Y214403D02*
X1930314Y218369D01*
G01X1933700Y212338D02*
X1931635Y214403D01*
G01X1931994Y212699D02*
X1930804Y213889D01*
G01X1931635Y214403D02*
X1930314Y218369D01*
G01X1930804Y213889D02*
X1929364Y218214D01*
G01X1933700Y212338D02*
X1931635Y214403D01*
G01X1931994Y212699D02*
X1933199Y211494D01*
G01X1935534Y211800D02*
X1933700Y212338D01*
G01X1933199Y211494D02*
X1935397Y210850D01*
G01X1941584Y211800D02*
X1940234D01*
G01X1937984D02*
X1935534D01*
G01X1935397Y210850D02*
X1941747D01*
G01X1952199Y215527D02*
X1951063Y215128D01*
G01X1948940Y214383D02*
X1947666Y213936D01*
G01X1945543Y213190D02*
X1944269Y212743D01*
G01X1942146Y211998D02*
X1941584Y211800D01*
G01X1941747Y210850D02*
X1952601Y214660D01*
G01X1955140Y217250D02*
X1952199Y215527D01*
G01X1952601Y214660D02*
X1955398Y216300D01*
G01X1955760Y217250D02*
X1955140D01*
G01D02*
X1952199Y215527D01*
G01X1955398Y216300D02*
X1955842D01*
G01X1933700Y212338D02*
X1931635Y214403D01*
G01X1931994Y212699D02*
X1930804Y213889D01*
G01X1931635Y214403D02*
X1930314Y218369D01*
G01X1930804Y213889D02*
X1929364Y218214D01*
G01X1933700Y212338D02*
X1931635Y214403D01*
G01X1931994Y212699D02*
X1933199Y211494D01*
G01X1935534Y211800D02*
X1933700Y212338D01*
G01X1933199Y211494D02*
X1935397Y210850D01*
G01X1941584Y211800D02*
X1940234D01*
G01X1937984D02*
X1935534D01*
G01X1935397Y210850D02*
X1941747D01*
G01X1952199Y215527D02*
X1951063Y215128D01*
G01X1948940Y214383D02*
X1947666Y213936D01*
G01X1945543Y213190D02*
X1944269Y212743D01*
G01X1942146Y211998D02*
X1941584Y211800D01*
G01X1941747Y210850D02*
X1952601Y214660D01*
G01X1955140Y217250D02*
X1952199Y215527D01*
G01X1952601Y214660D02*
X1955398Y216300D01*
G01X1955760Y217250D02*
X1955140D01*
G01D02*
X1952199Y215527D01*
G01X1955398Y216300D02*
X1955842D01*
G01X1941131Y218411D02*
X1939470Y216750D01*
G01X1940737Y219361D02*
X1939076Y217700D01*
G01X1939470Y216750D02*
X1936146D01*
G01X1939076Y217700D02*
X1936540D01*
G01X1936146Y216750D02*
X1935009Y217887D01*
G01X1936540Y217700D02*
X1935959Y218281D01*
G01X1940737Y219361D02*
X1939076Y217700D01*
G01X1940737Y219361D02*
X1939076Y217700D01*
G01X1941131Y218411D02*
X1939470Y216750D01*
G01X1939076Y217700D02*
X1936540D01*
G01X1939470Y216750D02*
X1936146D01*
G01X1936540Y217700D02*
X1935959Y218281D01*
G01X1936146Y216750D02*
X1935009Y217887D01*
G01X1955398Y216300D02*
X1955842D01*
G01X1955760Y217250D02*
X1955140D01*
G01X1952601Y214660D02*
X1955398Y216300D01*
G01D02*
X1955842D01*
G01X1955140Y217250D02*
X1952199Y215527D01*
G01X1941747Y210850D02*
X1952601Y214660D01*
G01X1952199Y215527D02*
X1951063Y215128D01*
G01X1941747Y210850D02*
X1952601Y214660D01*
G01X1948940Y214383D02*
X1947666Y213936D01*
G01X1941747Y210850D02*
X1952601Y214660D01*
G01X1945543Y213190D02*
X1944269Y212743D01*
G01X1941747Y210850D02*
X1952601Y214660D01*
G01X1942146Y211998D02*
X1941584Y211800D01*
G01X1935397Y210850D02*
X1941747D01*
G01X1941584Y211800D02*
X1940234D01*
G01X1935397Y210850D02*
X1941747D01*
G01X1937984Y211800D02*
X1935534D01*
G01X1933199Y211494D02*
X1935397Y210850D01*
G01X1935534Y211800D02*
X1933700Y212338D01*
G01X1931994Y212699D02*
X1930804Y213889D01*
G01X1931994Y212699D02*
X1933199Y211494D01*
G01X1933700Y212338D02*
X1931635Y214403D01*
G01X1930804Y213889D02*
X1929364Y218214D01*
G01X1931635Y214403D02*
X1930314Y218369D01*
G01X1955398Y216300D02*
X1955842D01*
G01X1955760Y217250D02*
X1955140D01*
G01X1952601Y214660D02*
X1955398Y216300D01*
G01D02*
X1955842D01*
G01X1955140Y217250D02*
X1952199Y215527D01*
G01X1941747Y210850D02*
X1952601Y214660D01*
G01X1952199Y215527D02*
X1951063Y215128D01*
G01X1941747Y210850D02*
X1952601Y214660D01*
G01X1948940Y214383D02*
X1947666Y213936D01*
G01X1941747Y210850D02*
X1952601Y214660D01*
G01X1945543Y213190D02*
X1944269Y212743D01*
G01X1941747Y210850D02*
X1952601Y214660D01*
G01X1942146Y211998D02*
X1941584Y211800D01*
G01X1935397Y210850D02*
X1941747D01*
G01X1941584Y211800D02*
X1940234D01*
G01X1935397Y210850D02*
X1941747D01*
G01X1937984Y211800D02*
X1935534D01*
G01X1933199Y211494D02*
X1935397Y210850D01*
G01X1935534Y211800D02*
X1933700Y212338D01*
G01X1931994Y212699D02*
X1930804Y213889D01*
G01X1931994Y212699D02*
X1933199Y211494D01*
G01X1933700Y212338D02*
X1931635Y214403D01*
G01X1930804Y213889D02*
X1929364Y218214D01*
G01X1931635Y214403D02*
X1930314Y218369D01*
G01X1955398Y216300D02*
X1955842D01*
G01X1955760Y217250D02*
X1955140D01*
G01X1952601Y214660D02*
X1955398Y216300D01*
G01D02*
X1955842D01*
G01X1955140Y217250D02*
X1952199Y215527D01*
G01X1941747Y210850D02*
X1952601Y214660D01*
G01X1952199Y215527D02*
X1951063Y215128D01*
G01X1941747Y210850D02*
X1952601Y214660D01*
G01X1948940Y214383D02*
X1947666Y213936D01*
G01X1941747Y210850D02*
X1952601Y214660D01*
G01X1945543Y213190D02*
X1944269Y212743D01*
G01X1941747Y210850D02*
X1952601Y214660D01*
G01X1942146Y211998D02*
X1941584Y211800D01*
G01X1935397Y210850D02*
X1941747D01*
G01X1941584Y211800D02*
X1940234D01*
G01X1935397Y210850D02*
X1941747D01*
G01X1937984Y211800D02*
X1935534D01*
G01X1933199Y211494D02*
X1935397Y210850D01*
G01X1935534Y211800D02*
X1933700Y212338D01*
G01X1931994Y212699D02*
X1930804Y213889D01*
G01X1931994Y212699D02*
X1933199Y211494D01*
G01X1933700Y212338D02*
X1931635Y214403D01*
G01X1930804Y213889D02*
X1929364Y218214D01*
G01X1931635Y214403D02*
X1930314Y218369D01*
G01X1933700Y212338D02*
X1931635Y214403D01*
G01X1931994Y212699D02*
X1930804Y213889D01*
G01X1931635Y214403D02*
X1930314Y218369D01*
G01X1930804Y213889D02*
X1929364Y218214D01*
G01X1933700Y212338D02*
X1931635Y214403D01*
G01X1931994Y212699D02*
X1933199Y211494D01*
G01X1935534Y211800D02*
X1933700Y212338D01*
G01X1933199Y211494D02*
X1935397Y210850D01*
G01X1941584Y211800D02*
X1940234D01*
G01X1937984D02*
X1935534D01*
G01X1935397Y210850D02*
X1941747D01*
G01X1952199Y215527D02*
X1951063Y215128D01*
G01X1948940Y214383D02*
X1947666Y213936D01*
G01X1945543Y213190D02*
X1944269Y212743D01*
G01X1942146Y211998D02*
X1941584Y211800D01*
G01X1941747Y210850D02*
X1952601Y214660D01*
G01X1955140Y217250D02*
X1952199Y215527D01*
G01X1952601Y214660D02*
X1955398Y216300D01*
G01X1955760Y217250D02*
X1955140D01*
G01D02*
X1952199Y215527D01*
G01X1955398Y216300D02*
X1955842D01*
G01X1933700Y212338D02*
X1931635Y214403D01*
G01X1931994Y212699D02*
X1930804Y213889D01*
G01X1931635Y214403D02*
X1930314Y218369D01*
G01X1930804Y213889D02*
X1929364Y218214D01*
G01X1933700Y212338D02*
X1931635Y214403D01*
G01X1931994Y212699D02*
X1933199Y211494D01*
G01X1935534Y211800D02*
X1933700Y212338D01*
G01X1933199Y211494D02*
X1935397Y210850D01*
G01X1941584Y211800D02*
X1940234D01*
G01X1937984D02*
X1935534D01*
G01X1935397Y210850D02*
X1941747D01*
G01X1952199Y215527D02*
X1951063Y215128D01*
G01X1948940Y214383D02*
X1947666Y213936D01*
G01X1945543Y213190D02*
X1944269Y212743D01*
G01X1942146Y211998D02*
X1941584Y211800D01*
G01X1941747Y210850D02*
X1952601Y214660D01*
G01X1955140Y217250D02*
X1952199Y215527D01*
G01X1952601Y214660D02*
X1955398Y216300D01*
G01X1955760Y217250D02*
X1955140D01*
G01D02*
X1952199Y215527D01*
G01X1955398Y216300D02*
X1955842D01*
G01X1941131Y218411D02*
X1939470Y216750D01*
G01X1940737Y219361D02*
X1939076Y217700D01*
G01X1939470Y216750D02*
X1936146D01*
G01X1939076Y217700D02*
X1936540D01*
G01X1936146Y216750D02*
X1935009Y217887D01*
G01X1936540Y217700D02*
X1935959Y218281D01*
G01X1941131Y218411D02*
X1939470Y216750D01*
G01X1940737Y219361D02*
X1939076Y217700D01*
G01X1939470Y216750D02*
X1936146D01*
G01X1939076Y217700D02*
X1936540D01*
G01X1936146Y216750D02*
X1935009Y217887D01*
G01X1936540Y217700D02*
X1935959Y218281D01*
G01X1941131Y218411D02*
X1939470Y216750D01*
G01X1940737Y219361D02*
X1939076Y217700D01*
G01X1939470Y216750D02*
X1936146D01*
G01X1939076Y217700D02*
X1936540D01*
G01X1936146Y216750D02*
X1935009Y217887D01*
G01X1936540Y217700D02*
X1935959Y218281D01*
G01X1940737Y219361D02*
X1939076Y217700D01*
G01X1940737Y219361D02*
X1939076Y217700D01*
G01X1941131Y218411D02*
X1939470Y216750D01*
G01X1939076Y217700D02*
X1936540D01*
G01X1939470Y216750D02*
X1936146D01*
G01X1936540Y217700D02*
X1935959Y218281D01*
G01X1936146Y216750D02*
X1935009Y217887D01*
G01X1940737Y219361D02*
X1939076Y217700D01*
G01X1940737Y219361D02*
X1939076Y217700D01*
G01X1941131Y218411D02*
X1939470Y216750D01*
G01X1939076Y217700D02*
X1936540D01*
G01X1939470Y216750D02*
X1936146D01*
G01X1936540Y217700D02*
X1935959Y218281D01*
G01X1936146Y216750D02*
X1935009Y217887D01*
G01X1940737Y219361D02*
X1939076Y217700D01*
G01X1940737Y219361D02*
X1939076Y217700D01*
G01X1941131Y218411D02*
X1939470Y216750D01*
G01X1939076Y217700D02*
X1936540D01*
G01X1939470Y216750D02*
X1936146D01*
G01X1936540Y217700D02*
X1935959Y218281D01*
G01X1936146Y216750D02*
X1935009Y217887D01*
G01X1901473Y236531D02*
X1901053Y236628D01*
G01D02*
X1899369Y237015D01*
G01X1903998Y234953D02*
X1901473Y236531D01*
G01X1901839Y237423D02*
X1904687Y235643D01*
G01X1905137Y233133D02*
X1903998Y234953D01*
G01X1904687Y235643D02*
X1906087Y233406D01*
G01X1905137Y231441D02*
Y233133D01*
G01X1906087Y233406D02*
Y231835D01*
G01X1906415Y230163D02*
X1905137Y231441D01*
G01X1906087Y231835D02*
X1906809Y231113D01*
G01X1907567Y230163D02*
X1906415D01*
G01D02*
X1905137Y231441D01*
G01X1906809Y231113D02*
X1907871D01*
G01X1906809D02*
X1907871D01*
G01X1907567Y230163D02*
X1906415D01*
G01X1906087Y231835D02*
X1906809Y231113D01*
G01D02*
X1907871D01*
G01X1906415Y230163D02*
X1905137Y231441D01*
G01X1906087Y233406D02*
Y231835D01*
G01X1905137Y231441D02*
Y233133D01*
G01X1904687Y235643D02*
X1906087Y233406D01*
G01X1905137Y233133D02*
X1903998Y234953D01*
G01X1901839Y237423D02*
X1904687Y235643D01*
G01X1903998Y234953D02*
X1901473Y236531D01*
G01D02*
X1901053Y236628D01*
G01D02*
X1899369Y237015D01*
G01X1908465Y237393D02*
X1902855Y240900D01*
G01X1903223Y241791D02*
X1908738Y238343D01*
G01X1909324Y237393D02*
X1908465D01*
G01D02*
X1902855Y240900D01*
G01X1908738Y238343D02*
X1909355D01*
G01X1908738D02*
X1909355D01*
G01X1909324Y237393D02*
X1908465D01*
G01X1903223Y241791D02*
X1908738Y238343D01*
G01D02*
X1909355D01*
G01X1908465Y237393D02*
X1902855Y240900D01*
G01X1927046Y226310D02*
X1926212Y227144D01*
G01D02*
X1925575D01*
G01X1924621Y228735D02*
X1923317Y230039D01*
G01D02*
X1922970D01*
G01X1928449Y226251D02*
X1923711Y230989D01*
G01X1923317Y230039D02*
X1922970D01*
G01X1923711Y230989D02*
X1922241D01*
G01X1929504Y223214D02*
Y223852D01*
G01X1930454Y223056D02*
Y224246D01*
G01X1929504Y223852D02*
X1928637Y224719D01*
G01X1930454Y224246D02*
X1928449Y226251D01*
G01X1929364Y218214D02*
Y218929D01*
G01X1930314Y218369D02*
Y218927D01*
G01X1930454Y223056D02*
Y224246D01*
G01X1929504Y223214D02*
Y223852D01*
G01X1930454Y224246D02*
X1928449Y226251D01*
G01X1929504Y223852D02*
X1928637Y224719D01*
G01X1928449Y226251D02*
X1923711Y230989D01*
G01X1927046Y226310D02*
X1926212Y227144D01*
G01X1928449Y226251D02*
X1923711Y230989D01*
G01X1926212Y227144D02*
X1925575D01*
G01X1928449Y226251D02*
X1923711Y230989D01*
G01X1924621Y228735D02*
X1923317Y230039D01*
G01X1928449Y226251D02*
X1923711Y230989D01*
G01D02*
X1922241D01*
G01X1923317Y230039D02*
X1922970D01*
G01X1930314Y218369D02*
Y218927D01*
G01X1929364Y218214D02*
Y218929D01*
G01X1930454Y223056D02*
Y224246D01*
G01X1929504Y223214D02*
Y223852D01*
G01X1930454Y224246D02*
X1928449Y226251D01*
G01X1929504Y223852D02*
X1928637Y224719D01*
G01X1928449Y226251D02*
X1923711Y230989D01*
G01X1927046Y226310D02*
X1926212Y227144D01*
G01X1928449Y226251D02*
X1923711Y230989D01*
G01X1926212Y227144D02*
X1925575D01*
G01X1928449Y226251D02*
X1923711Y230989D01*
G01X1924621Y228735D02*
X1923317Y230039D01*
G01X1928449Y226251D02*
X1923711Y230989D01*
G01D02*
X1922241D01*
G01X1923317Y230039D02*
X1922970D01*
G01X1930314Y218369D02*
Y218927D01*
G01X1929364Y218214D02*
Y218929D01*
G01X1931985Y237886D02*
X1932814D01*
G01X1931664Y238836D02*
X1933208D01*
G01X1932814Y237886D02*
X1935220Y235480D01*
G01X1933208Y238836D02*
X1936170Y235874D01*
G01X1935220Y235480D02*
Y231013D01*
G01X1936170Y235874D02*
Y233087D01*
G01X1935220Y228763D02*
Y226688D01*
G01Y224142D02*
Y226688D01*
G01X1936170Y224078D02*
Y233087D01*
G01X1942451Y218411D02*
X1941131D01*
G01X1942544Y219361D02*
X1940737D01*
G01X1942451Y218411D02*
X1941131D01*
G01X1935009Y217887D02*
Y219313D01*
G01X1935959Y218281D02*
Y218919D01*
G01X1931664Y238836D02*
X1933208D01*
G01X1931985Y237886D02*
X1932814D01*
G01X1933208Y238836D02*
X1936170Y235874D01*
G01X1932814Y237886D02*
X1935220Y235480D01*
G01X1936170Y235874D02*
Y233087D01*
G01X1935220Y235480D02*
Y231013D01*
G01X1936170Y224078D02*
Y233087D01*
G01X1935220Y228763D02*
Y226688D01*
G01X1936170Y224078D02*
Y233087D01*
G01X1935220Y224142D02*
Y226688D01*
G01X1942544Y219361D02*
X1940737D01*
G01X1942451Y218411D02*
X1941131D01*
G01X1935959Y218281D02*
Y218919D01*
G01X1935009Y217887D02*
Y219313D01*
G01X1916338Y237386D02*
X1915087D01*
G01X1916166Y238336D02*
X1915092D01*
G01X1916166D02*
X1915092D01*
G01X1916338Y237386D02*
X1915087D01*
G01X1927046Y226310D02*
X1926212Y227144D01*
G01D02*
X1925575D01*
G01X1924621Y228735D02*
X1923317Y230039D01*
G01D02*
X1922970D01*
G01X1928449Y226251D02*
X1923711Y230989D01*
G01X1923317Y230039D02*
X1922970D01*
G01X1923711Y230989D02*
X1922241D01*
G01X1929504Y223214D02*
Y223852D01*
G01X1930454Y223056D02*
Y224246D01*
G01X1929504Y223852D02*
X1928637Y224719D01*
G01X1930454Y224246D02*
X1928449Y226251D01*
G01X1929364Y218214D02*
Y218929D01*
G01X1930314Y218369D02*
Y218927D01*
G01X1927046Y226310D02*
X1926212Y227144D01*
G01D02*
X1925575D01*
G01X1924621Y228735D02*
X1923317Y230039D01*
G01D02*
X1922970D01*
G01X1928449Y226251D02*
X1923711Y230989D01*
G01X1923317Y230039D02*
X1922970D01*
G01X1923711Y230989D02*
X1922241D01*
G01X1929504Y223214D02*
Y223852D01*
G01X1930454Y223056D02*
Y224246D01*
G01X1929504Y223852D02*
X1928637Y224719D01*
G01X1930454Y224246D02*
X1928449Y226251D01*
G01X1929364Y218214D02*
Y218929D01*
G01X1930314Y218369D02*
Y218927D01*
G01X1927046Y226310D02*
X1926212Y227144D01*
G01D02*
X1925575D01*
G01X1924621Y228735D02*
X1923317Y230039D01*
G01D02*
X1922970D01*
G01X1928449Y226251D02*
X1923711Y230989D01*
G01X1923317Y230039D02*
X1922970D01*
G01X1923711Y230989D02*
X1922241D01*
G01X1929504Y223214D02*
Y223852D01*
G01X1930454Y223056D02*
Y224246D01*
G01X1929504Y223852D02*
X1928637Y224719D01*
G01X1930454Y224246D02*
X1928449Y226251D01*
G01X1929364Y218214D02*
Y218929D01*
G01X1930314Y218369D02*
Y218927D01*
G01X1930454Y223056D02*
Y224246D01*
G01X1929504Y223214D02*
Y223852D01*
G01X1930454Y224246D02*
X1928449Y226251D01*
G01X1929504Y223852D02*
X1928637Y224719D01*
G01X1928449Y226251D02*
X1923711Y230989D01*
G01X1927046Y226310D02*
X1926212Y227144D01*
G01X1928449Y226251D02*
X1923711Y230989D01*
G01X1926212Y227144D02*
X1925575D01*
G01X1928449Y226251D02*
X1923711Y230989D01*
G01X1924621Y228735D02*
X1923317Y230039D01*
G01X1928449Y226251D02*
X1923711Y230989D01*
G01D02*
X1922241D01*
G01X1923317Y230039D02*
X1922970D01*
G01X1930314Y218369D02*
Y218927D01*
G01X1929364Y218214D02*
Y218929D01*
G01X1930454Y223056D02*
Y224246D01*
G01X1929504Y223214D02*
Y223852D01*
G01X1930454Y224246D02*
X1928449Y226251D01*
G01X1929504Y223852D02*
X1928637Y224719D01*
G01X1928449Y226251D02*
X1923711Y230989D01*
G01X1927046Y226310D02*
X1926212Y227144D01*
G01X1928449Y226251D02*
X1923711Y230989D01*
G01X1926212Y227144D02*
X1925575D01*
G01X1928449Y226251D02*
X1923711Y230989D01*
G01X1924621Y228735D02*
X1923317Y230039D01*
G01X1928449Y226251D02*
X1923711Y230989D01*
G01D02*
X1922241D01*
G01X1923317Y230039D02*
X1922970D01*
G01X1930314Y218369D02*
Y218927D01*
G01X1929364Y218214D02*
Y218929D01*
G01X1931985Y237886D02*
X1932814D01*
G01X1931664Y238836D02*
X1933208D01*
G01X1932814Y237886D02*
X1935220Y235480D01*
G01X1933208Y238836D02*
X1936170Y235874D01*
G01X1935220Y235480D02*
Y231013D01*
G01X1936170Y235874D02*
Y233087D01*
G01X1935220Y228763D02*
Y226688D01*
G01Y224142D02*
Y226688D01*
G01X1936170Y224078D02*
Y233087D01*
G01X1942451Y218411D02*
X1941131D01*
G01X1942544Y219361D02*
X1940737D01*
G01X1942451Y218411D02*
X1941131D01*
G01X1935009Y217887D02*
Y219313D01*
G01X1935959Y218281D02*
Y218919D01*
G01X1931985Y237886D02*
X1932814D01*
G01X1931664Y238836D02*
X1933208D01*
G01X1932814Y237886D02*
X1935220Y235480D01*
G01X1933208Y238836D02*
X1936170Y235874D01*
G01X1935220Y235480D02*
Y231013D01*
G01X1936170Y235874D02*
Y233087D01*
G01X1935220Y228763D02*
Y226688D01*
G01Y224142D02*
Y226688D01*
G01X1936170Y224078D02*
Y233087D01*
G01X1942451Y218411D02*
X1941131D01*
G01X1942544Y219361D02*
X1940737D01*
G01X1942451Y218411D02*
X1941131D01*
G01X1935009Y217887D02*
Y219313D01*
G01X1935959Y218281D02*
Y218919D01*
G01X1931985Y237886D02*
X1932814D01*
G01X1931664Y238836D02*
X1933208D01*
G01X1932814Y237886D02*
X1935220Y235480D01*
G01X1933208Y238836D02*
X1936170Y235874D01*
G01X1935220Y235480D02*
Y231013D01*
G01X1936170Y235874D02*
Y233087D01*
G01X1935220Y228763D02*
Y226688D01*
G01Y224142D02*
Y226688D01*
G01X1936170Y224078D02*
Y233087D01*
G01X1942451Y218411D02*
X1941131D01*
G01X1942544Y219361D02*
X1940737D01*
G01X1942451Y218411D02*
X1941131D01*
G01X1935009Y217887D02*
Y219313D01*
G01X1935959Y218281D02*
Y218919D01*
G01X1931664Y238836D02*
X1933208D01*
G01X1931985Y237886D02*
X1932814D01*
G01X1933208Y238836D02*
X1936170Y235874D01*
G01X1932814Y237886D02*
X1935220Y235480D01*
G01X1936170Y235874D02*
Y233087D01*
G01X1935220Y235480D02*
Y231013D01*
G01X1936170Y224078D02*
Y233087D01*
G01X1935220Y228763D02*
Y226688D01*
G01X1936170Y224078D02*
Y233087D01*
G01X1935220Y224142D02*
Y226688D01*
G01X1942544Y219361D02*
X1940737D01*
G01X1942451Y218411D02*
X1941131D01*
G01X1935959Y218281D02*
Y218919D01*
G01X1935009Y217887D02*
Y219313D01*
G01X1931664Y238836D02*
X1933208D01*
G01X1931985Y237886D02*
X1932814D01*
G01X1933208Y238836D02*
X1936170Y235874D01*
G01X1932814Y237886D02*
X1935220Y235480D01*
G01X1936170Y235874D02*
Y233087D01*
G01X1935220Y235480D02*
Y231013D01*
G01X1936170Y224078D02*
Y233087D01*
G01X1935220Y228763D02*
Y226688D01*
G01X1936170Y224078D02*
Y233087D01*
G01X1935220Y224142D02*
Y226688D01*
G01X1942544Y219361D02*
X1940737D01*
G01X1942451Y218411D02*
X1941131D01*
G01X1935959Y218281D02*
Y218919D01*
G01X1935009Y217887D02*
Y219313D01*
G01X1931664Y238836D02*
X1933208D01*
G01X1931985Y237886D02*
X1932814D01*
G01X1933208Y238836D02*
X1936170Y235874D01*
G01X1932814Y237886D02*
X1935220Y235480D01*
G01X1936170Y235874D02*
Y233087D01*
G01X1935220Y235480D02*
Y231013D01*
G01X1936170Y224078D02*
Y233087D01*
G01X1935220Y228763D02*
Y226688D01*
G01X1936170Y224078D02*
Y233087D01*
G01X1935220Y224142D02*
Y226688D01*
G01X1942544Y219361D02*
X1940737D01*
G01X1942451Y218411D02*
X1941131D01*
G01X1935959Y218281D02*
Y218919D01*
G01X1935009Y217887D02*
Y219313D01*
G01X1906809Y231113D02*
X1907871D01*
G01X1907567Y230163D02*
X1906415D01*
G01X1906087Y231835D02*
X1906809Y231113D01*
G01D02*
X1907871D01*
G01X1906415Y230163D02*
X1905137Y231441D01*
G01X1906087Y233406D02*
Y231835D01*
G01X1905137Y231441D02*
Y233133D01*
G01X1904687Y235643D02*
X1906087Y233406D01*
G01X1905137Y233133D02*
X1903998Y234953D01*
G01X1901839Y237423D02*
X1904687Y235643D01*
G01X1903998Y234953D02*
X1901473Y236531D01*
G01D02*
X1901053Y236628D01*
G01D02*
X1899369Y237015D01*
G01X1897678Y498800D02*
X1900150Y501272D01*
G01X1898072Y497850D02*
X1901100Y500878D01*
G01X1900150Y501272D02*
Y520359D01*
G01X1901100Y500878D02*
Y502228D01*
G01X1900150Y501272D02*
Y520359D01*
G01X1901100Y504478D02*
Y505828D01*
G01X1900150Y501272D02*
Y520359D01*
G01X1901100Y508078D02*
Y509428D01*
G01X1900150Y501272D02*
Y520359D01*
G01X1901100Y511678D02*
Y513028D01*
G01X1900150Y501272D02*
Y520359D01*
G01X1901100Y515278D02*
Y519965D01*
G01X1900150Y520359D02*
X1901461Y521671D01*
G01X1901100Y519965D02*
X1902000Y520865D01*
G01X1901461Y521671D02*
X1903981Y522714D01*
G01X1902000Y520865D02*
X1904170Y521764D01*
G01X1903981Y522714D02*
X1906386D01*
G01X1904170Y521764D02*
X1905992D01*
G01X1906386Y522714D02*
X1908938Y520162D01*
G01X1905992Y521764D02*
X1907988Y519768D01*
G01X1908938Y520162D02*
Y518779D01*
G01X1907988Y519768D02*
Y518775D01*
G01X1897678Y498800D02*
X1900150Y501272D01*
G01X1898072Y497850D02*
X1901100Y500878D01*
G01X1900150Y501272D02*
Y520359D01*
G01X1901100Y500878D02*
Y502228D01*
G01X1900150Y501272D02*
Y520359D01*
G01X1901100Y504478D02*
Y505828D01*
G01X1900150Y501272D02*
Y520359D01*
G01X1901100Y508078D02*
Y509428D01*
G01X1900150Y501272D02*
Y520359D01*
G01X1901100Y511678D02*
Y513028D01*
G01X1900150Y501272D02*
Y520359D01*
G01X1901100Y515278D02*
Y519965D01*
G01X1900150Y520359D02*
X1901461Y521671D01*
G01X1901100Y519965D02*
X1902000Y520865D01*
G01X1901461Y521671D02*
X1903981Y522714D01*
G01X1902000Y520865D02*
X1904170Y521764D01*
G01X1903981Y522714D02*
X1906386D01*
G01X1904170Y521764D02*
X1905992D01*
G01X1906386Y522714D02*
X1908938Y520162D01*
G01X1905992Y521764D02*
X1907988Y519768D01*
G01X1908938Y520162D02*
Y518779D01*
G01X1907988Y519768D02*
Y518775D01*
G01X1897678Y498800D02*
X1900150Y501272D01*
G01X1898072Y497850D02*
X1901100Y500878D01*
G01X1900150Y501272D02*
Y520359D01*
G01X1901100Y500878D02*
Y502228D01*
G01X1900150Y501272D02*
Y520359D01*
G01X1901100Y504478D02*
Y505828D01*
G01X1900150Y501272D02*
Y520359D01*
G01X1901100Y508078D02*
Y509428D01*
G01X1900150Y501272D02*
Y520359D01*
G01X1901100Y511678D02*
Y513028D01*
G01X1900150Y501272D02*
Y520359D01*
G01X1901100Y515278D02*
Y519965D01*
G01X1900150Y520359D02*
X1901461Y521671D01*
G01X1901100Y519965D02*
X1902000Y520865D01*
G01X1901461Y521671D02*
X1903981Y522714D01*
G01X1902000Y520865D02*
X1904170Y521764D01*
G01X1903981Y522714D02*
X1906386D01*
G01X1904170Y521764D02*
X1905992D01*
G01X1906386Y522714D02*
X1908938Y520162D01*
G01X1905992Y521764D02*
X1907988Y519768D01*
G01X1908938Y520162D02*
Y518779D01*
G01X1907988Y519768D02*
Y518775D01*
G01X1898072Y497850D02*
X1901100Y500878D01*
G01X1897678Y498800D02*
X1900150Y501272D01*
G01X1901100Y500878D02*
Y502228D01*
G01Y504478D02*
Y505828D01*
G01Y508078D02*
Y509428D01*
G01Y511678D02*
Y513028D01*
G01Y515278D02*
Y519965D01*
G01X1900150Y501272D02*
Y520359D01*
G01X1901100Y519965D02*
X1902000Y520865D01*
G01X1900150Y520359D02*
X1901461Y521671D01*
G01X1902000Y520865D02*
X1904170Y521764D01*
G01X1901461Y521671D02*
X1903981Y522714D01*
G01X1904170Y521764D02*
X1905992D01*
G01X1903981Y522714D02*
X1906386D01*
G01X1905992Y521764D02*
X1907988Y519768D01*
G01X1906386Y522714D02*
X1908938Y520162D01*
G01X1907988Y519768D02*
Y518775D01*
G01X1908938Y520162D02*
Y518779D01*
G01X1898072Y497850D02*
X1901100Y500878D01*
G01X1897678Y498800D02*
X1900150Y501272D01*
G01X1901100Y500878D02*
Y502228D01*
G01Y504478D02*
Y505828D01*
G01Y508078D02*
Y509428D01*
G01Y511678D02*
Y513028D01*
G01Y515278D02*
Y519965D01*
G01X1900150Y501272D02*
Y520359D01*
G01X1901100Y519965D02*
X1902000Y520865D01*
G01X1900150Y520359D02*
X1901461Y521671D01*
G01X1902000Y520865D02*
X1904170Y521764D01*
G01X1901461Y521671D02*
X1903981Y522714D01*
G01X1904170Y521764D02*
X1905992D01*
G01X1903981Y522714D02*
X1906386D01*
G01X1905992Y521764D02*
X1907988Y519768D01*
G01X1906386Y522714D02*
X1908938Y520162D01*
G01X1907988Y519768D02*
Y518775D01*
G01X1908938Y520162D02*
Y518779D01*
G01X1898072Y497850D02*
X1901100Y500878D01*
G01X1897678Y498800D02*
X1900150Y501272D01*
G01X1901100Y500878D02*
Y502228D01*
G01Y504478D02*
Y505828D01*
G01Y508078D02*
Y509428D01*
G01Y511678D02*
Y513028D01*
G01Y515278D02*
Y519965D01*
G01X1900150Y501272D02*
Y520359D01*
G01X1901100Y519965D02*
X1902000Y520865D01*
G01X1900150Y520359D02*
X1901461Y521671D01*
G01X1902000Y520865D02*
X1904170Y521764D01*
G01X1901461Y521671D02*
X1903981Y522714D01*
G01X1904170Y521764D02*
X1905992D01*
G01X1903981Y522714D02*
X1906386D01*
G01X1905992Y521764D02*
X1907988Y519768D01*
G01X1906386Y522714D02*
X1908938Y520162D01*
G01X1907988Y519768D02*
Y518775D01*
G01X1908938Y520162D02*
Y518779D01*
G54D13*
G01X362929Y84036D02*
Y87006D01*
G01X364079Y84014D02*
Y86345D01*
G01Y84014D02*
Y86345D01*
G01X362929Y84036D02*
Y87006D01*
G01X770462Y-40725D02*
X581982D01*
G01X770462Y-41875D02*
X581982D01*
G01Y-40725D02*
G03Y-46975I0J-3125D01*
G01Y-41875D02*
G03Y-45825I0J-1975D01*
G01Y-46975D02*
X770577D01*
G01X581982Y-45825D02*
X770577D01*
G01Y-50925D02*
X578504D01*
G01X770577Y-52075D02*
X578027D01*
G01X578504Y-50925D02*
X574305Y-46726D01*
G01X578027Y-52075D02*
X573828Y-47876D01*
G01X574305Y-46726D02*
X571671D01*
G01X573828Y-47876D02*
X571671D01*
G01X770462Y-41875D02*
X581982D01*
G01X770462Y-40725D02*
X581982D01*
G01Y-41875D02*
G03Y-45825I0J-1975D01*
G01Y-40725D02*
G03Y-46975I0J-3125D01*
G01Y-45825D02*
X770577D01*
G01X581982Y-46975D02*
X770577D01*
G01Y-52075D02*
X578027D01*
G01X770577Y-50925D02*
X578504D01*
G01X578027Y-52075D02*
X573828Y-47876D01*
G01X578504Y-50925D02*
X574305Y-46726D01*
G01X573828Y-47876D02*
X571671D01*
G01X574305Y-46726D02*
X571671D01*
G01X770577Y-46975D02*
G02Y-50925I0J-1975D01*
G01Y-45825D02*
G02Y-52075I0J-3125D01*
G01Y-45825D02*
G02Y-52075I0J-3125D01*
G01Y-46975D02*
G02Y-50925I0J-1975D01*
G01X1012537Y84036D02*
Y87006D01*
G01X1013687Y84014D02*
Y86345D01*
G01Y84014D02*
Y86345D01*
G01X1012537Y84036D02*
Y87006D01*
G54D14*
G01X1703724Y132076D02*
X1700436Y135364D01*
G01X1703100Y135246D02*
X1704997Y133349D01*
G01X1712840Y128300D02*
G02X1703724Y132076I0J12892D01*
G01X1704997Y133349D02*
G03X1712840Y130100I7843J7842D01*
G01X1698084Y136338D02*
X1697173D01*
G01X1696986Y138138D02*
X1698084D01*
G01X1700436Y135364D02*
G03X1698084Y136338I-2352J-2353D01*
G01Y138138D02*
G02X1701709Y136637I0J-5128D01*
G01X1703724Y132076D02*
X1700436Y135364D01*
G01X1701709Y136637D02*
X1703100Y135246D01*
G01X1703724Y132076D02*
X1700436Y135364D01*
G01X1703100Y135246D02*
X1704997Y133349D01*
G01X1712840Y128300D02*
G02X1703724Y132076I0J12892D01*
G01X1704997Y133349D02*
G03X1712840Y130100I7843J7842D01*
G01X1698084Y136338D02*
X1697173D01*
G01X1696986Y138138D02*
X1698084D01*
G01X1700436Y135364D02*
G03X1698084Y136338I-2352J-2353D01*
G01Y138138D02*
G02X1701709Y136637I0J-5128D01*
G01X1703724Y132076D02*
X1700436Y135364D01*
G01X1701709Y136637D02*
X1703100Y135246D01*
G01X1704997Y133349D02*
G03X1712840Y130100I7843J7842D01*
G01Y128300D02*
G02X1703724Y132076I0J12892D01*
G01X1703100Y135246D02*
X1704997Y133349D01*
G01X1701709Y136637D02*
X1703100Y135246D01*
G01X1703724Y132076D02*
X1700436Y135364D01*
G01X1698084Y138138D02*
G02X1701709Y136637I0J-5128D01*
G01X1700436Y135364D02*
G03X1698084Y136338I-2352J-2353D01*
G01X1696986Y138138D02*
X1698084D01*
G01Y136338D02*
X1697173D01*
G01X1711806Y118900D02*
X1697953D01*
G01X1709277Y120700D02*
X1711807D01*
G01X1712742Y118512D02*
G03X1711806Y118900I-936J-936D01*
G01X1711807Y120700D02*
G02X1714015Y119785I-1J-3124D01*
G01X1684383Y130408D02*
X1677785D01*
G01X1677964Y132208D02*
X1684383D01*
G01X1684745Y130257D02*
G03X1684383Y130408I-363J-361D01*
G01Y132208D02*
G02X1686019Y131530I0J-2313D01*
G01X1694796Y120207D02*
X1690860Y124143D01*
G01D02*
X1686018Y128985D01*
G01D02*
X1684745Y130257D01*
G01X1686019Y131530D02*
X1696069Y121480D01*
G01X1697952Y118900D02*
G02X1694796Y120207I-1J4462D01*
G01X1696069Y121480D02*
G03X1697952Y120700I1883J1882D01*
G01X1711806Y118900D02*
X1697953D01*
G01X1697952Y120700D02*
X1709277D01*
G01X1711806Y118900D02*
X1697953D01*
G01X1709277Y120700D02*
X1711807D01*
G01X1712742Y118512D02*
G03X1711806Y118900I-936J-936D01*
G01X1711807Y120700D02*
G02X1714015Y119785I-1J-3124D01*
G01X1684383Y130408D02*
X1677785D01*
G01X1677964Y132208D02*
X1684383D01*
G01X1684745Y130257D02*
G03X1684383Y130408I-363J-361D01*
G01Y132208D02*
G02X1686019Y131530I0J-2313D01*
G01X1694796Y120207D02*
X1690860Y124143D01*
G01D02*
X1686018Y128985D01*
G01D02*
X1684745Y130257D01*
G01X1686019Y131530D02*
X1696069Y121480D01*
G01X1697952Y118900D02*
G02X1694796Y120207I-1J4462D01*
G01X1696069Y121480D02*
G03X1697952Y120700I1883J1882D01*
G01X1711806Y118900D02*
X1697953D01*
G01X1697952Y120700D02*
X1709277D01*
G01X1711807D02*
G02X1714015Y119785I-1J-3124D01*
G01X1712742Y118512D02*
G03X1711806Y118900I-936J-936D01*
G01X1709277Y120700D02*
X1711807D01*
G01X1697952D02*
X1709277D01*
G01X1711806Y118900D02*
X1697953D01*
G01X1696069Y121480D02*
G03X1697952Y120700I1883J1882D01*
G01Y118900D02*
G02X1694796Y120207I-1J4462D01*
G01X1686019Y131530D02*
X1696069Y121480D01*
G01X1694796Y120207D02*
X1690860Y124143D01*
G01X1686019Y131530D02*
X1696069Y121480D01*
G01X1690860Y124143D02*
X1686018Y128985D01*
G01X1686019Y131530D02*
X1696069Y121480D01*
G01X1686018Y128985D02*
X1684745Y130257D01*
G01X1684383Y132208D02*
G02X1686019Y131530I0J-2313D01*
G01X1684745Y130257D02*
G03X1684383Y130408I-363J-361D01*
G01X1677964Y132208D02*
X1684383D01*
G01Y130408D02*
X1677785D01*
G01X1711807Y120700D02*
G02X1714015Y119785I-1J-3124D01*
G01X1712742Y118512D02*
G03X1711806Y118900I-936J-936D01*
G01X1709277Y120700D02*
X1711807D01*
G01X1697952D02*
X1709277D01*
G01X1711806Y118900D02*
X1697953D01*
G01X1696069Y121480D02*
G03X1697952Y120700I1883J1882D01*
G01Y118900D02*
G02X1694796Y120207I-1J4462D01*
G01X1686019Y131530D02*
X1696069Y121480D01*
G01X1694796Y120207D02*
X1690860Y124143D01*
G01X1686019Y131530D02*
X1696069Y121480D01*
G01X1690860Y124143D02*
X1686018Y128985D01*
G01X1686019Y131530D02*
X1696069Y121480D01*
G01X1686018Y128985D02*
X1684745Y130257D01*
G01X1684383Y132208D02*
G02X1686019Y131530I0J-2313D01*
G01X1684745Y130257D02*
G03X1684383Y130408I-363J-361D01*
G01X1677964Y132208D02*
X1684383D01*
G01Y130408D02*
X1677785D01*
G01X1709971Y99689D02*
X1713023Y102741D01*
G01X1709971Y99689D02*
X1713023Y102741D01*
G01X1712642Y99814D02*
X1711244Y98416D01*
G01X1708277Y101383D02*
G03X1709971Y99689I847J-847D01*
G01X1711244Y98416D02*
G02X1707003Y102656I-2120J2120D01*
G01X1710973Y104079D02*
X1708277Y101383D01*
G01X1707003Y102656D02*
X1709700Y105352D01*
G01X1706697Y108355D02*
G02X1710973Y104079I2138J-2138D01*
G01X1709700Y105352D02*
G03X1707970Y107082I-865J865D01*
G01X1704129Y105787D02*
X1706697Y108355D01*
G01X1707970Y107082D02*
X1705402Y104514D01*
G01X1702362Y106519D02*
G03X1704129Y105787I1035J0D01*
G01X1705402Y104514D02*
G02X1700562Y106519I-2005J2005D01*
G01X1702362Y109053D02*
Y106519D01*
G01X1700562D02*
Y109053D01*
G01X1696367D02*
G02X1702362I2998J0D01*
G01X1700562D02*
G03X1698167I-1197J0D01*
G01X1693972Y108523D02*
G03X1696367I1197J0D01*
G01X1698167D02*
G02X1692172I-2997J0D01*
G01X1693972Y109223D02*
Y108523D01*
G01X1692172D02*
Y109223D01*
G01X1687977D02*
G02X1693972I2998J0D01*
G01X1692172D02*
G03X1689777I-1197J0D01*
G01X1687977Y108539D02*
Y109223D01*
G01X1689777D02*
Y108539D01*
G01X1685582D02*
G03X1687977I1197J0D01*
G01X1689777D02*
G02X1683782I-2998J0D01*
G01X1682607Y111933D02*
G02X1685582Y108958I0J-2975D01*
G01X1683782D02*
G03X1682607Y110133I-1175J0D01*
G01X1681717Y112328D02*
G03X1682112Y111933I395J0D01*
G01Y110133D02*
G02X1679917Y112328I0J2195D01*
G01X1681717Y116349D02*
Y112328D01*
G01Y120019D02*
Y116349D01*
G01X1679917Y112328D02*
Y120019D01*
G01X1679223Y122513D02*
G02X1681717Y120019I0J-2494D01*
G01X1679917D02*
G03X1679223Y120713I-694J0D01*
G01X1678516Y122513D02*
X1679223D01*
G01Y120713D02*
X1678516D01*
G01X1679917Y112328D02*
Y120019D01*
G01X1681717Y116349D02*
Y112328D01*
G01X1682112Y110133D02*
G02X1679917Y112328I0J2195D01*
G01X1681717D02*
G03X1682112Y111933I395J0D01*
G01X1683782Y108958D02*
G03X1682607Y110133I-1175J0D01*
G01Y111933D02*
G02X1685582Y108958I0J-2975D01*
G01X1689777Y108539D02*
G02X1683782I-2998J0D01*
G01X1685582D02*
G03X1687977I1197J0D01*
G01X1689777Y109223D02*
Y108539D01*
G01X1687977D02*
Y109223D01*
G01X1692172D02*
G03X1689777I-1197J0D01*
G01X1687977D02*
G02X1693972I2998J0D01*
G01X1692172Y108523D02*
Y109223D01*
G01X1693972D02*
Y108523D01*
G01X1698167D02*
G02X1692172I-2997J0D01*
G01X1693972D02*
G03X1696367I1197J0D01*
G01X1700562Y109053D02*
G03X1698167I-1197J0D01*
G01X1696367D02*
G02X1702362I2998J0D01*
G01X1700562Y106519D02*
Y109053D01*
G01X1702362D02*
Y106519D01*
G01X1705402Y104514D02*
G02X1700562Y106519I-2005J2005D01*
G01X1702362D02*
G03X1704129Y105787I1035J0D01*
G01X1707970Y107082D02*
X1705402Y104514D01*
G01X1704129Y105787D02*
X1706697Y108355D01*
G01X1709700Y105352D02*
G03X1707970Y107082I-865J865D01*
G01X1706697Y108355D02*
G02X1710973Y104079I2138J-2138D01*
G01X1707003Y102656D02*
X1709700Y105352D01*
G01X1710973Y104079D02*
X1708277Y101383D01*
G01X1711244Y98416D02*
G02X1707003Y102656I-2120J2120D01*
G01X1708277Y101383D02*
G03X1709971Y99689I847J-847D01*
G01X1712642Y99814D02*
X1711244Y98416D01*
G01X1709971Y99689D02*
X1713023Y102741D01*
G01X1679223Y120713D02*
X1678516D01*
G01Y122513D02*
X1679223D01*
G01X1679917Y120019D02*
G03X1679223Y120713I-694J0D01*
G01Y122513D02*
G02X1681717Y120019I0J-2494D01*
G01X1679917Y112328D02*
Y120019D01*
G01X1681717D02*
Y116349D01*
G01X1679917Y112328D02*
Y120019D01*
G01X1681717Y116349D02*
Y112328D01*
G01X1682112Y110133D02*
G02X1679917Y112328I0J2195D01*
G01X1681717D02*
G03X1682112Y111933I395J0D01*
G01X1683782Y108958D02*
G03X1682607Y110133I-1175J0D01*
G01Y111933D02*
G02X1685582Y108958I0J-2975D01*
G01X1689777Y108539D02*
G02X1683782I-2998J0D01*
G01X1685582D02*
G03X1687977I1197J0D01*
G01X1689777Y109223D02*
Y108539D01*
G01X1687977D02*
Y109223D01*
G01X1692172D02*
G03X1689777I-1197J0D01*
G01X1687977D02*
G02X1693972I2998J0D01*
G01X1692172Y108523D02*
Y109223D01*
G01X1693972D02*
Y108523D01*
G01X1698167D02*
G02X1692172I-2997J0D01*
G01X1693972D02*
G03X1696367I1197J0D01*
G01X1700562Y109053D02*
G03X1698167I-1197J0D01*
G01X1696367D02*
G02X1702362I2998J0D01*
G01X1700562Y106519D02*
Y109053D01*
G01X1702362D02*
Y106519D01*
G01X1705402Y104514D02*
G02X1700562Y106519I-2005J2005D01*
G01X1702362D02*
G03X1704129Y105787I1035J0D01*
G01X1707970Y107082D02*
X1705402Y104514D01*
G01X1704129Y105787D02*
X1706697Y108355D01*
G01X1709700Y105352D02*
G03X1707970Y107082I-865J865D01*
G01X1706697Y108355D02*
G02X1710973Y104079I2138J-2138D01*
G01X1707003Y102656D02*
X1709700Y105352D01*
G01X1710973Y104079D02*
X1708277Y101383D01*
G01X1711244Y98416D02*
G02X1707003Y102656I-2120J2120D01*
G01X1708277Y101383D02*
G03X1709971Y99689I847J-847D01*
G01X1712642Y99814D02*
X1711244Y98416D01*
G01X1709971Y99689D02*
X1713023Y102741D01*
G01X1679223Y120713D02*
X1678516D01*
G01Y122513D02*
X1679223D01*
G01X1679917Y120019D02*
G03X1679223Y120713I-694J0D01*
G01Y122513D02*
G02X1681717Y120019I0J-2494D01*
G01X1679917Y112328D02*
Y120019D01*
G01X1681717D02*
Y116349D01*
G01X1703724Y132076D02*
X1700436Y135364D01*
G01X1703100Y135246D02*
X1704997Y133349D01*
G01X1712840Y128300D02*
G02X1703724Y132076I0J12892D01*
G01X1704997Y133349D02*
G03X1712840Y130100I7843J7842D01*
G01X1698084Y136338D02*
X1697173D01*
G01X1696986Y138138D02*
X1698084D01*
G01X1700436Y135364D02*
G03X1698084Y136338I-2352J-2353D01*
G01Y138138D02*
G02X1701709Y136637I0J-5128D01*
G01X1703724Y132076D02*
X1700436Y135364D01*
G01X1701709Y136637D02*
X1703100Y135246D01*
G01X1704997Y133349D02*
G03X1712840Y130100I7843J7842D01*
G01Y128300D02*
G02X1703724Y132076I0J12892D01*
G01X1703100Y135246D02*
X1704997Y133349D01*
G01X1701709Y136637D02*
X1703100Y135246D01*
G01X1703724Y132076D02*
X1700436Y135364D01*
G01X1698084Y138138D02*
G02X1701709Y136637I0J-5128D01*
G01X1700436Y135364D02*
G03X1698084Y136338I-2352J-2353D01*
G01X1696986Y138138D02*
X1698084D01*
G01Y136338D02*
X1697173D01*
G01X1704997Y133349D02*
G03X1712840Y130100I7843J7842D01*
G01Y128300D02*
G02X1703724Y132076I0J12892D01*
G01X1703100Y135246D02*
X1704997Y133349D01*
G01X1701709Y136637D02*
X1703100Y135246D01*
G01X1703724Y132076D02*
X1700436Y135364D01*
G01X1698084Y138138D02*
G02X1701709Y136637I0J-5128D01*
G01X1700436Y135364D02*
G03X1698084Y136338I-2352J-2353D01*
G01X1696986Y138138D02*
X1698084D01*
G01Y136338D02*
X1697173D01*
G01X1709971Y99689D02*
X1713023Y102741D01*
G01X1709971Y99689D02*
X1713023Y102741D01*
G01X1712642Y99814D02*
X1711244Y98416D01*
G01X1708277Y101383D02*
G03X1709971Y99689I847J-847D01*
G01X1711244Y98416D02*
G02X1707003Y102656I-2120J2120D01*
G01X1710973Y104079D02*
X1708277Y101383D01*
G01X1707003Y102656D02*
X1709700Y105352D01*
G01X1706697Y108355D02*
G02X1710973Y104079I2138J-2138D01*
G01X1709700Y105352D02*
G03X1707970Y107082I-865J865D01*
G01X1704129Y105787D02*
X1706697Y108355D01*
G01X1707970Y107082D02*
X1705402Y104514D01*
G01X1702362Y106519D02*
G03X1704129Y105787I1035J0D01*
G01X1705402Y104514D02*
G02X1700562Y106519I-2005J2005D01*
G01X1702362Y109053D02*
Y106519D01*
G01X1700562D02*
Y109053D01*
G01X1696367D02*
G02X1702362I2998J0D01*
G01X1700562D02*
G03X1698167I-1197J0D01*
G01X1693972Y108523D02*
G03X1696367I1197J0D01*
G01X1698167D02*
G02X1692172I-2997J0D01*
G01X1693972Y109223D02*
Y108523D01*
G01X1692172D02*
Y109223D01*
G01X1687977D02*
G02X1693972I2998J0D01*
G01X1692172D02*
G03X1689777I-1197J0D01*
G01X1687977Y108539D02*
Y109223D01*
G01X1689777D02*
Y108539D01*
G01X1685582D02*
G03X1687977I1197J0D01*
G01X1689777D02*
G02X1683782I-2998J0D01*
G01X1682607Y111933D02*
G02X1685582Y108958I0J-2975D01*
G01X1683782D02*
G03X1682607Y110133I-1175J0D01*
G01X1681717Y112328D02*
G03X1682112Y111933I395J0D01*
G01Y110133D02*
G02X1679917Y112328I0J2195D01*
G01X1681717Y116349D02*
Y112328D01*
G01Y120019D02*
Y116349D01*
G01X1679917Y112328D02*
Y120019D01*
G01X1679223Y122513D02*
G02X1681717Y120019I0J-2494D01*
G01X1679917D02*
G03X1679223Y120713I-694J0D01*
G01X1678516Y122513D02*
X1679223D01*
G01Y120713D02*
X1678516D01*
G01X1719944Y128300D02*
X1715318D01*
G01D02*
X1712840D01*
G01Y130100D02*
X1723264D01*
G01X1719944Y128300D02*
X1715318D01*
G01D02*
X1712840D01*
G01Y130100D02*
X1723264D01*
G01X1712840D02*
X1723264D01*
G01X1719944Y128300D02*
X1715318D01*
G01X1712840Y130100D02*
X1723264D01*
G01X1715318Y128300D02*
X1712840D01*
G01X1717139Y114116D02*
X1712742Y118512D01*
G01X1714015Y119785D02*
X1718412Y115389D01*
G01X1719715Y113050D02*
G02X1717139Y114116I-2J3641D01*
G01X1718412Y115389D02*
G03X1719714Y114850I1302J1302D01*
G01X1726145Y113050D02*
X1719715D01*
G01X1719714Y114850D02*
X1726145D01*
G01X1727584Y112454D02*
G03X1726145Y113050I-1439J-1439D01*
G01Y114850D02*
G02X1728857Y113727I0J-3836D01*
G01X1730512Y109526D02*
X1727584Y112454D01*
G01X1728857Y113727D02*
X1731785Y110799D01*
G01X1734754Y113767D02*
G02X1730512Y109526I-2121J-2121D01*
G01X1731785Y110799D02*
G03X1733480Y112494I848J848D01*
G01X1733291Y115229D02*
X1734753Y113767D01*
G01X1733480Y112494D02*
X1731491Y114483D01*
G01X1730240Y118281D02*
X1733291Y115230D01*
G01X1731491Y114484D02*
X1728967Y117008D01*
G01X1731182Y120557D02*
G03X1730240Y118281I0J-1333D01*
G01X1728967Y117008D02*
G02X1731182Y122357I2215J2216D01*
G01X1733474Y120557D02*
X1731182D01*
G01Y122357D02*
X1733475D01*
G01X1735468Y119615D02*
G03X1733474Y120557I-1994J-1640D01*
G01X1733475Y122357D02*
G02X1736859Y120759I0J-4383D01*
G01X1736189Y118738D02*
X1735468Y119615D01*
G01X1736859Y120759D02*
X1737580Y119882D01*
G01X1717139Y114116D02*
X1712742Y118512D01*
G01X1714015Y119785D02*
X1718412Y115389D01*
G01X1719715Y113050D02*
G02X1717139Y114116I-2J3641D01*
G01X1718412Y115389D02*
G03X1719714Y114850I1302J1302D01*
G01X1726145Y113050D02*
X1719715D01*
G01X1719714Y114850D02*
X1726145D01*
G01X1727584Y112454D02*
G03X1726145Y113050I-1439J-1439D01*
G01Y114850D02*
G02X1728857Y113727I0J-3836D01*
G01X1730512Y109526D02*
X1727584Y112454D01*
G01X1728857Y113727D02*
X1731785Y110799D01*
G01X1734754Y113767D02*
G02X1730512Y109526I-2121J-2121D01*
G01X1731785Y110799D02*
G03X1733480Y112494I848J848D01*
G01X1733291Y115229D02*
X1734753Y113767D01*
G01X1733480Y112494D02*
X1731491Y114483D01*
G01X1730240Y118281D02*
X1733291Y115230D01*
G01X1731491Y114484D02*
X1728967Y117008D01*
G01X1731182Y120557D02*
G03X1730240Y118281I0J-1333D01*
G01X1728967Y117008D02*
G02X1731182Y122357I2215J2216D01*
G01X1733474Y120557D02*
X1731182D01*
G01Y122357D02*
X1733475D01*
G01X1735468Y119615D02*
G03X1733474Y120557I-1994J-1640D01*
G01X1733475Y122357D02*
G02X1736859Y120759I0J-4383D01*
G01X1736189Y118738D02*
X1735468Y119615D01*
G01X1736859Y120759D02*
X1737580Y119882D01*
G01X1736859Y120759D02*
X1737580Y119882D01*
G01X1736189Y118738D02*
X1735468Y119615D01*
G01X1733475Y122357D02*
G02X1736859Y120759I0J-4383D01*
G01X1735468Y119615D02*
G03X1733474Y120557I-1994J-1640D01*
G01X1731182Y122357D02*
X1733475D01*
G01X1733474Y120557D02*
X1731182D01*
G01X1728967Y117008D02*
G02X1731182Y122357I2215J2216D01*
G01Y120557D02*
G03X1730240Y118281I0J-1333D01*
G01X1731491Y114484D02*
X1728967Y117008D01*
G01X1730240Y118281D02*
X1733291Y115230D01*
G01X1733480Y112494D02*
X1731491Y114483D01*
G01X1733291Y115229D02*
X1734753Y113767D01*
G01X1731785Y110799D02*
G03X1733480Y112494I848J848D01*
G01X1734754Y113767D02*
G02X1730512Y109526I-2121J-2121D01*
G01X1728857Y113727D02*
X1731785Y110799D01*
G01X1730512Y109526D02*
X1727584Y112454D01*
G01X1726145Y114850D02*
G02X1728857Y113727I0J-3836D01*
G01X1727584Y112454D02*
G03X1726145Y113050I-1439J-1439D01*
G01X1719714Y114850D02*
X1726145D01*
G01Y113050D02*
X1719715D01*
G01X1718412Y115389D02*
G03X1719714Y114850I1302J1302D01*
G01X1719715Y113050D02*
G02X1717139Y114116I-2J3641D01*
G01X1714015Y119785D02*
X1718412Y115389D01*
G01X1717139Y114116D02*
X1712742Y118512D01*
G01X1736859Y120759D02*
X1737580Y119882D01*
G01X1736189Y118738D02*
X1735468Y119615D01*
G01X1733475Y122357D02*
G02X1736859Y120759I0J-4383D01*
G01X1735468Y119615D02*
G03X1733474Y120557I-1994J-1640D01*
G01X1731182Y122357D02*
X1733475D01*
G01X1733474Y120557D02*
X1731182D01*
G01X1728967Y117008D02*
G02X1731182Y122357I2215J2216D01*
G01Y120557D02*
G03X1730240Y118281I0J-1333D01*
G01X1731491Y114484D02*
X1728967Y117008D01*
G01X1730240Y118281D02*
X1733291Y115230D01*
G01X1733480Y112494D02*
X1731491Y114483D01*
G01X1733291Y115229D02*
X1734753Y113767D01*
G01X1731785Y110799D02*
G03X1733480Y112494I848J848D01*
G01X1734754Y113767D02*
G02X1730512Y109526I-2121J-2121D01*
G01X1728857Y113727D02*
X1731785Y110799D01*
G01X1730512Y109526D02*
X1727584Y112454D01*
G01X1726145Y114850D02*
G02X1728857Y113727I0J-3836D01*
G01X1727584Y112454D02*
G03X1726145Y113050I-1439J-1439D01*
G01X1719714Y114850D02*
X1726145D01*
G01Y113050D02*
X1719715D01*
G01X1718412Y115389D02*
G03X1719714Y114850I1302J1302D01*
G01X1719715Y113050D02*
G02X1717139Y114116I-2J3641D01*
G01X1714015Y119785D02*
X1718412Y115389D01*
G01X1717139Y114116D02*
X1712742Y118512D01*
G01X1718708Y101025D02*
X1721687D01*
G01X1722307Y99225D02*
X1718708D01*
G01X1717798Y101402D02*
G03X1718708Y101025I910J910D01*
G01Y99225D02*
G02X1716525Y100128I-1J3088D01*
G01X1716460Y102741D02*
X1717798Y101402D01*
G01X1716525Y100128D02*
X1715186Y101468D01*
G01X1713023Y102741D02*
G02X1716460I1719J-1718D01*
G01X1715186Y101468D02*
G03X1714296I-445J-445D01*
G01D02*
X1712642Y99814D01*
G01X1714296Y101468D02*
X1712642Y99814D01*
G01X1715186Y101468D02*
G03X1714296I-445J-445D01*
G01X1713023Y102741D02*
G02X1716460I1719J-1718D01*
G01X1716525Y100128D02*
X1715186Y101468D01*
G01X1716460Y102741D02*
X1717798Y101402D01*
G01X1718708Y99225D02*
G02X1716525Y100128I-1J3088D01*
G01X1717798Y101402D02*
G03X1718708Y101025I910J910D01*
G01X1722307Y99225D02*
X1718708D01*
G01Y101025D02*
X1721687D01*
G01X1714296Y101468D02*
X1712642Y99814D01*
G01X1715186Y101468D02*
G03X1714296I-445J-445D01*
G01X1713023Y102741D02*
G02X1716460I1719J-1718D01*
G01X1716525Y100128D02*
X1715186Y101468D01*
G01X1716460Y102741D02*
X1717798Y101402D01*
G01X1718708Y99225D02*
G02X1716525Y100128I-1J3088D01*
G01X1717798Y101402D02*
G03X1718708Y101025I910J910D01*
G01X1722307Y99225D02*
X1718708D01*
G01Y101025D02*
X1721687D01*
G01X1719944Y128300D02*
X1715318D01*
G01D02*
X1712840D01*
G01Y130100D02*
X1723264D01*
G01X1712840D02*
X1723264D01*
G01X1719944Y128300D02*
X1715318D01*
G01X1712840Y130100D02*
X1723264D01*
G01X1715318Y128300D02*
X1712840D01*
G01Y130100D02*
X1723264D01*
G01X1719944Y128300D02*
X1715318D01*
G01X1712840Y130100D02*
X1723264D01*
G01X1715318Y128300D02*
X1712840D01*
G01X1718708Y101025D02*
X1721687D01*
G01X1722307Y99225D02*
X1718708D01*
G01X1717798Y101402D02*
G03X1718708Y101025I910J910D01*
G01Y99225D02*
G02X1716525Y100128I-1J3088D01*
G01X1716460Y102741D02*
X1717798Y101402D01*
G01X1716525Y100128D02*
X1715186Y101468D01*
G01X1713023Y102741D02*
G02X1716460I1719J-1718D01*
G01X1715186Y101468D02*
G03X1714296I-445J-445D01*
G01D02*
X1712642Y99814D01*
G01X1883993Y13300D02*
X1888910D01*
G01X1885554Y11500D02*
X1888164D01*
G01X1888910Y13300D02*
X1892544Y9666D01*
G01X1888164Y11500D02*
X1891798Y7866D01*
G01X1892544Y9666D02*
X1900945D01*
G01X1891798Y7866D02*
X1896769D01*
G01X1885554Y11500D02*
X1888164D01*
G01X1883993Y13300D02*
X1888910D01*
G01X1888164Y11500D02*
X1891798Y7866D01*
G01X1888910Y13300D02*
X1892544Y9666D01*
G01X1891798Y7866D02*
X1896769D01*
G01X1892544Y9666D02*
X1900945D01*
M02*
